%#################################################################
Title:        Pin Cross Referencing Report
Design:       s9s_mb_2u
Date:         Sep 23 11:25:20 2022
%#################################################################


Part      	Bodyname       	Pin       	Zone      	Net Name            

BT1       	CONN2_AAABAT029Y19	          	          	                    
          	               	1         	185B3     	P3V_BAT             
          	               	2         	185B3     	GND                 

C1        	Q_CAP_C0402    	          	          	                    
          	               	1         	37B3      	P3V3_AUX            
          	               	2         	37B3      	GND                 

C2        	Q_CAP_C0402    	          	          	                    
          	               	1         	82A3      	P3V3_AUX            
          	               	2         	82A3      	GND                 

C3        	Q_CAP_C0805    	          	          	                    
          	               	1         	82A2      	P12V_S3_AUX_CPU0_NVDIMM
          	               	2         	82A2      	GND                 

C4        	Q_CAP_C0805    	          	          	                    
          	               	1         	82A2      	P12V_S3_AUX_CPU0_NVDIMM
          	               	2         	82A2      	GND                 

C5        	Q_CAP_C0402    	          	          	                    
          	               	1         	83A3      	P3V3_AUX            
          	               	2         	83A3      	GND                 

C6        	Q_CAP_C0805    	          	          	                    
          	               	1         	83A2      	P12V_S3_AUX_CPU0_NVDIMM
          	               	2         	83A2      	GND                 

C7        	Q_CAP_C0805    	          	          	                    
          	               	1         	83A2      	P12V_S3_AUX_CPU0_NVDIMM
          	               	2         	83A2      	GND                 

C8        	Q_CAP_C0402    	          	          	                    
          	               	1         	84A3      	P3V3_AUX            
          	               	2         	84A3      	GND                 

C9        	Q_CAP_C0805    	          	          	                    
          	               	1         	84A2      	P12V_S3_AUX_CPU0_NVDIMM
          	               	2         	84A2      	GND                 

C10       	Q_CAP_C0805    	          	          	                    
          	               	1         	84A2      	P12V_S3_AUX_CPU0_NVDIMM
          	               	2         	84A2      	GND                 

C11       	Q_CAP_C0402    	          	          	                    
          	               	1         	85A3      	P3V3_AUX            
          	               	2         	85A3      	GND                 

C12       	Q_CAP_C0805    	          	          	                    
          	               	1         	85A2      	P12V_S3_AUX_CPU0_NVDIMM
          	               	2         	85A2      	GND                 

C13       	Q_CAP_C0805    	          	          	                    
          	               	1         	85A2      	P12V_S3_AUX_CPU0_NVDIMM
          	               	2         	85A2      	GND                 

C14       	Q_CAP_C0402    	          	          	                    
          	               	1         	86A3      	P3V3_AUX            
          	               	2         	86A3      	GND                 

C15       	Q_CAP_C0805    	          	          	                    
          	               	1         	86A2      	P12V_S3_AUX_CPU0_NVDIMM
          	               	2         	86A2      	GND                 

C16       	Q_CAP_C0805    	          	          	                    
          	               	1         	86A2      	P12V_S3_AUX_CPU0_NVDIMM
          	               	2         	86A2      	GND                 

C17       	Q_CAP_C0402    	          	          	                    
          	               	1         	87A3      	P3V3_AUX            
          	               	2         	87A3      	GND                 

C18       	Q_CAP_C0805    	          	          	                    
          	               	1         	87A2      	P12V_S3_AUX_CPU0_NVDIMM
          	               	2         	87A2      	GND                 

C19       	Q_CAP_C0805    	          	          	                    
          	               	1         	87A2      	P12V_S3_AUX_CPU0_NVDIMM
          	               	2         	87A2      	GND                 

C20       	Q_CAP_C0402    	          	          	                    
          	               	1         	88A3      	P3V3_AUX            
          	               	2         	88A3      	GND                 

C21       	Q_CAP_C0805    	          	          	                    
          	               	1         	88A2      	P12V_S3_AUX_CPU0_NVDIMM
          	               	2         	88A2      	GND                 

C22       	Q_CAP_C0805    	          	          	                    
          	               	1         	88A2      	P12V_S3_AUX_CPU0_NVDIMM
          	               	2         	88A2      	GND                 

C23       	Q_CAP_C0402    	          	          	                    
          	               	1         	89A3      	P3V3_AUX            
          	               	2         	89A3      	GND                 

C24       	Q_CAP_C0805    	          	          	                    
          	               	1         	89A2      	P12V_S3_AUX_CPU0_NVDIMM
          	               	2         	89A2      	GND                 

C25       	Q_CAP_C0805    	          	          	                    
          	               	1         	89A2      	P12V_S3_AUX_CPU0_NVDIMM
          	               	2         	89A2      	GND                 

C26       	Q_CAP_C0402    	          	          	                    
          	               	1         	90A3      	P3V3_AUX            
          	               	2         	90A3      	GND                 

C27       	Q_CAP_C0805    	          	          	                    
          	               	1         	90A2      	P12V_S3_AUX_CPU0_NVDIMM
          	               	2         	90A2      	GND                 

C28       	Q_CAP_C0805    	          	          	                    
          	               	1         	90A2      	P12V_S3_AUX_CPU0_NVDIMM
          	               	2         	90A2      	GND                 

C29       	Q_CAP_C0402    	          	          	                    
          	               	1         	91A3      	P3V3_AUX            
          	               	2         	91A3      	GND                 

C30       	Q_CAP_C0805    	          	          	                    
          	               	1         	91A2      	P12V_S3_AUX_CPU0_NVDIMM
          	               	2         	91A2      	GND                 

C31       	Q_CAP_C0805    	          	          	                    
          	               	1         	91A2      	P12V_S3_AUX_CPU0_NVDIMM
          	               	2         	91A2      	GND                 

C32       	Q_CAP_C0402    	          	          	                    
          	               	1         	92A3      	P3V3_AUX            
          	               	2         	92A3      	GND                 

C33       	Q_CAP_C0805    	          	          	                    
          	               	1         	92A2      	P12V_S3_AUX_CPU0_NVDIMM
          	               	2         	92A2      	GND                 

C34       	Q_CAP_C0805    	          	          	                    
          	               	1         	92A2      	P12V_S3_AUX_CPU0_NVDIMM
          	               	2         	92A2      	GND                 

C35       	Q_CAP_C0402    	          	          	                    
          	               	1         	93A3      	P3V3_AUX            
          	               	2         	93A3      	GND                 

C36       	Q_CAP_C0805    	          	          	                    
          	               	1         	93A2      	P12V_S3_AUX_CPU0_NVDIMM
          	               	2         	93A2      	GND                 

C37       	Q_CAP_C0805    	          	          	                    
          	               	1         	93A2      	P12V_S3_AUX_CPU0_NVDIMM
          	               	2         	93A2      	GND                 

C38       	Q_CAP_C0402    	          	          	                    
          	               	1         	94A3      	P3V3_AUX            
          	               	2         	94A3      	GND                 

C39       	Q_CAP_C0805    	          	          	                    
          	               	1         	94A2      	P12V_S3_AUX_CPU0_NVDIMM
          	               	2         	94A2      	GND                 

C40       	Q_CAP_C0805    	          	          	                    
          	               	1         	94A2      	P12V_S3_AUX_CPU0_NVDIMM
          	               	2         	94A2      	GND                 

C41       	Q_CAP_C0402    	          	          	                    
          	               	1         	95A3      	P3V3_AUX            
          	               	2         	95A3      	GND                 

C42       	Q_CAP_C0805    	          	          	                    
          	               	1         	95A2      	P12V_S3_AUX_CPU0_NVDIMM
          	               	2         	95A2      	GND                 

C43       	Q_CAP_C0805    	          	          	                    
          	               	1         	95A2      	P12V_S3_AUX_CPU0_NVDIMM
          	               	2         	95A2      	GND                 

C44       	Q_CAP_C0402    	          	          	                    
          	               	1         	96A3      	P3V3_AUX            
          	               	2         	96A3      	GND                 

C45       	Q_CAP_C0805    	          	          	                    
          	               	1         	96A2      	P12V_S3_AUX_CPU0_NVDIMM
          	               	2         	96A2      	GND                 

C46       	Q_CAP_C0805    	          	          	                    
          	               	1         	96A2      	P12V_S3_AUX_CPU0_NVDIMM
          	               	2         	96A2      	GND                 

C47       	Q_CAP_C0402    	          	          	                    
          	               	1         	97A3      	P3V3_AUX            
          	               	2         	97A3      	GND                 

C48       	Q_CAP_C0805    	          	          	                    
          	               	1         	97A2      	P12V_S3_AUX_CPU0_NVDIMM
          	               	2         	97A2      	GND                 

C49       	Q_CAP_C0805    	          	          	                    
          	               	1         	97A2      	P12V_S3_AUX_CPU0_NVDIMM
          	               	2         	97A2      	GND                 

C50       	Q_CAP_C0402    	          	          	                    
          	               	1         	98A3      	P3V3_AUX            
          	               	2         	98A3      	GND                 

C51       	Q_CAP_C0805    	          	          	                    
          	               	1         	98A2      	P12V_S3_AUX_CPU1_NVDIMM
          	               	2         	98A2      	GND                 

C52       	Q_CAP_C0805    	          	          	                    
          	               	1         	98A2      	P12V_S3_AUX_CPU1_NVDIMM
          	               	2         	98A2      	GND                 

C53       	Q_CAP_C0402    	          	          	                    
          	               	1         	99A3      	P3V3_AUX            
          	               	2         	99A3      	GND                 

C54       	Q_CAP_C0805    	          	          	                    
          	               	1         	99A2      	P12V_S3_AUX_CPU1_NVDIMM
          	               	2         	99A2      	GND                 

C55       	Q_CAP_C0805    	          	          	                    
          	               	1         	99A2      	P12V_S3_AUX_CPU1_NVDIMM
          	               	2         	99A2      	GND                 

C56       	Q_CAP_C0402    	          	          	                    
          	               	1         	100A3     	P3V3_AUX            
          	               	2         	100A3     	GND                 

C57       	Q_CAP_C0805    	          	          	                    
          	               	1         	100A2     	P12V_S3_AUX_CPU1_NVDIMM
          	               	2         	100A2     	GND                 

C58       	Q_CAP_C0805    	          	          	                    
          	               	1         	100A2     	P12V_S3_AUX_CPU1_NVDIMM
          	               	2         	100A2     	GND                 

C59       	Q_CAP_C0402    	          	          	                    
          	               	1         	101A3     	P3V3_AUX            
          	               	2         	101A3     	GND                 

C60       	Q_CAP_C0805    	          	          	                    
          	               	1         	101A2     	P12V_S3_AUX_CPU1_NVDIMM
          	               	2         	101A2     	GND                 

C61       	Q_CAP_C0805    	          	          	                    
          	               	1         	101A2     	P12V_S3_AUX_CPU1_NVDIMM
          	               	2         	101A2     	GND                 

C62       	Q_CAP_C0402    	          	          	                    
          	               	1         	102A3     	P3V3_AUX            
          	               	2         	102A3     	GND                 

C63       	Q_CAP_C0805    	          	          	                    
          	               	1         	102A2     	P12V_S3_AUX_CPU1_NVDIMM
          	               	2         	102A2     	GND                 

C64       	Q_CAP_C0805    	          	          	                    
          	               	1         	102A2     	P12V_S3_AUX_CPU1_NVDIMM
          	               	2         	102A2     	GND                 

C65       	Q_CAP_C0402    	          	          	                    
          	               	1         	103A3     	P3V3_AUX            
          	               	2         	103A3     	GND                 

C66       	Q_CAP_C0805    	          	          	                    
          	               	1         	103A2     	P12V_S3_AUX_CPU1_NVDIMM
          	               	2         	103A2     	GND                 

C67       	Q_CAP_C0805    	          	          	                    
          	               	1         	103A2     	P12V_S3_AUX_CPU1_NVDIMM
          	               	2         	103A2     	GND                 

C68       	Q_CAP_C0402    	          	          	                    
          	               	1         	104A3     	P3V3_AUX            
          	               	2         	104A3     	GND                 

C69       	Q_CAP_C0805    	          	          	                    
          	               	1         	104A2     	P12V_S3_AUX_CPU1_NVDIMM
          	               	2         	104A2     	GND                 

C70       	Q_CAP_C0805    	          	          	                    
          	               	1         	104A2     	P12V_S3_AUX_CPU1_NVDIMM
          	               	2         	104A2     	GND                 

C71       	Q_CAP_C0402    	          	          	                    
          	               	1         	68B3      	P3V3_AUX            
          	               	2         	68B3      	GND                 

C72       	Q_CAP_C0402    	          	          	                    
          	               	1         	113A3     	P3V3_AUX            
          	               	2         	113A3     	GND                 

C73       	Q_CAP_C0805    	          	          	                    
          	               	1         	113A2     	P12V_S3_AUX_CPU1_NVDIMM
          	               	2         	113A2     	GND                 

C74       	Q_CAP_C0805    	          	          	                    
          	               	1         	113A2     	P12V_S3_AUX_CPU1_NVDIMM
          	               	2         	113A2     	GND                 

C75       	Q_CAP_C0402    	          	          	                    
          	               	1         	112A3     	P3V3_AUX            
          	               	2         	112A3     	GND                 

C76       	Q_CAP_C0805    	          	          	                    
          	               	1         	112A2     	P12V_S3_AUX_CPU1_NVDIMM
          	               	2         	112A2     	GND                 

C77       	Q_CAP_C0805    	          	          	                    
          	               	1         	112A2     	P12V_S3_AUX_CPU1_NVDIMM
          	               	2         	112A2     	GND                 

C78       	Q_CAP_C0402    	          	          	                    
          	               	1         	111A3     	P3V3_AUX            
          	               	2         	111A3     	GND                 

C79       	Q_CAP_C0805    	          	          	                    
          	               	1         	111A2     	P12V_S3_AUX_CPU1_NVDIMM
          	               	2         	111A2     	GND                 

C80       	Q_CAP_C0805    	          	          	                    
          	               	1         	111A2     	P12V_S3_AUX_CPU1_NVDIMM
          	               	2         	111A2     	GND                 

C81       	Q_CAP_C0402    	          	          	                    
          	               	1         	110A3     	P3V3_AUX            
          	               	2         	110A3     	GND                 

C82       	Q_CAP_C0805    	          	          	                    
          	               	1         	110A2     	P12V_S3_AUX_CPU1_NVDIMM
          	               	2         	110A2     	GND                 

C83       	Q_CAP_C0805    	          	          	                    
          	               	1         	110A2     	P12V_S3_AUX_CPU1_NVDIMM
          	               	2         	110A2     	GND                 

C84       	Q_CAP_C0402    	          	          	                    
          	               	1         	109A3     	P3V3_AUX            
          	               	2         	109A3     	GND                 

C85       	Q_CAP_C0805    	          	          	                    
          	               	1         	109A2     	P12V_S3_AUX_CPU1_NVDIMM
          	               	2         	109A2     	GND                 

C86       	Q_CAP_C0805    	          	          	                    
          	               	1         	109A2     	P12V_S3_AUX_CPU1_NVDIMM
          	               	2         	109A2     	GND                 

C87       	Q_CAP_C0402    	          	          	                    
          	               	1         	108A3     	P3V3_AUX            
          	               	2         	108A3     	GND                 

C88       	Q_CAP_C0805    	          	          	                    
          	               	1         	108A2     	P12V_S3_AUX_CPU1_NVDIMM
          	               	2         	108A2     	GND                 

C89       	Q_CAP_C0805    	          	          	                    
          	               	1         	108A2     	P12V_S3_AUX_CPU1_NVDIMM
          	               	2         	108A2     	GND                 

C90       	Q_CAP_C0402    	          	          	                    
          	               	1         	107A3     	P3V3_AUX            
          	               	2         	107A3     	GND                 

C91       	Q_CAP_C0805    	          	          	                    
          	               	1         	107A2     	P12V_S3_AUX_CPU1_NVDIMM
          	               	2         	107A2     	GND                 

C92       	Q_CAP_C0805    	          	          	                    
          	               	1         	107A2     	P12V_S3_AUX_CPU1_NVDIMM
          	               	2         	107A2     	GND                 

C93       	Q_CAP_C0402    	          	          	                    
          	               	1         	106A3     	P3V3_AUX            
          	               	2         	106A3     	GND                 

C94       	Q_CAP_C0805    	          	          	                    
          	               	1         	106A2     	P12V_S3_AUX_CPU1_NVDIMM
          	               	2         	106A2     	GND                 

C95       	Q_CAP_C0805    	          	          	                    
          	               	1         	106A2     	P12V_S3_AUX_CPU1_NVDIMM
          	               	2         	106A2     	GND                 

C96       	Q_CAP_C0402    	          	          	                    
          	               	1         	105A3     	P3V3_AUX            
          	               	2         	105A3     	GND                 

C97       	Q_CAP_C0805    	          	          	                    
          	               	1         	105A2     	P12V_S3_AUX_CPU1_NVDIMM
          	               	2         	105A2     	GND                 

C98       	Q_CAP_C0805    	          	          	                    
          	               	1         	105A2     	P12V_S3_AUX_CPU1_NVDIMM
          	               	2         	105A2     	GND                 

C101      	Q_CAP_C0805    	          	          	                    
          	               	1         	74B4      	PVCCIN_CPU0         
          	               	2         	74B4      	GND                 

C103      	Q_CAP_0402     	          	          	                    
          	               	1         	179A4     	XTAL_PCH_25M_IN_R   
          	               	2         	179A4     	GND                 

C104      	Q_CAP_0402     	          	          	                    
          	               	1         	179A4     	XTAL_PCH_25M_OUT    
          	               	2         	179A4     	GND                 

C107      	Q_CAP_C0402    	          	          	                    
          	               	1         	210B4     	P3V3_AUX_CLK_GEN_VDD_CK440
          	               	2         	210B4     	GND                 

C108      	Q_CAP_C0603    	          	          	                    
          	               	1         	210B4     	P3V3_AUX_CLK_GEN_VDD_CK440
          	               	2         	210B4     	GND                 

C110      	Q_CAP_C0402    	          	          	                    
          	               	1         	210B4     	P3V3_AUX_CLK_GEN_VDD_CK440
          	               	2         	210B4     	GND                 

C111      	Q_CAP_C0402    	          	          	                    
          	               	1         	210B4     	P3V3_AUX_CLK_GEN_VDDXTAL_CK440
          	               	2         	210B4     	GND                 

C112      	Q_CAP_C0402    	          	          	                    
          	               	1         	210B4     	P3V3_AUX_CLK_GEN_VDDXTAL_CK440
          	               	2         	210B4     	GND                 

C114      	Q_CAP_C0402    	          	          	                    
          	               	1         	210B3     	P3V3_AUX_CLK_GEN_VDDA25M_CK440
          	               	2         	210B3     	GND                 

C115      	Q_CAP_C0402    	          	          	                    
          	               	1         	210B4     	P3V3_AUX_CLK_GEN_VDDMXCK_CK440
          	               	2         	210A4     	GND                 

C116      	Q_CAP_C0402    	          	          	                    
          	               	1         	210B4     	P3V3_AUX_CLK_GEN_VDDMXCK_CK440
          	               	2         	210A4     	GND                 

C117      	Q_CAP_C0402    	          	          	                    
          	               	1         	210B4     	P3V3_AUX_CLK_GEN_VDDMXCK_CK440
          	               	2         	210A4     	GND                 

C119      	Q_CAP_C0402    	          	          	                    
          	               	1         	210B4     	P3V3_AUX_CLK_GEN_VDDMXCK_CK440
          	               	2         	210A4     	GND                 

C120      	Q_CAP_C0402    	          	          	                    
          	               	1         	210B3     	P3V3_AUX_CLK_GEN_VDDPT_CK440
          	               	2         	210A3     	GND                 

C139      	Q_CAP_DIFFBUS_C0201	          	          	                    
          	               	1         	178B3     	DMI_CPU0_PCH_TX_C_DN<7>
          	               	2         	178B3     	DMI_CPU0_PCH_TX_DN<7>

C141      	Q_CAP_DIFFBUS_C0201	          	          	                    
          	               	1         	178B3     	DMI_CPU0_PCH_TX_C_DN<6>
          	               	2         	178B3     	DMI_CPU0_PCH_TX_DN<6>

C142      	Q_CAP_DIFFBUS_C0201	          	          	                    
          	               	1         	178B3     	DMI_CPU0_PCH_TX_C_DP<6>
          	               	2         	178B3     	DMI_CPU0_PCH_TX_DP<6>

C143      	Q_CAP_DIFFBUS_C0201	          	          	                    
          	               	1         	178B3     	DMI_CPU0_PCH_TX_C_DN<5>
          	               	2         	178B3     	DMI_CPU0_PCH_TX_DN<5>

C144      	Q_CAP_DIFFBUS_C0201	          	          	                    
          	               	1         	178B3     	DMI_CPU0_PCH_TX_C_DP<5>
          	               	2         	178B3     	DMI_CPU0_PCH_TX_DP<5>

C145      	Q_CAP_DIFFBUS_C0201	          	          	                    
          	               	1         	178B3     	DMI_CPU0_PCH_TX_C_DN<4>
          	               	2         	178B3     	DMI_CPU0_PCH_TX_DN<4>

C146      	Q_CAP_DIFFBUS_C0201	          	          	                    
          	               	1         	178B3     	DMI_CPU0_PCH_TX_C_DP<4>
          	               	2         	178B3     	DMI_CPU0_PCH_TX_DP<4>

C147      	Q_CAP_DIFFBUS_C0201	          	          	                    
          	               	1         	178B3     	DMI_CPU0_PCH_TX_C_DN<3>
          	               	2         	178B3     	DMI_CPU0_PCH_TX_DN<3>

C148      	Q_CAP_DIFFBUS_C0201	          	          	                    
          	               	1         	178B3     	DMI_CPU0_PCH_TX_C_DP<3>
          	               	2         	178B3     	DMI_CPU0_PCH_TX_DP<3>

C149      	Q_CAP_DIFFBUS_C0201	          	          	                    
          	               	1         	178B3     	DMI_CPU0_PCH_TX_C_DN<2>
          	               	2         	178B3     	DMI_CPU0_PCH_TX_DN<2>

C150      	Q_CAP_DIFFBUS_C0201	          	          	                    
          	               	1         	178B3     	DMI_CPU0_PCH_TX_C_DP<2>
          	               	2         	178B3     	DMI_CPU0_PCH_TX_DP<2>

C151      	Q_CAP_DIFFBUS_C0201	          	          	                    
          	               	1         	178B3     	DMI_CPU0_PCH_TX_C_DN<1>
          	               	2         	178B3     	DMI_CPU0_PCH_TX_DN<1>

C152      	Q_CAP_DIFFBUS_C0201	          	          	                    
          	               	1         	178B3     	DMI_CPU0_PCH_TX_C_DP<1>
          	               	2         	178B3     	DMI_CPU0_PCH_TX_DP<1>

C153      	Q_CAP_DIFFBUS_C0201	          	          	                    
          	               	1         	178B3     	DMI_CPU0_PCH_TX_C_DN<0>
          	               	2         	178B3     	DMI_CPU0_PCH_TX_DN<0>

C154      	Q_CAP_DIFFBUS_C0201	          	          	                    
          	               	1         	178B3     	DMI_CPU0_PCH_TX_C_DP<0>
          	               	2         	178B3     	DMI_CPU0_PCH_TX_DP<0>

C155      	Q_CAP_DIFFBUS_C0201	          	          	                    
          	               	1         	178B3     	DMI_CPU0_PCH_RX_C_DN<7>
          	               	2         	178B3     	DMI_CPU0_PCH_RX_DN<7>

C156      	Q_CAP_DIFFBUS_C0201	          	          	                    
          	               	1         	178B3     	DMI_CPU0_PCH_RX_C_DP<7>
          	               	2         	178B3     	DMI_CPU0_PCH_RX_DP<7>

C157      	Q_CAP_DIFFBUS_C0201	          	          	                    
          	               	1         	178B3     	DMI_CPU0_PCH_RX_C_DN<6>
          	               	2         	178B3     	DMI_CPU0_PCH_RX_DN<6>

C158      	Q_CAP_DIFFBUS_C0201	          	          	                    
          	               	1         	178B3     	DMI_CPU0_PCH_RX_C_DP<6>
          	               	2         	178B3     	DMI_CPU0_PCH_RX_DP<6>

C159      	Q_CAP_DIFFBUS_C0201	          	          	                    
          	               	1         	178B3     	DMI_CPU0_PCH_RX_C_DN<5>
          	               	2         	178B3     	DMI_CPU0_PCH_RX_DN<5>

C160      	Q_CAP_DIFFBUS_C0201	          	          	                    
          	               	1         	178A3     	DMI_CPU0_PCH_RX_C_DP<5>
          	               	2         	178A3     	DMI_CPU0_PCH_RX_DP<5>

C161      	Q_CAP_DIFFBUS_C0201	          	          	                    
          	               	1         	178A3     	DMI_CPU0_PCH_RX_C_DN<4>
          	               	2         	178A3     	DMI_CPU0_PCH_RX_DN<4>

C162      	Q_CAP_DIFFBUS_C0201	          	          	                    
          	               	1         	178A3     	DMI_CPU0_PCH_RX_C_DP<4>
          	               	2         	178A3     	DMI_CPU0_PCH_RX_DP<4>

C163      	Q_CAP_DIFFBUS_C0201	          	          	                    
          	               	1         	178A3     	DMI_CPU0_PCH_RX_C_DN<3>
          	               	2         	178A3     	DMI_CPU0_PCH_RX_DN<3>

C164      	Q_CAP_DIFFBUS_C0201	          	          	                    
          	               	1         	178A3     	DMI_CPU0_PCH_RX_C_DP<3>
          	               	2         	178A3     	DMI_CPU0_PCH_RX_DP<3>

C165      	Q_CAP_DIFFBUS_C0201	          	          	                    
          	               	1         	178A3     	DMI_CPU0_PCH_RX_C_DN<2>
          	               	2         	178A3     	DMI_CPU0_PCH_RX_DN<2>

C166      	Q_CAP_DIFFBUS_C0201	          	          	                    
          	               	1         	178A3     	DMI_CPU0_PCH_RX_C_DP<2>
          	               	2         	178A3     	DMI_CPU0_PCH_RX_DP<2>

C167      	Q_CAP_DIFFBUS_C0201	          	          	                    
          	               	1         	178A3     	DMI_CPU0_PCH_RX_C_DN<1>
          	               	2         	178A3     	DMI_CPU0_PCH_RX_DN<1>

C168      	Q_CAP_DIFFBUS_C0201	          	          	                    
          	               	1         	178A3     	DMI_CPU0_PCH_RX_C_DP<1>
          	               	2         	178A3     	DMI_CPU0_PCH_RX_DP<1>

C169      	Q_CAP_DIFFBUS_C0201	          	          	                    
          	               	1         	178A3     	DMI_CPU0_PCH_RX_C_DN<0>
          	               	2         	178A3     	DMI_CPU0_PCH_RX_DN<0>

C170      	Q_CAP_DIFFBUS_C0201	          	          	                    
          	               	1         	178A3     	DMI_CPU0_PCH_RX_C_DP<0>
          	               	2         	178A3     	DMI_CPU0_PCH_RX_DP<0>

C171      	Q_CAP_C0402    	          	          	                    
          	               	1         	210B4     	P3V3_AUX_CLK_GEN_VDD_CK440
          	               	2         	210B4     	GND                 

C172      	Q_CAP_C0603    	          	          	                    
          	               	1         	210B3     	P3V3_AUX_CLK_GEN_VDDA100M_CK440
          	               	2         	210B3     	GND                 

C173      	Q_CAP_C0402    	          	          	                    
          	               	1         	210B3     	P3V3_AUX_CLK_GEN_VDDA100M_CK440
          	               	2         	210B3     	GND                 

C174      	Q_CAP_0402     	          	          	                    
          	               	1         	231B3     	P3V3_AUX            
          	               	2         	231B3     	GND                 

C188      	Q_CAP_0402     	          	          	                    
          	               	1         	155B3     	P3V3_AUX            
          	               	2         	155B3     	GND                 

C204      	Q_CAP_0402     	          	          	                    
          	               	1         	206B4     	P3V3_DB2000_VDD     
          	               	2         	206B4     	GND                 

C205      	Q_CAP_0402     	          	          	                    
          	               	1         	206B4     	P3V3_DB2000_VDD     
          	               	2         	206B4     	GND                 

C206      	Q_CAP_0402     	          	          	                    
          	               	1         	206B4     	P3V3_DB2000_VDD     
          	               	2         	206B4     	GND                 

C207      	Q_CAP_0402     	          	          	                    
          	               	1         	206B4     	P3V3_DB2000_VDD     
          	               	2         	206B4     	GND                 

C208      	Q_CAP_C0603    	          	          	                    
          	               	1         	206B4     	P3V3_DB2000_VDDR    
          	               	2         	206B4     	GND                 

C209      	Q_CAP_C0603    	          	          	                    
          	               	1         	206B4     	P3V3_DB2000_VDDA    
          	               	2         	206B4     	GND                 

C210      	Q_CAP_0402     	          	          	                    
          	               	1         	206B4     	P3V3_DB2000_VDDR    
          	               	2         	206B4     	GND                 

C211      	Q_CAP_0402     	          	          	                    
          	               	1         	206B4     	P3V3_DB2000_VDDA    
          	               	2         	206B4     	GND                 

C212      	Q_CAP_C0805    	          	          	                    
          	               	1         	74B4      	PVCCIN_CPU0         
          	               	2         	74B4      	GND                 

C213      	Q_CAP_C0805    	          	          	                    
          	               	1         	74B4      	PVCCIN_CPU0         
          	               	2         	74B4      	GND                 

C214      	Q_CAP_C0805    	          	          	                    
          	               	1         	74B4      	PVCCIN_CPU0         
          	               	2         	74B4      	GND                 

C215      	Q_CAP_C0805    	          	          	                    
          	               	1         	74B4      	PVCCIN_CPU0         
          	               	2         	74B4      	GND                 

C216      	Q_CAP_C0805    	          	          	                    
          	               	1         	74B4      	PVCCIN_CPU0         
          	               	2         	74B4      	GND                 

C217      	Q_CAP_C0805    	          	          	                    
          	               	1         	74B4      	PVCCIN_CPU0         
          	               	2         	74B4      	GND                 

C218      	Q_CAP_C0805    	          	          	                    
          	               	1         	74B3      	PVCCIN_CPU0         
          	               	2         	74B3      	GND                 

C219      	Q_CAP_C0805    	          	          	                    
          	               	1         	74B3      	PVCCIN_CPU0         
          	               	2         	74B3      	GND                 

C220      	Q_CAP_C0805    	          	          	                    
          	               	1         	74B3      	PVCCIN_CPU0         
          	               	2         	74B3      	GND                 

C221      	Q_CAP_C0402    	          	          	                    
          	               	1         	77B4      	PVCCIN_CPU1         
          	               	2         	77B4      	GND                 

C222      	Q_CAP_C0402    	          	          	                    
          	               	1         	77B4      	PVCCIN_CPU1         
          	               	2         	77B4      	GND                 

C223      	Q_CAP_C0402    	          	          	                    
          	               	1         	77B4      	PVCCIN_CPU1         
          	               	2         	77B4      	GND                 

C224      	Q_CAP_C0402    	          	          	                    
          	               	1         	77B4      	PVCCIN_CPU1         
          	               	2         	77B4      	GND                 

C225      	Q_CAP_C0805    	          	          	                    
          	               	1         	77B4      	PVCCIN_CPU1         
          	               	2         	77B4      	GND                 

C226      	Q_CAP_C0402    	          	          	                    
          	               	1         	77B4      	PVCCIN_CPU1         
          	               	2         	77B4      	GND                 

C227      	Q_CAP_C0402    	          	          	                    
          	               	1         	77B4      	PVCCIN_CPU1         
          	               	2         	77B4      	GND                 

C228      	Q_CAP_C0402    	          	          	                    
          	               	1         	77B4      	PVCCIN_CPU1         
          	               	2         	77B4      	GND                 

C229      	Q_CAP_C0402    	          	          	                    
          	               	1         	77B4      	PVCCIN_CPU1         
          	               	2         	77B4      	GND                 

C230      	Q_CAP_C0805    	          	          	                    
          	               	1         	77B4      	PVCCIN_CPU1         
          	               	2         	77B4      	GND                 

C231      	Q_CAP_C0402    	          	          	                    
          	               	1         	77B4      	PVCCIN_CPU1         
          	               	2         	77B4      	GND                 

C232      	Q_CAP_C0402    	          	          	                    
          	               	1         	77B4      	PVCCIN_CPU1         
          	               	2         	77B4      	GND                 

C233      	Q_CAP_C0402    	          	          	                    
          	               	1         	77B4      	PVCCIN_CPU1         
          	               	2         	77B4      	GND                 

C234      	Q_CAP_C0402    	          	          	                    
          	               	1         	77B4      	PVCCIN_CPU1         
          	               	2         	77B4      	GND                 

C235      	Q_CAP_C0805    	          	          	                    
          	               	1         	77B4      	PVCCIN_CPU1         
          	               	2         	77B4      	GND                 

C236      	Q_CAP_C0402    	          	          	                    
          	               	1         	77B4      	PVCCIN_CPU1         
          	               	2         	77B4      	GND                 

C237      	Q_CAP_C0402    	          	          	                    
          	               	1         	77B4      	PVCCIN_CPU1         
          	               	2         	77B4      	GND                 

C238      	Q_CAP_C0402    	          	          	                    
          	               	1         	77B4      	PVCCIN_CPU1         
          	               	2         	77B4      	GND                 

C239      	Q_CAP_C0402    	          	          	                    
          	               	1         	77B4      	PVCCIN_CPU1         
          	               	2         	77B4      	GND                 

C240      	Q_CAP_C0805    	          	          	                    
          	               	1         	77B4      	PVCCIN_CPU1         
          	               	2         	77B4      	GND                 

C241      	Q_CAP_C0402    	          	          	                    
          	               	1         	77B4      	PVCCIN_CPU1         
          	               	2         	77B4      	GND                 

C242      	Q_CAP_C0402    	          	          	                    
          	               	1         	77B4      	PVCCIN_CPU1         
          	               	2         	77B4      	GND                 

C243      	Q_CAP_C0402    	          	          	                    
          	               	1         	77B4      	PVCCIN_CPU1         
          	               	2         	77B4      	GND                 

C244      	Q_CAP_C0402    	          	          	                    
          	               	1         	77B4      	PVCCIN_CPU1         
          	               	2         	77B4      	GND                 

C245      	Q_CAP_C0805    	          	          	                    
          	               	1         	77B4      	PVCCIN_CPU1         
          	               	2         	77B4      	GND                 

C246      	Q_CAP_C0402    	          	          	                    
          	               	1         	77B4      	PVCCIN_CPU1         
          	               	2         	77B4      	GND                 

C247      	Q_CAP_C0402    	          	          	                    
          	               	1         	77B4      	PVCCIN_CPU1         
          	               	2         	77B4      	GND                 

C248      	Q_CAP_C0402    	          	          	                    
          	               	1         	77B4      	PVCCIN_CPU1         
          	               	2         	77B4      	GND                 

C249      	Q_CAP_C0402    	          	          	                    
          	               	1         	77B4      	PVCCIN_CPU1         
          	               	2         	77B4      	GND                 

C250      	Q_CAP_C0805    	          	          	                    
          	               	1         	77B4      	PVCCIN_CPU1         
          	               	2         	77B4      	GND                 

C251      	Q_CAP_C0402    	          	          	                    
          	               	1         	77B4      	PVCCIN_CPU1         
          	               	2         	77B4      	GND                 

C252      	Q_CAP_C0402    	          	          	                    
          	               	1         	77B4      	PVCCIN_CPU1         
          	               	2         	77B4      	GND                 

C253      	Q_CAP_C0402    	          	          	                    
          	               	1         	77B4      	PVCCIN_CPU1         
          	               	2         	77B4      	GND                 

C254      	Q_CAP_C0402    	          	          	                    
          	               	1         	77B4      	PVCCIN_CPU1         
          	               	2         	77B4      	GND                 

C255      	Q_CAP_C0805    	          	          	                    
          	               	1         	77B4      	PVCCIN_CPU1         
          	               	2         	77B4      	GND                 

C256      	Q_CAP_C0402    	          	          	                    
          	               	1         	77B3      	PVCCIN_CPU1         
          	               	2         	77B3      	GND                 

C257      	Q_CAP_C0402    	          	          	                    
          	               	1         	77B3      	PVCCIN_CPU1         
          	               	2         	77B3      	GND                 

C258      	Q_CAP_C0402    	          	          	                    
          	               	1         	77B3      	PVCCIN_CPU1         
          	               	2         	77B3      	GND                 

C259      	Q_CAP_C0402    	          	          	                    
          	               	1         	77B3      	PVCCIN_CPU1         
          	               	2         	77B3      	GND                 

C260      	Q_CAP_C0805    	          	          	                    
          	               	1         	77B3      	PVCCIN_CPU1         
          	               	2         	77B3      	GND                 

C261      	Q_CAP_C0402    	          	          	                    
          	               	1         	77B3      	PVCCIN_CPU1         
          	               	2         	77B3      	GND                 

C262      	Q_CAP_C0402    	          	          	                    
          	               	1         	77B3      	PVCCIN_CPU1         
          	               	2         	77B3      	GND                 

C263      	Q_CAP_C0402    	          	          	                    
          	               	1         	77B3      	PVCCIN_CPU1         
          	               	2         	77B3      	GND                 

C264      	Q_CAP_C0402    	          	          	                    
          	               	1         	77B3      	PVCCIN_CPU1         
          	               	2         	77B3      	GND                 

C265      	Q_CAP_C0805    	          	          	                    
          	               	1         	77B3      	PVCCIN_CPU1         
          	               	2         	77B3      	GND                 

C266      	Q_CAP_C0402    	          	          	                    
          	               	1         	77B3      	PVCCIN_CPU1         
          	               	2         	77B3      	GND                 

C267      	Q_CAP_C0402    	          	          	                    
          	               	1         	77B3      	PVCCIN_CPU1         
          	               	2         	77B3      	GND                 

C268      	Q_CAP_C0402    	          	          	                    
          	               	1         	77B3      	PVCCIN_CPU1         
          	               	2         	77B3      	GND                 

C269      	Q_CAP_C0402    	          	          	                    
          	               	1         	77B3      	PVCCIN_CPU1         
          	               	2         	77B3      	GND                 

C270      	Q_CAP_C0805    	          	          	                    
          	               	1         	77B3      	PVCCIN_CPU1         
          	               	2         	77B3      	GND                 

C271      	Q_CAP_C0402    	          	          	                    
          	               	1         	77B3      	PVCCIN_CPU1         
          	               	2         	77B3      	GND                 

C272      	Q_CAP_C0402    	          	          	                    
          	               	1         	77B3      	PVCCIN_CPU1         
          	               	2         	77B3      	GND                 

C273      	Q_CAP_C0402    	          	          	                    
          	               	1         	77B3      	PVCCIN_CPU1         
          	               	2         	77B3      	GND                 

C274      	Q_CAP_C0402    	          	          	                    
          	               	1         	77B3      	PVCCIN_CPU1         
          	               	2         	77B3      	GND                 

C275      	Q_CAP_C0402    	          	          	                    
          	               	1         	77B3      	PVCCIN_CPU1         
          	               	2         	77B3      	GND                 

C276      	Q_CAP_C0402    	          	          	                    
          	               	1         	77B3      	PVCCIN_CPU1         
          	               	2         	77B3      	GND                 

C277      	Q_CAP_C0402    	          	          	                    
          	               	1         	77B3      	PVCCIN_CPU1         
          	               	2         	77B3      	GND                 

C278      	Q_CAP_C0402    	          	          	                    
          	               	1         	77B3      	PVCCIN_CPU1         
          	               	2         	77B3      	GND                 

C279      	Q_CAP_C0402    	          	          	                    
          	               	1         	77B2      	PVCCIN_CPU1         
          	               	2         	77B2      	GND                 

C280      	Q_CAP_C0402    	          	          	                    
          	               	1         	77B2      	PVCCIN_CPU1         
          	               	2         	77B2      	GND                 

C281      	Q_CAP_C0402    	          	          	                    
          	               	1         	77B2      	PVCCIN_CPU1         
          	               	2         	77B2      	GND                 

C282      	Q_CAP_C0402    	          	          	                    
          	               	1         	77B2      	PVCCIN_CPU1         
          	               	2         	77B2      	GND                 

C283      	Q_CAP_C0402    	          	          	                    
          	               	1         	77B2      	PVCCIN_CPU1         
          	               	2         	77B2      	GND                 

C284      	Q_CAP_C0402    	          	          	                    
          	               	1         	77B2      	PVCCIN_CPU1         
          	               	2         	77B2      	GND                 

C285      	Q_CAP_C0402    	          	          	                    
          	               	1         	77B2      	PVCCIN_CPU1         
          	               	2         	77B2      	GND                 

C286      	Q_CAP_C0402    	          	          	                    
          	               	1         	77B2      	PVCCIN_CPU1         
          	               	2         	77B2      	GND                 

C287      	Q_CAP_C0402    	          	          	                    
          	               	1         	77B2      	PVCCIN_CPU1         
          	               	2         	77B2      	GND                 

C288      	Q_CAP_C0402    	          	          	                    
          	               	1         	77B2      	PVCCIN_CPU1         
          	               	2         	77B2      	GND                 

C289      	Q_CAP_C0402    	          	          	                    
          	               	1         	77B2      	PVCCIN_CPU1         
          	               	2         	77B2      	GND                 

C290      	Q_CAP_C0402    	          	          	                    
          	               	1         	77B2      	PVCCIN_CPU1         
          	               	2         	77B2      	GND                 

C291      	Q_CAP_C0402    	          	          	                    
          	               	1         	77B2      	PVCCIN_CPU1         
          	               	2         	77B2      	GND                 

C292      	Q_CAP_C0402    	          	          	                    
          	               	1         	77B2      	PVCCIN_CPU1         
          	               	2         	77B2      	GND                 

C293      	Q_CAP_C0402    	          	          	                    
          	               	1         	77B2      	PVCCIN_CPU1         
          	               	2         	77B2      	GND                 

C294      	Q_CAP_C0402    	          	          	                    
          	               	1         	77B2      	PVCCIN_CPU1         
          	               	2         	77B2      	GND                 

C295      	Q_CAP_C0402    	          	          	                    
          	               	1         	77B1      	PVCCIN_CPU1         
          	               	2         	77B1      	GND                 

C296      	Q_CAP_C0402    	          	          	                    
          	               	1         	77B1      	PVCCIN_CPU1         
          	               	2         	77B1      	GND                 

C297      	Q_CAP_C0402    	          	          	                    
          	               	1         	77B1      	PVCCIN_CPU1         
          	               	2         	77B1      	GND                 

C298      	Q_CAP_C0402    	          	          	                    
          	               	1         	77B1      	PVCCIN_CPU1         
          	               	2         	77B1      	GND                 

C299      	Q_CAP_C0402    	          	          	                    
          	               	1         	77B1      	PVCCIN_CPU1         
          	               	2         	77B1      	GND                 

C300      	Q_CAP_C0402    	          	          	                    
          	               	1         	77B1      	PVCCIN_CPU1         
          	               	2         	77B1      	GND                 

C301      	Q_CAP_C0402    	          	          	                    
          	               	1         	77B1      	PVCCIN_CPU1         
          	               	2         	77B1      	GND                 

C302      	Q_CAP_C0402    	          	          	                    
          	               	1         	77B1      	PVCCIN_CPU1         
          	               	2         	77B1      	GND                 

C303      	Q_CAP_C0402    	          	          	                    
          	               	1         	77B1      	PVCCIN_CPU1         
          	               	2         	77B1      	GND                 

C304      	Q_CAP_C0402    	          	          	                    
          	               	1         	77B1      	PVCCIN_CPU1         
          	               	2         	77B1      	GND                 

C305      	Q_CAP_C0402    	          	          	                    
          	               	1         	77B1      	PVCCIN_CPU1         
          	               	2         	77B1      	GND                 

C306      	Q_CAP_C0402    	          	          	                    
          	               	1         	77B1      	PVCCIN_CPU1         
          	               	2         	77B1      	GND                 

C307      	Q_CAP_C0402    	          	          	                    
          	               	1         	77B1      	PVCCIN_CPU1         
          	               	2         	77B1      	GND                 

C308      	Q_CAP_C0402    	          	          	                    
          	               	1         	77B1      	PVCCIN_CPU1         
          	               	2         	77B1      	GND                 

C309      	Q_CAP_C0402    	          	          	                    
          	               	1         	77B1      	PVCCIN_CPU1         
          	               	2         	77B1      	GND                 

C310      	Q_CAP_C0402    	          	          	                    
          	               	1         	77B2      	PVNN_MAIN_CPU1      
          	               	2         	77B2      	GND                 

C311      	Q_CAP_C0805    	          	          	                    
          	               	1         	78B4      	PVCCIN_CPU1         
          	               	2         	78B4      	GND                 

C312      	Q_CAP_C0805    	          	          	                    
          	               	1         	78B4      	PVCCIN_CPU1         
          	               	2         	78B4      	GND                 

C313      	Q_CAP_C0805    	          	          	                    
          	               	1         	78B3      	PVCCIN_CPU1         
          	               	2         	78B3      	GND                 

C314      	Q_CAP_C0805    	          	          	                    
          	               	1         	78B4      	PVCCIN_CPU1         
          	               	2         	78B4      	GND                 

C315      	Q_CAP_C0805    	          	          	                    
          	               	1         	78B4      	PVCCIN_CPU1         
          	               	2         	78B4      	GND                 

C316      	Q_CAP_C0805    	          	          	                    
          	               	1         	78B3      	PVCCIN_CPU1         
          	               	2         	78B3      	GND                 

C317      	Q_CAP_C0805    	          	          	                    
          	               	1         	78B4      	PVCCIN_CPU1         
          	               	2         	78B4      	GND                 

C318      	Q_CAP_C0805    	          	          	                    
          	               	1         	78B4      	PVCCIN_CPU1         
          	               	2         	78B4      	GND                 

C320      	Q_CAP_C0805    	          	          	                    
          	               	1         	78B4      	PVCCIN_CPU1         
          	               	2         	78B4      	GND                 

C321      	Q_CAP_C0805    	          	          	                    
          	               	1         	78B4      	PVCCIN_CPU1         
          	               	2         	78B4      	GND                 

C322      	Q_CAP_C0805    	          	          	                    
          	               	1         	79B3      	PVCCIN_CPU1         
          	               	2         	79B3      	GND                 

C323      	Q_CAP_C0805    	          	          	                    
          	               	1         	78B4      	PVCCIN_CPU1         
          	               	2         	78B4      	GND                 

C324      	Q_CAP_C0805    	          	          	                    
          	               	1         	78B4      	PVCCIN_CPU1         
          	               	2         	78B4      	GND                 

C325      	Q_CAP_C0805    	          	          	                    
          	               	1         	79B3      	PVCCIN_CPU1         
          	               	2         	79B3      	GND                 

C326      	Q_CAP_C0805    	          	          	                    
          	               	1         	78B4      	PVCCIN_CPU1         
          	               	2         	78B4      	GND                 

C327      	Q_CAP_C0805    	          	          	                    
          	               	1         	78B4      	PVCCIN_CPU1         
          	               	2         	78B4      	GND                 

C328      	Q_CAP_C0805    	          	          	                    
          	               	1         	79B3      	PVCCIN_CPU1         
          	               	2         	79B3      	GND                 

C329      	Q_CAP_C0805    	          	          	                    
          	               	1         	78B4      	PVCCIN_CPU1         
          	               	2         	78B4      	GND                 

C330      	Q_CAP_C0805    	          	          	                    
          	               	1         	78B4      	PVCCIN_CPU1         
          	               	2         	78B4      	GND                 

C332      	Q_CAP_C0805    	          	          	                    
          	               	1         	78B3      	PVCCIN_CPU1         
          	               	2         	78B3      	GND                 

C333      	Q_CAP_C0805    	          	          	                    
          	               	1         	78B3      	PVCCIN_CPU1         
          	               	2         	78B3      	GND                 

C335      	Q_CAP_C0805    	          	          	                    
          	               	1         	78B3      	PVCCIN_CPU1         
          	               	2         	78B3      	GND                 

C336      	Q_CAP_C0805    	          	          	                    
          	               	1         	78B3      	PVCCIN_CPU1         
          	               	2         	78B3      	GND                 

C337      	Q_CAP_C0805    	          	          	                    
          	               	1         	78B2      	PVCCIN_CPU1         
          	               	2         	78B2      	GND                 

C338      	Q_CAP_C0805    	          	          	                    
          	               	1         	78B3      	PVCCIN_CPU1         
          	               	2         	78B3      	GND                 

C339      	Q_CAP_C0805    	          	          	                    
          	               	1         	78B3      	PVCCIN_CPU1         
          	               	2         	78B3      	GND                 

C341      	Q_CAP_C0805    	          	          	                    
          	               	1         	79B3      	PVCCIN_CPU1         
          	               	2         	79B3      	GND                 

C342      	Q_CAP_C0805    	          	          	                    
          	               	1         	79B4      	PVCCIN_CPU1         
          	               	2         	79B4      	GND                 

C343      	Q_CAP_C0805    	          	          	                    
          	               	1         	79B3      	PVCCIN_CPU1         
          	               	2         	79B3      	GND                 

C344      	Q_CAP_C0805    	          	          	                    
          	               	1         	79B4      	PVCCIN_CPU1         
          	               	2         	79B4      	GND                 

C345      	Q_CAP_C0805    	          	          	                    
          	               	1         	79B2      	PVCCIN_CPU1         
          	               	2         	79B2      	GND                 

C346      	Q_CAP_C0805    	          	          	                    
          	               	1         	79B4      	PVCCIN_CPU1         
          	               	2         	79B4      	GND                 

C347      	Q_CAP_C0805    	          	          	                    
          	               	1         	79B2      	PVCCIN_CPU1         
          	               	2         	79B2      	GND                 

C348      	Q_CAP_C0805    	          	          	                    
          	               	1         	79B4      	PVCCIN_CPU1         
          	               	2         	79B4      	GND                 

C349      	Q_CAP_C0805    	          	          	                    
          	               	1         	78B3      	PVCCIN_CPU1         
          	               	2         	78B3      	GND                 

C350      	Q_CAP_C0805    	          	          	                    
          	               	1         	79B4      	PVCCIN_CPU1         
          	               	2         	79B4      	GND                 

C351      	Q_CAP_C0805    	          	          	                    
          	               	1         	78B3      	PVCCIN_CPU1         
          	               	2         	78B3      	GND                 

C352      	Q_CAP_C0805    	          	          	                    
          	               	1         	79B4      	PVCCIN_CPU1         
          	               	2         	79B4      	GND                 

C353      	Q_CAP_C0805    	          	          	                    
          	               	1         	78B2      	PVCCIN_CPU1         
          	               	2         	78B2      	GND                 

C354      	Q_CAP_C0805    	          	          	                    
          	               	1         	79B4      	PVCCIN_CPU1         
          	               	2         	79B4      	GND                 

C355      	Q_CAP_C0805    	          	          	                    
          	               	1         	75B4      	PVCCIN_CPU0         
          	               	2         	75B4      	GND                 

C356      	Q_CAP_C0805    	          	          	                    
          	               	1         	75B4      	PVCCIN_CPU0         
          	               	2         	75B4      	GND                 

C357      	Q_CAP_C0805    	          	          	                    
          	               	1         	75B3      	PVCCIN_CPU0         
          	               	2         	75B3      	GND                 

C358      	Q_CAP_C0805    	          	          	                    
          	               	1         	75B4      	PVCCIN_CPU0         
          	               	2         	75B4      	GND                 

C359      	Q_CAP_C0805    	          	          	                    
          	               	1         	75B4      	PVCCIN_CPU0         
          	               	2         	75B4      	GND                 

C360      	Q_CAP_C0805    	          	          	                    
          	               	1         	75B3      	PVCCIN_CPU0         
          	               	2         	75B3      	GND                 

C361      	Q_CAP_C0805    	          	          	                    
          	               	1         	75B4      	PVCCIN_CPU0         
          	               	2         	75B4      	GND                 

C362      	Q_CAP_C0805    	          	          	                    
          	               	1         	75B4      	PVCCIN_CPU0         
          	               	2         	75B4      	GND                 

C363      	Q_CAP_C0805    	          	          	                    
          	               	1         	75B2      	PVCCIN_CPU0         
          	               	2         	75B2      	GND                 

C364      	Q_CAP_C0805    	          	          	                    
          	               	1         	75B4      	PVCCIN_CPU0         
          	               	2         	75B4      	GND                 

C365      	Q_CAP_C0805    	          	          	                    
          	               	1         	75B4      	PVCCIN_CPU0         
          	               	2         	75B4      	GND                 

C366      	Q_CAP_C0805    	          	          	                    
          	               	1         	76B3      	PVCCIN_CPU0         
          	               	2         	76B3      	GND                 

C367      	Q_CAP_C0805    	          	          	                    
          	               	1         	75B4      	PVCCIN_CPU0         
          	               	2         	75B4      	GND                 

C368      	Q_CAP_C0805    	          	          	                    
          	               	1         	75B4      	PVCCIN_CPU0         
          	               	2         	75B4      	GND                 

C369      	Q_CAP_C0805    	          	          	                    
          	               	1         	76B3      	PVCCIN_CPU0         
          	               	2         	76B3      	GND                 

C370      	Q_CAP_C0805    	          	          	                    
          	               	1         	75B4      	PVCCIN_CPU0         
          	               	2         	75B4      	GND                 

C371      	Q_CAP_C0805    	          	          	                    
          	               	1         	75B4      	PVCCIN_CPU0         
          	               	2         	75B4      	GND                 

C372      	Q_CAP_C0805    	          	          	                    
          	               	1         	76B3      	PVCCIN_CPU0         
          	               	2         	76B3      	GND                 

C373      	Q_CAP_C0805    	          	          	                    
          	               	1         	75B4      	PVCCIN_CPU0         
          	               	2         	75B4      	GND                 

C374      	Q_CAP_C0805    	          	          	                    
          	               	1         	76B3      	PVCCIN_CPU0         
          	               	2         	76B3      	GND                 

C376      	Q_CAP_C0805    	          	          	                    
          	               	1         	75B3      	PVCCIN_CPU0         
          	               	2         	75B3      	GND                 

C377      	Q_CAP_C0805    	          	          	                    
          	               	1         	76B3      	PVCCIN_CPU0         
          	               	2         	76B3      	GND                 

C379      	Q_CAP_C0805    	          	          	                    
          	               	1         	75B3      	PVCCIN_CPU0         
          	               	2         	75B3      	GND                 

C380      	Q_CAP_C0805    	          	          	                    
          	               	1         	76B2      	PVCCIN_CPU0         
          	               	2         	76B2      	GND                 

C381      	Q_CAP_C0805    	          	          	                    
          	               	1         	75B1      	PVCCIN_CPU0         
          	               	2         	75B1      	GND                 

C382      	Q_CAP_C0805    	          	          	                    
          	               	1         	75B3      	PVCCIN_CPU0         
          	               	2         	75B3      	GND                 

C383      	Q_CAP_C0805    	          	          	                    
          	               	1         	76B2      	PVCCIN_CPU0         
          	               	2         	76B2      	GND                 

C385      	Q_CAP_C0805    	          	          	                    
          	               	1         	75B3      	PVCCIN_CPU0         
          	               	2         	75B3      	GND                 

C386      	Q_CAP_C0805    	          	          	                    
          	               	1         	76B4      	PVCCIN_CPU0         
          	               	2         	76B4      	GND                 

C387      	Q_CAP_C0805    	          	          	                    
          	               	1         	75B3      	PVCCIN_CPU0         
          	               	2         	75B3      	GND                 

C388      	Q_CAP_C0805    	          	          	                    
          	               	1         	76B4      	PVCCIN_CPU0         
          	               	2         	76B4      	GND                 

C389      	Q_CAP_C0805    	          	          	                    
          	               	1         	75B3      	PVCCIN_CPU0         
          	               	2         	75B3      	GND                 

C390      	Q_CAP_C0805    	          	          	                    
          	               	1         	76B4      	PVCCIN_CPU0         
          	               	2         	76B4      	GND                 

C391      	Q_CAP_C0805    	          	          	                    
          	               	1         	75B3      	PVCCIN_CPU0         
          	               	2         	75B3      	GND                 

C392      	Q_CAP_C0805    	          	          	                    
          	               	1         	76B4      	PVCCIN_CPU0         
          	               	2         	76B4      	GND                 

C393      	Q_CAP_C0805    	          	          	                    
          	               	1         	75B3      	PVCCIN_CPU0         
          	               	2         	75B3      	GND                 

C394      	Q_CAP_C0805    	          	          	                    
          	               	1         	76B4      	PVCCIN_CPU0         
          	               	2         	76B4      	GND                 

C395      	Q_CAP_C0805    	          	          	                    
          	               	1         	75B3      	PVNN_MAIN_CPU0      
          	               	2         	75B3      	GND                 

C396      	Q_CAP_C0805    	          	          	                    
          	               	1         	76B4      	PVCCIN_CPU0         
          	               	2         	76B4      	GND                 

C397      	Q_CAP_C0805    	          	          	                    
          	               	1         	75B4      	PVCCIN_CPU0         
          	               	2         	75B4      	GND                 

C398      	Q_CAP_C0805    	          	          	                    
          	               	1         	76B4      	PVCCIN_CPU0         
          	               	2         	76B4      	GND                 

C399      	Q_CAP_C0402    	          	          	                    
          	               	1         	74A4      	PVCCD_HV_CPU0       
          	               	2         	74A4      	GND                 

C400      	Q_CAP_C0402    	          	          	                    
          	               	1         	74A4      	PVCCFA_EHV_FIVRA_CPU0
          	               	2         	74A4      	GND                 

C401      	Q_CAP_C0402    	          	          	                    
          	               	1         	74A4      	PVCCD_HV_CPU0       
          	               	2         	74A4      	GND                 

C402      	Q_CAP_C0402    	          	          	                    
          	               	1         	74A4      	PVCCFA_EHV_FIVRA_CPU0
          	               	2         	74A4      	GND                 

C403      	Q_CAP_C0402    	          	          	                    
          	               	1         	74A4      	PVCCD_HV_CPU0       
          	               	2         	74A4      	GND                 

C404      	Q_CAP_C0402    	          	          	                    
          	               	1         	74A4      	PVCCFA_EHV_FIVRA_CPU0
          	               	2         	74A4      	GND                 

C405      	Q_CAP_C0402    	          	          	                    
          	               	1         	74A4      	PVCCD_HV_CPU0       
          	               	2         	74A4      	GND                 

C406      	Q_CAP_C0402    	          	          	                    
          	               	1         	74A4      	PVCCFA_EHV_FIVRA_CPU0
          	               	2         	74A4      	GND                 

C407      	Q_CAP_C0402    	          	          	                    
          	               	1         	74A4      	PVCCFA_EHV_FIVRA_CPU0
          	               	2         	74A4      	GND                 

C408      	Q_CAP_C0402    	          	          	                    
          	               	1         	74A4      	PVCCINFAON_CPU0     
          	               	2         	74A4      	GND                 

C409      	Q_CAP_C0402    	          	          	                    
          	               	1         	74A4      	PVCCFA_EHV_FIVRA_CPU0
          	               	2         	74A4      	GND                 

C410      	Q_CAP_C0402    	          	          	                    
          	               	1         	74A4      	PVCCINFAON_CPU0     
          	               	2         	74A4      	GND                 

C411      	Q_CAP_C0402    	          	          	                    
          	               	1         	74A4      	PVCCFA_EHV_FIVRA_CPU0
          	               	2         	74A4      	GND                 

C412      	Q_CAP_C0402    	          	          	                    
          	               	1         	74A3      	PVCCINFAON_CPU0     
          	               	2         	74A3      	GND                 

C413      	Q_CAP_C0402    	          	          	                    
          	               	1         	74A3      	PVCCFA_EHV_FIVRA_CPU0
          	               	2         	74A3      	GND                 

C414      	Q_CAP_C0402    	          	          	                    
          	               	1         	74A3      	PVCCINFAON_CPU0     
          	               	2         	74A3      	GND                 

C415      	Q_CAP_C0402    	          	          	                    
          	               	1         	74A3      	PVCCFA_EHV_FIVRA_CPU0
          	               	2         	74A3      	GND                 

C416      	Q_CAP_C0402    	          	          	                    
          	               	1         	74A3      	PVCCINFAON_CPU0     
          	               	2         	74A3      	GND                 

C417      	Q_CAP_C0402    	          	          	                    
          	               	1         	74A3      	PVCCFA_EHV_FIVRA_CPU0
          	               	2         	74A3      	GND                 

C418      	Q_CAP_C0402    	          	          	                    
          	               	1         	74A3      	PVCCFA_EHV_FIVRA_CPU0
          	               	2         	74A3      	GND                 

C419      	Q_CAP_C0402    	          	          	                    
          	               	1         	74A2      	PVCCFA_EHV_CPU0     
          	               	2         	74A2      	GND                 

C420      	Q_CAP_C0402    	          	          	                    
          	               	1         	74A2      	PVCCFA_EHV_CPU0     
          	               	2         	74A2      	GND                 

C421      	Q_CAP_C0402    	          	          	                    
          	               	1         	74A2      	PVCCFA_EHV_CPU0     
          	               	2         	74A2      	GND                 

C422      	Q_CAP_C0402    	          	          	                    
          	               	1         	74A2      	PVCCFA_EHV_CPU0     
          	               	2         	74A2      	GND                 

C423      	Q_CAP_C0402    	          	          	                    
          	               	1         	77A4      	PVCCD_HV_CPU1       
          	               	2         	77A4      	GND                 

C424      	Q_CAP_C0402    	          	          	                    
          	               	1         	77A4      	PVCCFA_EHV_FIVRA_CPU1
          	               	2         	77A4      	GND                 

C425      	Q_CAP_C0402    	          	          	                    
          	               	1         	77A4      	PVCCD_HV_CPU1       
          	               	2         	77A4      	GND                 

C426      	Q_CAP_C0402    	          	          	                    
          	               	1         	77A4      	PVCCFA_EHV_FIVRA_CPU1
          	               	2         	77A4      	GND                 

C427      	Q_CAP_C0402    	          	          	                    
          	               	1         	77A4      	PVCCD_HV_CPU1       
          	               	2         	77A4      	GND                 

C428      	Q_CAP_C0402    	          	          	                    
          	               	1         	77A4      	PVCCFA_EHV_FIVRA_CPU1
          	               	2         	77A4      	GND                 

C429      	Q_CAP_C0402    	          	          	                    
          	               	1         	77A4      	PVCCD_HV_CPU1       
          	               	2         	77A4      	GND                 

C430      	Q_CAP_C0402    	          	          	                    
          	               	1         	77A4      	PVCCFA_EHV_FIVRA_CPU1
          	               	2         	77A4      	GND                 

C431      	Q_CAP_C0402    	          	          	                    
          	               	1         	77A4      	PVCCFA_EHV_FIVRA_CPU1
          	               	2         	77A4      	GND                 

C432      	Q_CAP_C0402    	          	          	                    
          	               	1         	77A4      	PVCCINFAON_CPU1     
          	               	2         	77A4      	GND                 

C433      	Q_CAP_C0402    	          	          	                    
          	               	1         	77A4      	PVCCFA_EHV_FIVRA_CPU1
          	               	2         	77A4      	GND                 

C434      	Q_CAP_C0402    	          	          	                    
          	               	1         	77A4      	PVCCINFAON_CPU1     
          	               	2         	77A4      	GND                 

C435      	Q_CAP_C0402    	          	          	                    
          	               	1         	77A4      	PVCCFA_EHV_FIVRA_CPU1
          	               	2         	77A4      	GND                 

C436      	Q_CAP_C0402    	          	          	                    
          	               	1         	77A3      	PVCCINFAON_CPU1     
          	               	2         	77A3      	GND                 

C437      	Q_CAP_C0402    	          	          	                    
          	               	1         	77A3      	PVCCFA_EHV_FIVRA_CPU1
          	               	2         	77A3      	GND                 

C438      	Q_CAP_C0402    	          	          	                    
          	               	1         	77A3      	PVCCINFAON_CPU1     
          	               	2         	77A3      	GND                 

C439      	Q_CAP_C0402    	          	          	                    
          	               	1         	77A3      	PVCCFA_EHV_FIVRA_CPU1
          	               	2         	77A3      	GND                 

C440      	Q_CAP_C0402    	          	          	                    
          	               	1         	77A3      	PVCCINFAON_CPU1     
          	               	2         	77A3      	GND                 

C441      	Q_CAP_C0402    	          	          	                    
          	               	1         	77A3      	PVCCFA_EHV_FIVRA_CPU1
          	               	2         	77A3      	GND                 

C442      	Q_CAP_C0402    	          	          	                    
          	               	1         	77A3      	PVCCFA_EHV_FIVRA_CPU1
          	               	2         	77A3      	GND                 

C443      	Q_CAP_C0402    	          	          	                    
          	               	1         	77A2      	PVCCFA_EHV_CPU1     
          	               	2         	77A2      	GND                 

C444      	Q_CAP_C0402    	          	          	                    
          	               	1         	77A2      	PVCCFA_EHV_CPU1     
          	               	2         	77A2      	GND                 

C445      	Q_CAP_C0402    	          	          	                    
          	               	1         	77A2      	PVCCFA_EHV_CPU1     
          	               	2         	77A2      	GND                 

C446      	Q_CAP_C0402    	          	          	                    
          	               	1         	77A2      	PVCCFA_EHV_CPU1     
          	               	2         	77A2      	GND                 

C447      	Q_CAP_C0805    	          	          	                    
          	               	1         	78B4      	PVCCD_HV_CPU1       
          	               	2         	78B4      	GND                 

C448      	Q_CAP_C0805    	          	          	                    
          	               	1         	78B4      	PVCCFA_EHV_CPU1     
          	               	2         	78B4      	GND                 

C449      	Q_CAP_C0805    	          	          	                    
          	               	1         	78A4      	PVCCFA_EHV_FIVRA_CPU1
          	               	2         	78A4      	GND                 

C450      	Q_CAP_C0805    	          	          	                    
          	               	1         	79A4      	PVCCFA_EHV_FIVRA_CPU1
          	               	2         	79A4      	GND                 

C451      	Q_CAP_C0805    	          	          	                    
          	               	1         	78B4      	PVCCD_HV_CPU1       
          	               	2         	78B4      	GND                 

C452      	Q_CAP_C0805    	          	          	                    
          	               	1         	78B4      	PVCCFA_EHV_CPU1     
          	               	2         	78B4      	GND                 

C453      	Q_CAP_C0805    	          	          	                    
          	               	1         	78A4      	PVCCFA_EHV_FIVRA_CPU1
          	               	2         	78A4      	GND                 

C454      	Q_CAP_C0805    	          	          	                    
          	               	1         	79A4      	PVCCFA_EHV_FIVRA_CPU1
          	               	2         	79A4      	GND                 

C455      	Q_CAP_C0805    	          	          	                    
          	               	1         	79B4      	PVCCD_HV_CPU1       
          	               	2         	79B4      	GND                 

C456      	Q_CAP_C0805    	          	          	                    
          	               	1         	79B4      	PVCCFA_EHV_CPU1     
          	               	2         	79B4      	GND                 

C457      	Q_CAP_C0805    	          	          	                    
          	               	1         	78A4      	PVCCFA_EHV_FIVRA_CPU1
          	               	2         	78A4      	GND                 

C458      	Q_CAP_C0805    	          	          	                    
          	               	1         	79A4      	PVCCFA_EHV_FIVRA_CPU1
          	               	2         	79A4      	GND                 

C459      	Q_CAP_C0805    	          	          	                    
          	               	1         	79B4      	PVCCD_HV_CPU1       
          	               	2         	79B4      	GND                 

C460      	Q_CAP_C0805    	          	          	                    
          	               	1         	79B4      	PVCCFA_EHV_CPU1     
          	               	2         	79B4      	GND                 

C461      	Q_CAP_C0805    	          	          	                    
          	               	1         	78A4      	PVCCFA_EHV_FIVRA_CPU1
          	               	2         	78A4      	GND                 

C462      	Q_CAP_C0805    	          	          	                    
          	               	1         	79A4      	PVCCFA_EHV_FIVRA_CPU1
          	               	2         	79A4      	GND                 

C463      	Q_CAP_C0805    	          	          	                    
          	               	1         	79B4      	PVCCD_HV_CPU1       
          	               	2         	79B4      	GND                 

C464      	Q_CAP_C0805    	          	          	                    
          	               	1         	79B4      	PVCCFA_EHV_CPU1     
          	               	2         	79B4      	GND                 

C465      	Q_CAP_C0603    	          	          	                    
          	               	1         	78A4      	PVCCFA_EHV_FIVRA_CPU1
          	               	2         	78A4      	GND                 

C466      	Q_CAP_C0805    	          	          	                    
          	               	1         	79A4      	PVCCFA_EHV_FIVRA_CPU1
          	               	2         	79A4      	GND                 

C467      	Q_CAP_C0805    	          	          	                    
          	               	1         	79B4      	PVCCD_HV_CPU1       
          	               	2         	79B4      	GND                 

C468      	Q_CAP_C0805    	          	          	                    
          	               	1         	79B4      	PVCCFA_EHV_CPU1     
          	               	2         	79B4      	GND                 

C470      	Q_CAP_C0805    	          	          	                    
          	               	1         	79A4      	PVCCFA_EHV_FIVRA_CPU1
          	               	2         	79A4      	GND                 

C471      	Q_CAP_C0805    	          	          	                    
          	               	1         	78B4      	PVCCD_HV_CPU1       
          	               	2         	78B4      	GND                 

C472      	Q_CAP_C0603    	          	          	                    
          	               	1         	79B4      	PVCCFA_EHV_CPU1     
          	               	2         	79B4      	GND                 

C473      	Q_CAP_C0805    	          	          	                    
          	               	1         	79A4      	PVCCFA_EHV_FIVRA_CPU1
          	               	2         	79A4      	GND                 

C474      	Q_CAP_C0805    	          	          	                    
          	               	1         	78B4      	PVCCD_HV_CPU1       
          	               	2         	78B4      	GND                 

C475      	Q_CAP_C0603    	          	          	                    
          	               	1         	79B4      	PVCCFA_EHV_CPU1     
          	               	2         	79B4      	GND                 

C476      	Q_CAP_C0805    	          	          	                    
          	               	1         	79A3      	PVCCFA_EHV_FIVRA_CPU1
          	               	2         	79A3      	GND                 

C477      	Q_CAP_C0805    	          	          	                    
          	               	1         	79A3      	PVCCFA_EHV_FIVRA_CPU1
          	               	2         	79A3      	GND                 

C478      	Q_CAP_C0805    	          	          	                    
          	               	1         	78A4      	PVCCINFAON_CPU1     
          	               	2         	78A4      	GND                 

C479      	Q_CAP_C0805    	          	          	                    
          	               	1         	79A3      	PVCCFA_EHV_FIVRA_CPU1
          	               	2         	79A3      	GND                 

C481      	Q_CAP_C0805    	          	          	                    
          	               	1         	79A4      	PVCCINFAON_CPU1     
          	               	2         	79A4      	GND                 

C482      	Q_CAP_C0805    	          	          	                    
          	               	1         	79A3      	PVCCFA_EHV_FIVRA_CPU1
          	               	2         	79A3      	GND                 

C483      	Q_CAP_C0805    	          	          	                    
          	               	1         	78B2      	PVCCIN_CPU1         
          	               	2         	78B2      	GND                 

C484      	Q_CAP_C0805    	          	          	                    
          	               	1         	79A4      	PVCCINFAON_CPU1     
          	               	2         	79A4      	GND                 

C485      	Q_CAP_C0805    	          	          	                    
          	               	1         	79A3      	PVCCFA_EHV_FIVRA_CPU1
          	               	2         	79A3      	GND                 

C486      	Q_CAP_C0805    	          	          	                    
          	               	1         	79A4      	PVCCINFAON_CPU1     
          	               	2         	79A4      	GND                 

C487      	Q_CAP_C0805    	          	          	                    
          	               	1         	79A4      	PVCCINFAON_CPU1     
          	               	2         	79A4      	GND                 

C488      	Q_CAP_C0603    	          	          	                    
          	               	1         	78A4      	PVCCINFAON_CPU1     
          	               	2         	78A4      	GND                 

C489      	Q_CAP_C0603    	          	          	                    
          	               	1         	78A4      	PVCCINFAON_CPU1     
          	               	2         	78A4      	GND                 

C490      	Q_CAP_C0402    	          	          	                    
          	               	1         	78A4      	PVCCINFAON_CPU1     
          	               	2         	78A4      	GND                 

C491      	Q_CAP_C0805    	          	          	                    
          	               	1         	75B4      	PVCCD_HV_CPU0       
          	               	2         	75B4      	GND                 

C492      	Q_CAP_C0805    	          	          	                    
          	               	1         	75B4      	PVCCFA_EHV_CPU0     
          	               	2         	75B4      	GND                 

C493      	Q_CAP_C0805    	          	          	                    
          	               	1         	75A4      	PVCCFA_EHV_FIVRA_CPU0
          	               	2         	75A4      	GND                 

C494      	Q_CAP_C0805    	          	          	                    
          	               	1         	76A4      	PVCCFA_EHV_FIVRA_CPU0
          	               	2         	76A4      	GND                 

C495      	Q_CAP_C0805    	          	          	                    
          	               	1         	75B4      	PVCCD_HV_CPU0       
          	               	2         	75B4      	GND                 

C496      	Q_CAP_C0805    	          	          	                    
          	               	1         	75B4      	PVCCFA_EHV_CPU0     
          	               	2         	75B4      	GND                 

C497      	Q_CAP_C0805    	          	          	                    
          	               	1         	75A4      	PVCCFA_EHV_FIVRA_CPU0
          	               	2         	75A4      	GND                 

C498      	Q_CAP_C0805    	          	          	                    
          	               	1         	76A4      	PVCCFA_EHV_FIVRA_CPU0
          	               	2         	76A4      	GND                 

C499      	Q_CAP_C0805    	          	          	                    
          	               	1         	76B4      	PVCCD_HV_CPU0       
          	               	2         	76B4      	GND                 

C500      	Q_CAP_C0805    	          	          	                    
          	               	1         	76B4      	PVCCFA_EHV_CPU0     
          	               	2         	76B4      	GND                 

C501      	Q_CAP_C0805    	          	          	                    
          	               	1         	75A4      	PVCCFA_EHV_FIVRA_CPU0
          	               	2         	75A4      	GND                 

C502      	Q_CAP_C0805    	          	          	                    
          	               	1         	76A4      	PVCCFA_EHV_FIVRA_CPU0
          	               	2         	76A4      	GND                 

C503      	Q_CAP_C0805    	          	          	                    
          	               	1         	76B4      	PVCCD_HV_CPU0       
          	               	2         	76B4      	GND                 

C504      	Q_CAP_C0805    	          	          	                    
          	               	1         	76B4      	PVCCFA_EHV_CPU0     
          	               	2         	76B4      	GND                 

C505      	Q_CAP_C0805    	          	          	                    
          	               	1         	75A4      	PVCCFA_EHV_FIVRA_CPU0
          	               	2         	75A4      	GND                 

C506      	Q_CAP_C0805    	          	          	                    
          	               	1         	76A4      	PVCCFA_EHV_FIVRA_CPU0
          	               	2         	76A4      	GND                 

C507      	Q_CAP_C0805    	          	          	                    
          	               	1         	76B4      	PVCCD_HV_CPU0       
          	               	2         	76B4      	GND                 

C508      	Q_CAP_C0805    	          	          	                    
          	               	1         	76B4      	PVCCFA_EHV_CPU0     
          	               	2         	76B4      	GND                 

C509      	Q_CAP_C0603    	          	          	                    
          	               	1         	75A4      	PVCCFA_EHV_FIVRA_CPU0
          	               	2         	75A4      	GND                 

C510      	Q_CAP_C0805    	          	          	                    
          	               	1         	76A4      	PVCCFA_EHV_FIVRA_CPU0
          	               	2         	76A4      	GND                 

C511      	Q_CAP_C0805    	          	          	                    
          	               	1         	76B4      	PVCCD_HV_CPU0       
          	               	2         	76B4      	GND                 

C512      	Q_CAP_C0805    	          	          	                    
          	               	1         	76B4      	PVCCFA_EHV_CPU0     
          	               	2         	76B4      	GND                 

C513      	Q_CAP_C0805    	          	          	                    
          	               	1         	257B2     	PGPPA_AUX           
          	               	2         	257B2     	GND                 

C514      	Q_CAP_C0805    	          	          	                    
          	               	1         	76A4      	PVCCFA_EHV_FIVRA_CPU0
          	               	2         	76A4      	GND                 

C515      	Q_CAP_C0805    	          	          	                    
          	               	1         	75B4      	PVCCD_HV_CPU0       
          	               	2         	75B4      	GND                 

C516      	Q_CAP_C0603    	          	          	                    
          	               	1         	76B4      	PVCCFA_EHV_CPU0     
          	               	2         	76B4      	GND                 

C517      	Q_CAP_C0805    	          	          	                    
          	               	1         	76A4      	PVCCFA_EHV_FIVRA_CPU0
          	               	2         	76A4      	GND                 

C518      	Q_CAP_C0805    	          	          	                    
          	               	1         	75B4      	PVCCD_HV_CPU0       
          	               	2         	75B4      	GND                 

C519      	Q_CAP_C0603    	          	          	                    
          	               	1         	76B4      	PVCCFA_EHV_CPU0     
          	               	2         	76B4      	GND                 

C520      	Q_CAP_C0805    	          	          	                    
          	               	1         	76A3      	PVCCFA_EHV_FIVRA_CPU0
          	               	2         	76A3      	GND                 

C521      	Q_CAP_C0805    	          	          	                    
          	               	1         	76A3      	PVCCFA_EHV_FIVRA_CPU0
          	               	2         	76A3      	GND                 

C522      	Q_CAP_C0805    	          	          	                    
          	               	1         	75A4      	PVCCINFAON_CPU0     
          	               	2         	75A4      	GND                 

C523      	Q_CAP_C0805    	          	          	                    
          	               	1         	76A3      	PVCCFA_EHV_FIVRA_CPU0
          	               	2         	76A3      	GND                 

C525      	Q_CAP_C0805    	          	          	                    
          	               	1         	76A4      	PVCCINFAON_CPU0     
          	               	2         	76A4      	GND                 

C526      	Q_CAP_C0805    	          	          	                    
          	               	1         	76A3      	PVCCFA_EHV_FIVRA_CPU0
          	               	2         	76A3      	GND                 

C527      	Q_CAP_C0805    	          	          	                    
          	               	1         	75B1      	PVCCIN_CPU0         
          	               	2         	75B1      	GND                 

C528      	Q_CAP_C0805    	          	          	                    
          	               	1         	76A4      	PVCCINFAON_CPU0     
          	               	2         	76A4      	GND                 

C529      	Q_CAP_C0805    	          	          	                    
          	               	1         	76A3      	PVCCFA_EHV_FIVRA_CPU0
          	               	2         	76A3      	GND                 

C530      	Q_CAP_C0805    	          	          	                    
          	               	1         	76A4      	PVCCINFAON_CPU0     
          	               	2         	76A4      	GND                 

C531      	Q_CAP_C0805    	          	          	                    
          	               	1         	76A4      	PVCCINFAON_CPU0     
          	               	2         	76A4      	GND                 

C532      	Q_CAP_C0603    	          	          	                    
          	               	1         	75A4      	PVCCINFAON_CPU0     
          	               	2         	75A4      	GND                 

C533      	Q_CAP_C0603    	          	          	                    
          	               	1         	75A4      	PVCCINFAON_CPU0     
          	               	2         	75A4      	GND                 

C534      	Q_CAP_C0402    	          	          	                    
          	               	1         	75A4      	PVCCINFAON_CPU0     
          	               	2         	75A4      	GND                 

C535      	Q_CAP_C0805    	          	          	                    
          	               	1         	257B2     	PGPPA_AUX           
          	               	2         	257B2     	GND                 

C537      	Q_CAP_0402     	          	          	                    
          	               	1         	230B3     	P3V3_AUX            
          	               	2         	230B3     	GND                 

C538      	Q_CAP_0402     	          	          	                    
          	               	1         	229B3     	P3V3_AUX            
          	               	2         	229B3     	GND                 

C539      	Q_CAP_0402     	          	          	                    
          	               	1         	133B4     	P3V3_AUX            
          	               	2         	133B4     	GND                 

C540      	Q_CAP_0402     	          	          	                    
          	               	1         	133B4     	P3V3_AUX            
          	               	2         	133B4     	GND                 

C541      	Q_CAP_C0402    	          	          	                    
          	               	1         	133B4     	P3V3_AUX            
          	               	2         	133B4     	GND                 

C542      	Q_CAP_C0402    	          	          	                    
          	               	1         	133B4     	P3V3_AUX            
          	               	2         	133B4     	GND                 

C543      	Q_CAP_0402     	          	          	                    
          	               	1         	133A3     	P3V3_AUX            
          	               	2         	133A3     	GND                 

C544      	Q_CAP_0402     	          	          	                    
          	               	1         	133A2     	P3V3_AUX            
          	               	2         	133A2     	GND                 

C545      	Q_CAP_C0402    	          	          	                    
          	               	1         	132B3     	P3V3_AUX            
          	               	2         	132B3     	GND                 

C546      	Q_CAP_C0402    	          	          	                    
          	               	1         	132B3     	P3V3_AUX            
          	               	2         	132B3     	GND                 

C547      	Q_CAP_C0402    	          	          	                    
          	               	1         	131B3     	P1V05_PCH_AUX       
          	               	2         	131B3     	GND                 

C548      	Q_CAP_0402     	          	          	                    
          	               	1         	131A3     	JTAG_DBP_POWER_BTN_N
          	               	2         	131A3     	GND                 

C549      	Q_CAP_0402     	          	          	                    
          	               	1         	131A3     	JTAG_RST_DBP_RST_CO_N
          	               	2         	131A3     	GND                 

C550      	Q_CAP_C0402    	          	          	                    
          	               	1         	131B3     	P1V8_PCH_AUX        
          	               	2         	131B3     	GND                 

C551      	Q_CAP_C0402    	          	          	                    
          	               	1         	131B2     	P3V3_AUX            
          	               	2         	131B2     	GND                 

C552      	Q_CAP_0402     	          	          	                    
          	               	1         	131B2     	FM_CPU_FBRK_DEBUG_N 
          	               	2         	131B2     	GND                 

C554      	Q_CAP_0402     	          	          	                    
          	               	1         	221B3     	P3V3_AUX_BMC_D      
          	               	2         	221B3     	GND                 

C559      	Q_CAP_0402     	          	          	                    
          	               	1         	235B3     	PVNN_TERM_CPU0      
          	               	2         	235B3     	GND                 

C560      	Q_CAP_0402     	          	          	                    
          	               	1         	235B3     	PVNN_TERM_CPU1      
          	               	2         	235B3     	GND                 

C561      	Q_CAP_0402     	          	          	                    
          	               	1         	235B3     	P3V3_AUX            
          	               	2         	235B3     	GND                 

C562      	Q_CAP_0402     	          	          	                    
          	               	1         	235B3     	P3V3_AUX            
          	               	2         	235B3     	GND                 

C563      	Q_CAP_C0805    	          	          	                    
          	               	1         	221B3     	P3V3_AUX_BMC_D      
          	               	2         	221B3     	GND                 

C567      	Q_CAP_0402     	          	          	                    
          	               	1         	236B4     	PVNN_TERM_CPU0      
          	               	2         	236B4     	GND                 

C568      	Q_CAP_0402     	          	          	                    
          	               	1         	236A4     	PVNN_TERM_CPU1      
          	               	2         	236A4     	GND                 

C569      	Q_CAP_0402     	          	          	                    
          	               	1         	236B3     	P3V3_AUX            
          	               	2         	236B3     	GND                 

C570      	Q_CAP_0402     	          	          	                    
          	               	1         	236A3     	P3V3_AUX            
          	               	2         	236A3     	GND                 

C578      	Q_CAP_0402     	          	          	                    
          	               	1         	158A4     	P3V3_AUX            
          	               	2         	158A4     	GND                 

C579      	Q_CAP_0402     	          	          	                    
          	               	1         	158B4     	P3V3_AUX            
          	               	2         	158B4     	GND                 

C580      	Q_CAP_0402     	          	          	                    
          	               	1         	158B4     	P3V3_OCP_SFF        
          	               	2         	158B4     	GND                 

C581      	Q_CAP_0402     	          	          	                    
          	               	1         	158B1     	P3V3_AUX            
          	               	2         	158B1     	GND                 

C590      	Q_CAP_C0402    	          	          	                    
          	               	1         	74B2      	PVNN_MAIN_CPU0      
          	               	2         	74B2      	GND                 

C592      	Q_CAP_0402     	          	          	                    
          	               	1         	156A3     	P3V3_AUX            
          	               	2         	156A3     	GND                 

C593      	Q_CAP_0402     	          	          	                    
          	               	1         	156A3     	P3V3_AUX            
          	               	2         	156A3     	GND                 

C605      	Q_CAP_C0402    	          	          	                    
          	               	1         	202B3     	PGPPA_AUX           
          	               	2         	202B3     	GND                 

C606      	Q_CAP_C0402    	          	          	                    
          	               	1         	202B3     	PGPPA_AUX           
          	               	2         	202B3     	GND                 

C607      	Q_CAP_0402     	          	          	                    
          	               	1         	202B3     	PGPPA_AUX           
          	               	2         	202B3     	GND                 

C608      	Q_CAP_0402     	          	          	                    
          	               	1         	202B3     	PGPPA_AUX           
          	               	2         	202B3     	GND                 

C609      	Q_CAP_0402     	          	          	                    
          	               	1         	179B4     	RTC_EXT_CAP         
          	               	2         	179B4     	GND                 

C610      	Q_CAP_C0402    	          	          	                    
          	               	1         	185B4     	RST_SRTCRST_N       
          	               	2         	185B4     	GND                 

C611      	Q_CAP_C0402    	          	          	                    
          	               	1         	185B2     	P3V3_RTC_AUX        
          	               	2         	185A2     	GND                 

C613      	Q_CAP_C0402    	          	          	                    
          	               	1         	130A4     	RST_PLD_CPU1_DRAM_GH_N
          	               	2         	130A4     	GND                 

C614      	Q_CAP_C0402    	          	          	                    
          	               	1         	130B4     	RST_PLD_CPU1_DRAM_AB_N
          	               	2         	130B4     	GND                 

C615      	Q_CAP_C0402    	          	          	                    
          	               	1         	130B4     	RST_PLD_CPU1_DRAM_CD_N
          	               	2         	130B4     	GND                 

C616      	Q_CAP_C0402    	          	          	                    
          	               	1         	130A4     	RST_PLD_CPU1_DRAM_EF_N
          	               	2         	130A4     	GND                 

C621      	Q_CAP_C0402    	          	          	                    
          	               	1         	129A4     	RST_PLD_CPU0_DRAM_GH_N
          	               	2         	129A4     	GND                 

C622      	Q_CAP_C0402    	          	          	                    
          	               	1         	129B4     	RST_PLD_CPU0_DRAM_AB_N
          	               	2         	129B4     	GND                 

C623      	Q_CAP_C0402    	          	          	                    
          	               	1         	129B4     	RST_PLD_CPU0_DRAM_CD_N
          	               	2         	129B4     	GND                 

C624      	Q_CAP_C0402    	          	          	                    
          	               	1         	129A4     	RST_PLD_CPU0_DRAM_EF_N
          	               	2         	129A4     	GND                 

C626      	Q_CAP_0402     	          	          	                    
          	               	1         	278B4     	PWRGD_PVCCD_HV_CPU0_R
          	               	2         	278B3     	GND                 

C629      	Q_CAP_0402     	          	          	                    
          	               	1         	243B3     	P3V3_AUX            
          	               	2         	243B3     	GND                 

C639      	Q_CAP_0402     	          	          	                    
          	               	1         	154B4     	P3V3_AUX            
          	               	2         	154B4     	GND                 

C640      	Q_CAP_0402     	          	          	                    
          	               	1         	154B3     	P3V3_AUX            
          	               	2         	154B3     	GND                 

C641      	Q_CAP_0402     	          	          	                    
          	               	1         	154B3     	P3V3_AUX            
          	               	2         	154B3     	GND                 

C678      	Q_CAP_DIFFBUS_C0201	          	          	                    
          	               	1         	177B2     	P5E_CPU1_PE4_TX_C_DN<15>
          	               	2         	177B2     	P5E_CPU1_PE4_TX_DN<15>

C679      	Q_CAP_DIFFBUS_C0201	          	          	                    
          	               	1         	177B2     	P5E_CPU1_PE4_TX_C_DP<15>
          	               	2         	177B2     	P5E_CPU1_PE4_TX_DP<15>

C680      	Q_CAP_DIFFBUS_C0201	          	          	                    
          	               	1         	177B2     	P5E_CPU1_PE4_TX_C_DN<14>
          	               	2         	177B2     	P5E_CPU1_PE4_TX_DN<14>

C681      	Q_CAP_DIFFBUS_C0201	          	          	                    
          	               	1         	177B2     	P5E_CPU1_PE4_TX_C_DP<14>
          	               	2         	177B2     	P5E_CPU1_PE4_TX_DP<14>

C682      	Q_CAP_DIFFBUS_C0201	          	          	                    
          	               	1         	177B2     	P5E_CPU1_PE4_TX_C_DN<13>
          	               	2         	177B2     	P5E_CPU1_PE4_TX_DN<13>

C683      	Q_CAP_DIFFBUS_C0201	          	          	                    
          	               	1         	177B2     	P5E_CPU1_PE4_TX_C_DP<13>
          	               	2         	177B2     	P5E_CPU1_PE4_TX_DP<13>

C684      	Q_CAP_DIFFBUS_C0201	          	          	                    
          	               	1         	177B2     	P5E_CPU1_PE4_TX_C_DN<12>
          	               	2         	177B2     	P5E_CPU1_PE4_TX_DN<12>

C685      	Q_CAP_DIFFBUS_C0201	          	          	                    
          	               	1         	177B2     	P5E_CPU1_PE4_TX_C_DP<12>
          	               	2         	177B2     	P5E_CPU1_PE4_TX_DP<12>

C686      	Q_CAP_DIFFBUS_C0201	          	          	                    
          	               	1         	177B2     	P5E_CPU1_PE4_TX_C_DN<11>
          	               	2         	177B2     	P5E_CPU1_PE4_TX_DN<11>

C687      	Q_CAP_DIFFBUS_C0201	          	          	                    
          	               	1         	177B2     	P5E_CPU1_PE4_TX_C_DP<11>
          	               	2         	177B2     	P5E_CPU1_PE4_TX_DP<11>

C688      	Q_CAP_DIFFBUS_C0201	          	          	                    
          	               	1         	177B2     	P5E_CPU1_PE4_TX_C_DN<10>
          	               	2         	177B2     	P5E_CPU1_PE4_TX_DN<10>

C689      	Q_CAP_DIFFBUS_C0201	          	          	                    
          	               	1         	177B2     	P5E_CPU1_PE4_TX_C_DP<10>
          	               	2         	177B2     	P5E_CPU1_PE4_TX_DP<10>

C690      	Q_CAP_DIFFBUS_C0201	          	          	                    
          	               	1         	177B2     	P5E_CPU1_PE4_TX_C_DN<9>
          	               	2         	177B2     	P5E_CPU1_PE4_TX_DN<9>

C691      	Q_CAP_DIFFBUS_C0201	          	          	                    
          	               	1         	177B2     	P5E_CPU1_PE4_TX_C_DP<9>
          	               	2         	177B2     	P5E_CPU1_PE4_TX_DP<9>

C692      	Q_CAP_DIFFBUS_C0201	          	          	                    
          	               	1         	177B2     	P5E_CPU1_PE4_TX_C_DN<8>
          	               	2         	177B2     	P5E_CPU1_PE4_TX_DN<8>

C693      	Q_CAP_DIFFBUS_C0201	          	          	                    
          	               	1         	177B2     	P5E_CPU1_PE4_TX_C_DP<8>
          	               	2         	177B2     	P5E_CPU1_PE4_TX_DP<8>

C694      	Q_CAP_DIFFBUS_C0201	          	          	                    
          	               	1         	177B2     	P5E_CPU1_PE4_TX_C_DN<7>
          	               	2         	177B2     	P5E_CPU1_PE4_TX_DN<7>

C695      	Q_CAP_DIFFBUS_C0201	          	          	                    
          	               	1         	177B2     	P5E_CPU1_PE4_TX_C_DP<7>
          	               	2         	177B2     	P5E_CPU1_PE4_TX_DP<7>

C696      	Q_CAP_DIFFBUS_C0201	          	          	                    
          	               	1         	177B2     	P5E_CPU1_PE4_TX_C_DN<6>
          	               	2         	177B2     	P5E_CPU1_PE4_TX_DN<6>

C697      	Q_CAP_DIFFBUS_C0201	          	          	                    
          	               	1         	177B2     	P5E_CPU1_PE4_TX_C_DP<6>
          	               	2         	177B2     	P5E_CPU1_PE4_TX_DP<6>

C698      	Q_CAP_DIFFBUS_C0201	          	          	                    
          	               	1         	177B2     	P5E_CPU1_PE4_TX_C_DN<5>
          	               	2         	177B2     	P5E_CPU1_PE4_TX_DN<5>

C699      	Q_CAP_DIFFBUS_C0201	          	          	                    
          	               	1         	177B2     	P5E_CPU1_PE4_TX_C_DP<5>
          	               	2         	177B2     	P5E_CPU1_PE4_TX_DP<5>

C700      	Q_CAP_DIFFBUS_C0201	          	          	                    
          	               	1         	177B2     	P5E_CPU1_PE4_TX_C_DN<4>
          	               	2         	177B2     	P5E_CPU1_PE4_TX_DN<4>

C701      	Q_CAP_DIFFBUS_C0201	          	          	                    
          	               	1         	177B2     	P5E_CPU1_PE4_TX_C_DP<4>
          	               	2         	177B2     	P5E_CPU1_PE4_TX_DP<4>

C702      	Q_CAP_DIFFBUS_C0201	          	          	                    
          	               	1         	177B2     	P5E_CPU1_PE4_TX_C_DN<3>
          	               	2         	177B2     	P5E_CPU1_PE4_TX_DN<3>

C703      	Q_CAP_DIFFBUS_C0201	          	          	                    
          	               	1         	177A2     	P5E_CPU1_PE4_TX_C_DP<3>
          	               	2         	177A2     	P5E_CPU1_PE4_TX_DP<3>

C704      	Q_CAP_DIFFBUS_C0201	          	          	                    
          	               	1         	177A2     	P5E_CPU1_PE4_TX_C_DN<2>
          	               	2         	177A2     	P5E_CPU1_PE4_TX_DN<2>

C705      	Q_CAP_DIFFBUS_C0201	          	          	                    
          	               	1         	177A2     	P5E_CPU1_PE4_TX_C_DP<2>
          	               	2         	177A2     	P5E_CPU1_PE4_TX_DP<2>

C706      	Q_CAP_DIFFBUS_C0201	          	          	                    
          	               	1         	177A2     	P5E_CPU1_PE4_TX_C_DN<1>
          	               	2         	177A2     	P5E_CPU1_PE4_TX_DN<1>

C707      	Q_CAP_DIFFBUS_C0201	          	          	                    
          	               	1         	177A2     	P5E_CPU1_PE4_TX_C_DP<1>
          	               	2         	177A2     	P5E_CPU1_PE4_TX_DP<1>

C708      	Q_CAP_DIFFBUS_C0201	          	          	                    
          	               	1         	177A2     	P5E_CPU1_PE4_TX_C_DN<0>
          	               	2         	177A2     	P5E_CPU1_PE4_TX_DN<0>

C709      	Q_CAP_DIFFBUS_C0201	          	          	                    
          	               	1         	177A2     	P5E_CPU1_PE4_TX_C_DP<0>
          	               	2         	177A2     	P5E_CPU1_PE4_TX_DP<0>

C710      	Q_CAP_DIFFBUS_C0201	          	          	                    
          	               	1         	176B4     	P5E_CPU1_PE0_TX_C_DN<15>
          	               	2         	176B4     	P5E_CPU1_PE0_TX_DN<15>

C711      	Q_CAP_DIFFBUS_C0201	          	          	                    
          	               	1         	176B4     	P5E_CPU1_PE0_TX_C_DP<15>
          	               	2         	176B4     	P5E_CPU1_PE0_TX_DP<15>

C712      	Q_CAP_DIFFBUS_C0201	          	          	                    
          	               	1         	176B4     	P5E_CPU1_PE0_TX_C_DN<14>
          	               	2         	176B4     	P5E_CPU1_PE0_TX_DN<14>

C713      	Q_CAP_DIFFBUS_C0201	          	          	                    
          	               	1         	176B4     	P5E_CPU1_PE0_TX_C_DP<14>
          	               	2         	176B4     	P5E_CPU1_PE0_TX_DP<14>

C714      	Q_CAP_DIFFBUS_C0201	          	          	                    
          	               	1         	176B4     	P5E_CPU1_PE0_TX_C_DN<13>
          	               	2         	176B4     	P5E_CPU1_PE0_TX_DN<13>

C715      	Q_CAP_DIFFBUS_C0201	          	          	                    
          	               	1         	176B4     	P5E_CPU1_PE0_TX_C_DP<13>
          	               	2         	176B4     	P5E_CPU1_PE0_TX_DP<13>

C716      	Q_CAP_DIFFBUS_C0201	          	          	                    
          	               	1         	176B4     	P5E_CPU1_PE0_TX_C_DN<12>
          	               	2         	176B4     	P5E_CPU1_PE0_TX_DN<12>

C717      	Q_CAP_DIFFBUS_C0201	          	          	                    
          	               	1         	176B4     	P5E_CPU1_PE0_TX_C_DP<12>
          	               	2         	176B4     	P5E_CPU1_PE0_TX_DP<12>

C718      	Q_CAP_DIFFBUS_C0201	          	          	                    
          	               	1         	176B4     	P5E_CPU1_PE0_TX_C_DN<11>
          	               	2         	176B4     	P5E_CPU1_PE0_TX_DN<11>

C719      	Q_CAP_DIFFBUS_C0201	          	          	                    
          	               	1         	176B4     	P5E_CPU1_PE0_TX_C_DP<11>
          	               	2         	176B4     	P5E_CPU1_PE0_TX_DP<11>

C720      	Q_CAP_DIFFBUS_C0201	          	          	                    
          	               	1         	176B4     	P5E_CPU1_PE0_TX_C_DN<10>
          	               	2         	176B4     	P5E_CPU1_PE0_TX_DN<10>

C721      	Q_CAP_DIFFBUS_C0201	          	          	                    
          	               	1         	176B4     	P5E_CPU1_PE0_TX_C_DP<10>
          	               	2         	176B4     	P5E_CPU1_PE0_TX_DP<10>

C722      	Q_CAP_DIFFBUS_C0201	          	          	                    
          	               	1         	176B4     	P5E_CPU1_PE0_TX_C_DN<9>
          	               	2         	176B4     	P5E_CPU1_PE0_TX_DN<9>

C723      	Q_CAP_DIFFBUS_C0201	          	          	                    
          	               	1         	176B4     	P5E_CPU1_PE0_TX_C_DP<9>
          	               	2         	176B4     	P5E_CPU1_PE0_TX_DP<9>

C724      	Q_CAP_DIFFBUS_C0201	          	          	                    
          	               	1         	176B4     	P5E_CPU1_PE0_TX_C_DN<8>
          	               	2         	176B4     	P5E_CPU1_PE0_TX_DN<8>

C725      	Q_CAP_DIFFBUS_C0201	          	          	                    
          	               	1         	176B4     	P5E_CPU1_PE0_TX_C_DP<8>
          	               	2         	176B4     	P5E_CPU1_PE0_TX_DP<8>

C726      	Q_CAP_DIFFBUS_C0201	          	          	                    
          	               	1         	176B4     	P5E_CPU1_PE0_TX_C_DN<7>
          	               	2         	176B4     	P5E_CPU1_PE0_TX_DN<7>

C727      	Q_CAP_DIFFBUS_C0201	          	          	                    
          	               	1         	176B4     	P5E_CPU1_PE0_TX_C_DP<7>
          	               	2         	176B4     	P5E_CPU1_PE0_TX_DP<7>

C728      	Q_CAP_DIFFBUS_C0201	          	          	                    
          	               	1         	176B4     	P5E_CPU1_PE0_TX_C_DN<6>
          	               	2         	176B4     	P5E_CPU1_PE0_TX_DN<6>

C729      	Q_CAP_DIFFBUS_C0201	          	          	                    
          	               	1         	176B4     	P5E_CPU1_PE0_TX_C_DP<6>
          	               	2         	176B4     	P5E_CPU1_PE0_TX_DP<6>

C730      	Q_CAP_DIFFBUS_C0201	          	          	                    
          	               	1         	176B4     	P5E_CPU1_PE0_TX_C_DN<5>
          	               	2         	176B4     	P5E_CPU1_PE0_TX_DN<5>

C731      	Q_CAP_DIFFBUS_C0201	          	          	                    
          	               	1         	176B4     	P5E_CPU1_PE0_TX_C_DP<5>
          	               	2         	176B4     	P5E_CPU1_PE0_TX_DP<5>

C732      	Q_CAP_DIFFBUS_C0201	          	          	                    
          	               	1         	176B4     	P5E_CPU1_PE0_TX_C_DN<4>
          	               	2         	176B4     	P5E_CPU1_PE0_TX_DN<4>

C733      	Q_CAP_DIFFBUS_C0201	          	          	                    
          	               	1         	176B4     	P5E_CPU1_PE0_TX_C_DP<4>
          	               	2         	176B4     	P5E_CPU1_PE0_TX_DP<4>

C734      	Q_CAP_DIFFBUS_C0201	          	          	                    
          	               	1         	176A4     	P5E_CPU1_PE0_TX_C_DN<3>
          	               	2         	176A4     	P5E_CPU1_PE0_TX_DN<3>

C735      	Q_CAP_DIFFBUS_C0201	          	          	                    
          	               	1         	176A4     	P5E_CPU1_PE0_TX_C_DP<3>
          	               	2         	176A4     	P5E_CPU1_PE0_TX_DP<3>

C736      	Q_CAP_DIFFBUS_C0201	          	          	                    
          	               	1         	176A4     	P5E_CPU1_PE0_TX_C_DN<2>
          	               	2         	176A4     	P5E_CPU1_PE0_TX_DN<2>

C737      	Q_CAP_DIFFBUS_C0201	          	          	                    
          	               	1         	176A4     	P5E_CPU1_PE0_TX_C_DP<2>
          	               	2         	176A4     	P5E_CPU1_PE0_TX_DP<2>

C738      	Q_CAP_DIFFBUS_C0201	          	          	                    
          	               	1         	176A4     	P5E_CPU1_PE0_TX_C_DN<1>
          	               	2         	176A4     	P5E_CPU1_PE0_TX_DN<1>

C739      	Q_CAP_DIFFBUS_C0201	          	          	                    
          	               	1         	176A4     	P5E_CPU1_PE0_TX_C_DP<1>
          	               	2         	176A4     	P5E_CPU1_PE0_TX_DP<1>

C740      	Q_CAP_DIFFBUS_C0201	          	          	                    
          	               	1         	176A4     	P5E_CPU1_PE0_TX_C_DN<0>
          	               	2         	176A4     	P5E_CPU1_PE0_TX_DN<0>

C741      	Q_CAP_DIFFBUS_C0201	          	          	                    
          	               	1         	176A4     	P5E_CPU1_PE0_TX_C_DP<0>
          	               	2         	176A4     	P5E_CPU1_PE0_TX_DP<0>

C742      	Q_CAP_DIFFBUS_C0201	          	          	                    
          	               	1         	176B2     	P5E_CPU1_PE2_TX_C_DN<15>
          	               	2         	176B2     	P5E_CPU1_PE2_TX_DN<15>

C743      	Q_CAP_DIFFBUS_C0201	          	          	                    
          	               	1         	176B2     	P5E_CPU1_PE2_TX_C_DP<15>
          	               	2         	176B2     	P5E_CPU1_PE2_TX_DP<15>

C744      	Q_CAP_DIFFBUS_C0201	          	          	                    
          	               	1         	176B2     	P5E_CPU1_PE2_TX_C_DN<14>
          	               	2         	176B2     	P5E_CPU1_PE2_TX_DN<14>

C745      	Q_CAP_DIFFBUS_C0201	          	          	                    
          	               	1         	176B2     	P5E_CPU1_PE2_TX_C_DP<14>
          	               	2         	176B2     	P5E_CPU1_PE2_TX_DP<14>

C746      	Q_CAP_DIFFBUS_C0201	          	          	                    
          	               	1         	176B2     	P5E_CPU1_PE2_TX_C_DN<13>
          	               	2         	176B2     	P5E_CPU1_PE2_TX_DN<13>

C747      	Q_CAP_DIFFBUS_C0201	          	          	                    
          	               	1         	176B2     	P5E_CPU1_PE2_TX_C_DP<13>
          	               	2         	176B2     	P5E_CPU1_PE2_TX_DP<13>

C748      	Q_CAP_DIFFBUS_C0201	          	          	                    
          	               	1         	176B2     	P5E_CPU1_PE2_TX_C_DN<12>
          	               	2         	176B2     	P5E_CPU1_PE2_TX_DN<12>

C749      	Q_CAP_DIFFBUS_C0201	          	          	                    
          	               	1         	176B2     	P5E_CPU1_PE2_TX_C_DP<12>
          	               	2         	176B2     	P5E_CPU1_PE2_TX_DP<12>

C750      	Q_CAP_DIFFBUS_C0201	          	          	                    
          	               	1         	176B2     	P5E_CPU1_PE2_TX_C_DN<11>
          	               	2         	176B2     	P5E_CPU1_PE2_TX_DN<11>

C751      	Q_CAP_DIFFBUS_C0201	          	          	                    
          	               	1         	176B2     	P5E_CPU1_PE2_TX_C_DP<11>
          	               	2         	176B2     	P5E_CPU1_PE2_TX_DP<11>

C752      	Q_CAP_DIFFBUS_C0201	          	          	                    
          	               	1         	176B2     	P5E_CPU1_PE2_TX_C_DN<10>
          	               	2         	176B2     	P5E_CPU1_PE2_TX_DN<10>

C753      	Q_CAP_DIFFBUS_C0201	          	          	                    
          	               	1         	176B2     	P5E_CPU1_PE2_TX_C_DP<10>
          	               	2         	176B2     	P5E_CPU1_PE2_TX_DP<10>

C754      	Q_CAP_DIFFBUS_C0201	          	          	                    
          	               	1         	176B2     	P5E_CPU1_PE2_TX_C_DN<9>
          	               	2         	176B2     	P5E_CPU1_PE2_TX_DN<9>

C755      	Q_CAP_DIFFBUS_C0201	          	          	                    
          	               	1         	176B2     	P5E_CPU1_PE2_TX_C_DP<9>
          	               	2         	176B2     	P5E_CPU1_PE2_TX_DP<9>

C756      	Q_CAP_DIFFBUS_C0201	          	          	                    
          	               	1         	176B2     	P5E_CPU1_PE2_TX_C_DN<8>
          	               	2         	176B2     	P5E_CPU1_PE2_TX_DN<8>

C757      	Q_CAP_DIFFBUS_C0201	          	          	                    
          	               	1         	176B2     	P5E_CPU1_PE2_TX_C_DP<8>
          	               	2         	176B2     	P5E_CPU1_PE2_TX_DP<8>

C758      	Q_CAP_DIFFBUS_C0201	          	          	                    
          	               	1         	176B2     	P5E_CPU1_PE2_TX_C_DN<7>
          	               	2         	176B2     	P5E_CPU1_PE2_TX_DN<7>

C759      	Q_CAP_DIFFBUS_C0201	          	          	                    
          	               	1         	176B2     	P5E_CPU1_PE2_TX_C_DP<7>
          	               	2         	176B2     	P5E_CPU1_PE2_TX_DP<7>

C760      	Q_CAP_DIFFBUS_C0201	          	          	                    
          	               	1         	176B2     	P5E_CPU1_PE2_TX_C_DN<6>
          	               	2         	176B2     	P5E_CPU1_PE2_TX_DN<6>

C761      	Q_CAP_DIFFBUS_C0201	          	          	                    
          	               	1         	176B2     	P5E_CPU1_PE2_TX_C_DP<6>
          	               	2         	176B2     	P5E_CPU1_PE2_TX_DP<6>

C762      	Q_CAP_DIFFBUS_C0201	          	          	                    
          	               	1         	176B2     	P5E_CPU1_PE2_TX_C_DN<5>
          	               	2         	176B2     	P5E_CPU1_PE2_TX_DN<5>

C763      	Q_CAP_DIFFBUS_C0201	          	          	                    
          	               	1         	176B2     	P5E_CPU1_PE2_TX_C_DP<5>
          	               	2         	176B2     	P5E_CPU1_PE2_TX_DP<5>

C764      	Q_CAP_DIFFBUS_C0201	          	          	                    
          	               	1         	176B2     	P5E_CPU1_PE2_TX_C_DN<4>
          	               	2         	176B2     	P5E_CPU1_PE2_TX_DN<4>

C765      	Q_CAP_DIFFBUS_C0201	          	          	                    
          	               	1         	176B2     	P5E_CPU1_PE2_TX_C_DP<4>
          	               	2         	176B2     	P5E_CPU1_PE2_TX_DP<4>

C766      	Q_CAP_DIFFBUS_C0201	          	          	                    
          	               	1         	176B2     	P5E_CPU1_PE2_TX_C_DN<3>
          	               	2         	176B2     	P5E_CPU1_PE2_TX_DN<3>

C767      	Q_CAP_DIFFBUS_C0201	          	          	                    
          	               	1         	176A2     	P5E_CPU1_PE2_TX_C_DP<3>
          	               	2         	176A2     	P5E_CPU1_PE2_TX_DP<3>

C768      	Q_CAP_DIFFBUS_C0201	          	          	                    
          	               	1         	176A2     	P5E_CPU1_PE2_TX_C_DN<2>
          	               	2         	176A2     	P5E_CPU1_PE2_TX_DN<2>

C769      	Q_CAP_DIFFBUS_C0201	          	          	                    
          	               	1         	176A2     	P5E_CPU1_PE2_TX_C_DP<2>
          	               	2         	176A2     	P5E_CPU1_PE2_TX_DP<2>

C770      	Q_CAP_DIFFBUS_C0201	          	          	                    
          	               	1         	176A2     	P5E_CPU1_PE2_TX_C_DN<1>
          	               	2         	176A2     	P5E_CPU1_PE2_TX_DN<1>

C771      	Q_CAP_DIFFBUS_C0201	          	          	                    
          	               	1         	176A2     	P5E_CPU1_PE2_TX_C_DP<1>
          	               	2         	176A2     	P5E_CPU1_PE2_TX_DP<1>

C772      	Q_CAP_DIFFBUS_C0201	          	          	                    
          	               	1         	176A2     	P5E_CPU1_PE2_TX_C_DN<0>
          	               	2         	176A2     	P5E_CPU1_PE2_TX_DN<0>

C773      	Q_CAP_DIFFBUS_C0201	          	          	                    
          	               	1         	176A2     	P5E_CPU1_PE2_TX_C_DP<0>
          	               	2         	176A2     	P5E_CPU1_PE2_TX_DP<0>

C806      	Q_CAP_DIFFBUS_C0201	          	          	                    
          	               	1         	175B2     	P5E_CPU1_PE1_TX_C_DN<15>
          	               	2         	175B2     	P5E_CPU1_PE1_TX_DN<15>

C807      	Q_CAP_DIFFBUS_C0201	          	          	                    
          	               	1         	175B2     	P5E_CPU1_PE1_TX_C_DP<15>
          	               	2         	175B2     	P5E_CPU1_PE1_TX_DP<15>

C808      	Q_CAP_DIFFBUS_C0201	          	          	                    
          	               	1         	175B2     	P5E_CPU1_PE1_TX_C_DN<14>
          	               	2         	175B2     	P5E_CPU1_PE1_TX_DN<14>

C809      	Q_CAP_DIFFBUS_C0201	          	          	                    
          	               	1         	175B2     	P5E_CPU1_PE1_TX_C_DP<14>
          	               	2         	175B2     	P5E_CPU1_PE1_TX_DP<14>

C810      	Q_CAP_DIFFBUS_C0201	          	          	                    
          	               	1         	175B2     	P5E_CPU1_PE1_TX_C_DN<13>
          	               	2         	175B2     	P5E_CPU1_PE1_TX_DN<13>

C811      	Q_CAP_DIFFBUS_C0201	          	          	                    
          	               	1         	175B2     	P5E_CPU1_PE1_TX_C_DP<13>
          	               	2         	175B2     	P5E_CPU1_PE1_TX_DP<13>

C812      	Q_CAP_DIFFBUS_C0201	          	          	                    
          	               	1         	175B2     	P5E_CPU1_PE1_TX_C_DN<12>
          	               	2         	175B2     	P5E_CPU1_PE1_TX_DN<12>

C813      	Q_CAP_DIFFBUS_C0201	          	          	                    
          	               	1         	175B2     	P5E_CPU1_PE1_TX_C_DP<12>
          	               	2         	175B2     	P5E_CPU1_PE1_TX_DP<12>

C814      	Q_CAP_DIFFBUS_C0201	          	          	                    
          	               	1         	175B2     	P5E_CPU1_PE1_TX_C_DN<11>
          	               	2         	175B2     	P5E_CPU1_PE1_TX_DN<11>

C815      	Q_CAP_DIFFBUS_C0201	          	          	                    
          	               	1         	175B2     	P5E_CPU1_PE1_TX_C_DP<11>
          	               	2         	175B2     	P5E_CPU1_PE1_TX_DP<11>

C816      	Q_CAP_DIFFBUS_C0201	          	          	                    
          	               	1         	175B2     	P5E_CPU1_PE1_TX_C_DN<10>
          	               	2         	175B2     	P5E_CPU1_PE1_TX_DN<10>

C817      	Q_CAP_DIFFBUS_C0201	          	          	                    
          	               	1         	175B2     	P5E_CPU1_PE1_TX_C_DP<10>
          	               	2         	175B2     	P5E_CPU1_PE1_TX_DP<10>

C818      	Q_CAP_DIFFBUS_C0201	          	          	                    
          	               	1         	175B2     	P5E_CPU1_PE1_TX_C_DN<9>
          	               	2         	175B2     	P5E_CPU1_PE1_TX_DN<9>

C819      	Q_CAP_DIFFBUS_C0201	          	          	                    
          	               	1         	175B2     	P5E_CPU1_PE1_TX_C_DP<9>
          	               	2         	175B2     	P5E_CPU1_PE1_TX_DP<9>

C820      	Q_CAP_DIFFBUS_C0201	          	          	                    
          	               	1         	175B2     	P5E_CPU1_PE1_TX_C_DN<8>
          	               	2         	175B2     	P5E_CPU1_PE1_TX_DN<8>

C821      	Q_CAP_DIFFBUS_C0201	          	          	                    
          	               	1         	175B2     	P5E_CPU1_PE1_TX_C_DP<8>
          	               	2         	175B2     	P5E_CPU1_PE1_TX_DP<8>

C822      	Q_CAP_DIFFBUS_C0201	          	          	                    
          	               	1         	175B2     	P5E_CPU1_PE1_TX_C_DN<7>
          	               	2         	175B2     	P5E_CPU1_PE1_TX_DN<7>

C823      	Q_CAP_DIFFBUS_C0201	          	          	                    
          	               	1         	175B2     	P5E_CPU1_PE1_TX_C_DP<7>
          	               	2         	175B2     	P5E_CPU1_PE1_TX_DP<7>

C824      	Q_CAP_DIFFBUS_C0201	          	          	                    
          	               	1         	175B2     	P5E_CPU1_PE1_TX_C_DN<6>
          	               	2         	175B2     	P5E_CPU1_PE1_TX_DN<6>

C825      	Q_CAP_DIFFBUS_C0201	          	          	                    
          	               	1         	175B2     	P5E_CPU1_PE1_TX_C_DP<6>
          	               	2         	175B2     	P5E_CPU1_PE1_TX_DP<6>

C826      	Q_CAP_DIFFBUS_C0201	          	          	                    
          	               	1         	175B2     	P5E_CPU1_PE1_TX_C_DN<5>
          	               	2         	175B2     	P5E_CPU1_PE1_TX_DN<5>

C827      	Q_CAP_DIFFBUS_C0201	          	          	                    
          	               	1         	175B2     	P5E_CPU1_PE1_TX_C_DP<5>
          	               	2         	175B2     	P5E_CPU1_PE1_TX_DP<5>

C828      	Q_CAP_DIFFBUS_C0201	          	          	                    
          	               	1         	175B2     	P5E_CPU1_PE1_TX_C_DN<4>
          	               	2         	175B2     	P5E_CPU1_PE1_TX_DN<4>

C829      	Q_CAP_DIFFBUS_C0201	          	          	                    
          	               	1         	175B2     	P5E_CPU1_PE1_TX_C_DP<4>
          	               	2         	175B2     	P5E_CPU1_PE1_TX_DP<4>

C830      	Q_CAP_DIFFBUS_C0201	          	          	                    
          	               	1         	175B2     	P5E_CPU1_PE1_TX_C_DN<3>
          	               	2         	175B2     	P5E_CPU1_PE1_TX_DN<3>

C831      	Q_CAP_DIFFBUS_C0201	          	          	                    
          	               	1         	175A2     	P5E_CPU1_PE1_TX_C_DP<3>
          	               	2         	175A2     	P5E_CPU1_PE1_TX_DP<3>

C832      	Q_CAP_DIFFBUS_C0201	          	          	                    
          	               	1         	175A2     	P5E_CPU1_PE1_TX_C_DN<2>
          	               	2         	175A2     	P5E_CPU1_PE1_TX_DN<2>

C833      	Q_CAP_DIFFBUS_C0201	          	          	                    
          	               	1         	175A2     	P5E_CPU1_PE1_TX_C_DP<2>
          	               	2         	175A2     	P5E_CPU1_PE1_TX_DP<2>

C834      	Q_CAP_DIFFBUS_C0201	          	          	                    
          	               	1         	175A2     	P5E_CPU1_PE1_TX_C_DN<1>
          	               	2         	175A2     	P5E_CPU1_PE1_TX_DN<1>

C835      	Q_CAP_DIFFBUS_C0201	          	          	                    
          	               	1         	175A2     	P5E_CPU1_PE1_TX_C_DP<1>
          	               	2         	175A2     	P5E_CPU1_PE1_TX_DP<1>

C836      	Q_CAP_DIFFBUS_C0201	          	          	                    
          	               	1         	175A2     	P5E_CPU1_PE1_TX_C_DN<0>
          	               	2         	175A2     	P5E_CPU1_PE1_TX_DN<0>

C837      	Q_CAP_DIFFBUS_C0201	          	          	                    
          	               	1         	175A2     	P5E_CPU1_PE1_TX_C_DP<0>
          	               	2         	175A2     	P5E_CPU1_PE1_TX_DP<0>

C838      	Q_CAP_DIFFBUS_C0201	          	          	                    
          	               	1         	174B4     	P5E_CPU0_PE1_TX_C_DN<15>
          	               	2         	174B4     	P5E_CPU0_PE1_TX_DN<15>

C839      	Q_CAP_DIFFBUS_C0201	          	          	                    
          	               	1         	174B4     	P5E_CPU0_PE1_TX_C_DP<15>
          	               	2         	174B4     	P5E_CPU0_PE1_TX_DP<15>

C840      	Q_CAP_DIFFBUS_C0201	          	          	                    
          	               	1         	174B4     	P5E_CPU0_PE1_TX_C_DN<14>
          	               	2         	174B4     	P5E_CPU0_PE1_TX_DN<14>

C841      	Q_CAP_DIFFBUS_C0201	          	          	                    
          	               	1         	174B4     	P5E_CPU0_PE1_TX_C_DP<14>
          	               	2         	174B4     	P5E_CPU0_PE1_TX_DP<14>

C842      	Q_CAP_DIFFBUS_C0201	          	          	                    
          	               	1         	174B4     	P5E_CPU0_PE1_TX_C_DN<13>
          	               	2         	174B4     	P5E_CPU0_PE1_TX_DN<13>

C843      	Q_CAP_DIFFBUS_C0201	          	          	                    
          	               	1         	174B4     	P5E_CPU0_PE1_TX_C_DP<13>
          	               	2         	174B4     	P5E_CPU0_PE1_TX_DP<13>

C844      	Q_CAP_DIFFBUS_C0201	          	          	                    
          	               	1         	174B4     	P5E_CPU0_PE1_TX_C_DN<12>
          	               	2         	174B4     	P5E_CPU0_PE1_TX_DN<12>

C845      	Q_CAP_DIFFBUS_C0201	          	          	                    
          	               	1         	174B4     	P5E_CPU0_PE1_TX_C_DP<12>
          	               	2         	174B4     	P5E_CPU0_PE1_TX_DP<12>

C846      	Q_CAP_DIFFBUS_C0201	          	          	                    
          	               	1         	174B4     	P5E_CPU0_PE1_TX_C_DN<11>
          	               	2         	174B4     	P5E_CPU0_PE1_TX_DN<11>

C847      	Q_CAP_DIFFBUS_C0201	          	          	                    
          	               	1         	174B4     	P5E_CPU0_PE1_TX_C_DP<11>
          	               	2         	174B4     	P5E_CPU0_PE1_TX_DP<11>

C848      	Q_CAP_DIFFBUS_C0201	          	          	                    
          	               	1         	174B4     	P5E_CPU0_PE1_TX_C_DN<10>
          	               	2         	174B4     	P5E_CPU0_PE1_TX_DN<10>

C849      	Q_CAP_DIFFBUS_C0201	          	          	                    
          	               	1         	174B4     	P5E_CPU0_PE1_TX_C_DP<10>
          	               	2         	174B4     	P5E_CPU0_PE1_TX_DP<10>

C850      	Q_CAP_DIFFBUS_C0201	          	          	                    
          	               	1         	174B4     	P5E_CPU0_PE1_TX_C_DN<9>
          	               	2         	174B4     	P5E_CPU0_PE1_TX_DN<9>

C851      	Q_CAP_DIFFBUS_C0201	          	          	                    
          	               	1         	174B4     	P5E_CPU0_PE1_TX_C_DP<9>
          	               	2         	174B4     	P5E_CPU0_PE1_TX_DP<9>

C852      	Q_CAP_DIFFBUS_C0201	          	          	                    
          	               	1         	174B4     	P5E_CPU0_PE1_TX_C_DN<8>
          	               	2         	174B4     	P5E_CPU0_PE1_TX_DN<8>

C853      	Q_CAP_DIFFBUS_C0201	          	          	                    
          	               	1         	174B4     	P5E_CPU0_PE1_TX_C_DP<8>
          	               	2         	174B4     	P5E_CPU0_PE1_TX_DP<8>

C854      	Q_CAP_DIFFBUS_C0201	          	          	                    
          	               	1         	174B4     	P5E_CPU0_PE1_TX_C_DN<7>
          	               	2         	174B4     	P5E_CPU0_PE1_TX_DN<7>

C855      	Q_CAP_DIFFBUS_C0201	          	          	                    
          	               	1         	174B4     	P5E_CPU0_PE1_TX_C_DP<7>
          	               	2         	174B4     	P5E_CPU0_PE1_TX_DP<7>

C856      	Q_CAP_DIFFBUS_C0201	          	          	                    
          	               	1         	174B4     	P5E_CPU0_PE1_TX_C_DN<6>
          	               	2         	174B4     	P5E_CPU0_PE1_TX_DN<6>

C857      	Q_CAP_DIFFBUS_C0201	          	          	                    
          	               	1         	174B4     	P5E_CPU0_PE1_TX_C_DP<6>
          	               	2         	174B4     	P5E_CPU0_PE1_TX_DP<6>

C858      	Q_CAP_DIFFBUS_C0201	          	          	                    
          	               	1         	174B4     	P5E_CPU0_PE1_TX_C_DN<5>
          	               	2         	174B4     	P5E_CPU0_PE1_TX_DN<5>

C859      	Q_CAP_DIFFBUS_C0201	          	          	                    
          	               	1         	174B4     	P5E_CPU0_PE1_TX_C_DP<5>
          	               	2         	174B4     	P5E_CPU0_PE1_TX_DP<5>

C860      	Q_CAP_DIFFBUS_C0201	          	          	                    
          	               	1         	174B4     	P5E_CPU0_PE1_TX_C_DN<4>
          	               	2         	174B4     	P5E_CPU0_PE1_TX_DN<4>

C861      	Q_CAP_DIFFBUS_C0201	          	          	                    
          	               	1         	174B4     	P5E_CPU0_PE1_TX_C_DP<4>
          	               	2         	174B4     	P5E_CPU0_PE1_TX_DP<4>

C862      	Q_CAP_DIFFBUS_C0201	          	          	                    
          	               	1         	174A4     	P5E_CPU0_PE1_TX_C_DN<3>
          	               	2         	174A4     	P5E_CPU0_PE1_TX_DN<3>

C863      	Q_CAP_DIFFBUS_C0201	          	          	                    
          	               	1         	174A4     	P5E_CPU0_PE1_TX_C_DP<3>
          	               	2         	174A4     	P5E_CPU0_PE1_TX_DP<3>

C864      	Q_CAP_DIFFBUS_C0201	          	          	                    
          	               	1         	174A4     	P5E_CPU0_PE1_TX_C_DN<2>
          	               	2         	174A4     	P5E_CPU0_PE1_TX_DN<2>

C865      	Q_CAP_DIFFBUS_C0201	          	          	                    
          	               	1         	174A4     	P5E_CPU0_PE1_TX_C_DP<2>
          	               	2         	174A4     	P5E_CPU0_PE1_TX_DP<2>

C866      	Q_CAP_DIFFBUS_C0201	          	          	                    
          	               	1         	174A4     	P5E_CPU0_PE1_TX_C_DN<1>
          	               	2         	174A4     	P5E_CPU0_PE1_TX_DN<1>

C867      	Q_CAP_DIFFBUS_C0201	          	          	                    
          	               	1         	174A4     	P5E_CPU0_PE1_TX_C_DP<1>
          	               	2         	174A4     	P5E_CPU0_PE1_TX_DP<1>

C868      	Q_CAP_DIFFBUS_C0201	          	          	                    
          	               	1         	174A4     	P5E_CPU0_PE1_TX_C_DN<0>
          	               	2         	174A4     	P5E_CPU0_PE1_TX_DN<0>

C869      	Q_CAP_DIFFBUS_C0201	          	          	                    
          	               	1         	174A4     	P5E_CPU0_PE1_TX_C_DP<0>
          	               	2         	174A4     	P5E_CPU0_PE1_TX_DP<0>

C870      	Q_CAP_DIFFBUS_C0201	          	          	                    
          	               	1         	174B2     	P5E_CPU0_PE3_TX_C_DN<15>
          	               	2         	174B2     	P5E_CPU0_PE3_TX_DN<15>

C871      	Q_CAP_DIFFBUS_C0201	          	          	                    
          	               	1         	174B2     	P5E_CPU0_PE3_TX_C_DP<15>
          	               	2         	174B2     	P5E_CPU0_PE3_TX_DP<15>

C872      	Q_CAP_DIFFBUS_C0201	          	          	                    
          	               	1         	174B2     	P5E_CPU0_PE3_TX_C_DN<14>
          	               	2         	174B2     	P5E_CPU0_PE3_TX_DN<14>

C873      	Q_CAP_DIFFBUS_C0201	          	          	                    
          	               	1         	174B2     	P5E_CPU0_PE3_TX_C_DP<14>
          	               	2         	174B2     	P5E_CPU0_PE3_TX_DP<14>

C874      	Q_CAP_DIFFBUS_C0201	          	          	                    
          	               	1         	174B2     	P5E_CPU0_PE3_TX_C_DN<13>
          	               	2         	174B2     	P5E_CPU0_PE3_TX_DN<13>

C875      	Q_CAP_DIFFBUS_C0201	          	          	                    
          	               	1         	174B2     	P5E_CPU0_PE3_TX_C_DP<13>
          	               	2         	174B2     	P5E_CPU0_PE3_TX_DP<13>

C876      	Q_CAP_DIFFBUS_C0201	          	          	                    
          	               	1         	174B2     	P5E_CPU0_PE3_TX_C_DN<12>
          	               	2         	174B2     	P5E_CPU0_PE3_TX_DN<12>

C877      	Q_CAP_DIFFBUS_C0201	          	          	                    
          	               	1         	174B2     	P5E_CPU0_PE3_TX_C_DP<12>
          	               	2         	174B2     	P5E_CPU0_PE3_TX_DP<12>

C878      	Q_CAP_DIFFBUS_C0201	          	          	                    
          	               	1         	174B2     	P5E_CPU0_PE3_TX_C_DN<11>
          	               	2         	174B2     	P5E_CPU0_PE3_TX_DN<11>

C879      	Q_CAP_DIFFBUS_C0201	          	          	                    
          	               	1         	174B2     	P5E_CPU0_PE3_TX_C_DP<11>
          	               	2         	174B2     	P5E_CPU0_PE3_TX_DP<11>

C880      	Q_CAP_DIFFBUS_C0201	          	          	                    
          	               	1         	174B2     	P5E_CPU0_PE3_TX_C_DN<10>
          	               	2         	174B2     	P5E_CPU0_PE3_TX_DN<10>

C881      	Q_CAP_DIFFBUS_C0201	          	          	                    
          	               	1         	174B2     	P5E_CPU0_PE3_TX_C_DP<10>
          	               	2         	174B2     	P5E_CPU0_PE3_TX_DP<10>

C882      	Q_CAP_DIFFBUS_C0201	          	          	                    
          	               	1         	174B2     	P5E_CPU0_PE3_TX_C_DN<9>
          	               	2         	174B2     	P5E_CPU0_PE3_TX_DN<9>

C883      	Q_CAP_DIFFBUS_C0201	          	          	                    
          	               	1         	174B2     	P5E_CPU0_PE3_TX_C_DP<9>
          	               	2         	174B2     	P5E_CPU0_PE3_TX_DP<9>

C884      	Q_CAP_DIFFBUS_C0201	          	          	                    
          	               	1         	174B2     	P5E_CPU0_PE3_TX_C_DN<8>
          	               	2         	174B2     	P5E_CPU0_PE3_TX_DN<8>

C885      	Q_CAP_DIFFBUS_C0201	          	          	                    
          	               	1         	174B2     	P5E_CPU0_PE3_TX_C_DP<8>
          	               	2         	174B2     	P5E_CPU0_PE3_TX_DP<8>

C886      	Q_CAP_DIFFBUS_C0201	          	          	                    
          	               	1         	174B2     	P5E_CPU0_PE3_TX_C_DN<7>
          	               	2         	174B2     	P5E_CPU0_PE3_TX_DN<7>

C887      	Q_CAP_DIFFBUS_C0201	          	          	                    
          	               	1         	174B2     	P5E_CPU0_PE3_TX_C_DP<7>
          	               	2         	174B2     	P5E_CPU0_PE3_TX_DP<7>

C888      	Q_CAP_DIFFBUS_C0201	          	          	                    
          	               	1         	174B2     	P5E_CPU0_PE3_TX_C_DN<6>
          	               	2         	174B2     	P5E_CPU0_PE3_TX_DN<6>

C889      	Q_CAP_DIFFBUS_C0201	          	          	                    
          	               	1         	174B2     	P5E_CPU0_PE3_TX_C_DP<6>
          	               	2         	174B2     	P5E_CPU0_PE3_TX_DP<6>

C890      	Q_CAP_DIFFBUS_C0201	          	          	                    
          	               	1         	174B2     	P5E_CPU0_PE3_TX_C_DN<5>
          	               	2         	174B2     	P5E_CPU0_PE3_TX_DN<5>

C891      	Q_CAP_DIFFBUS_C0201	          	          	                    
          	               	1         	174B2     	P5E_CPU0_PE3_TX_C_DP<5>
          	               	2         	174B2     	P5E_CPU0_PE3_TX_DP<5>

C892      	Q_CAP_DIFFBUS_C0201	          	          	                    
          	               	1         	174B2     	P5E_CPU0_PE3_TX_C_DN<4>
          	               	2         	174B2     	P5E_CPU0_PE3_TX_DN<4>

C893      	Q_CAP_DIFFBUS_C0201	          	          	                    
          	               	1         	174B2     	P5E_CPU0_PE3_TX_C_DP<4>
          	               	2         	174B2     	P5E_CPU0_PE3_TX_DP<4>

C894      	Q_CAP_DIFFBUS_C0201	          	          	                    
          	               	1         	174A2     	P5E_CPU0_PE3_TX_C_DN<3>
          	               	2         	174A2     	P5E_CPU0_PE3_TX_DN<3>

C895      	Q_CAP_DIFFBUS_C0201	          	          	                    
          	               	1         	174A2     	P5E_CPU0_PE3_TX_C_DP<3>
          	               	2         	174A2     	P5E_CPU0_PE3_TX_DP<3>

C896      	Q_CAP_DIFFBUS_C0201	          	          	                    
          	               	1         	174A2     	P5E_CPU0_PE3_TX_C_DN<2>
          	               	2         	174A2     	P5E_CPU0_PE3_TX_DN<2>

C897      	Q_CAP_DIFFBUS_C0201	          	          	                    
          	               	1         	174A2     	P5E_CPU0_PE3_TX_C_DP<2>
          	               	2         	174A2     	P5E_CPU0_PE3_TX_DP<2>

C898      	Q_CAP_DIFFBUS_C0201	          	          	                    
          	               	1         	174A2     	P5E_CPU0_PE3_TX_C_DN<1>
          	               	2         	174A2     	P5E_CPU0_PE3_TX_DN<1>

C899      	Q_CAP_DIFFBUS_C0201	          	          	                    
          	               	1         	174A2     	P5E_CPU0_PE3_TX_C_DP<1>
          	               	2         	174A2     	P5E_CPU0_PE3_TX_DP<1>

C900      	Q_CAP_DIFFBUS_C0201	          	          	                    
          	               	1         	174A2     	P5E_CPU0_PE3_TX_C_DN<0>
          	               	2         	174A2     	P5E_CPU0_PE3_TX_DN<0>

C901      	Q_CAP_DIFFBUS_C0201	          	          	                    
          	               	1         	174A2     	P5E_CPU0_PE3_TX_C_DP<0>
          	               	2         	174A2     	P5E_CPU0_PE3_TX_DP<0>

C902      	Q_CAP_DIFFBUS_C0201	          	          	                    
          	               	1         	173B4     	P5E_CPU0_PE0_TX_C_DN<15>
          	               	2         	173B4     	P5E_CPU0_PE0_TX_DN<15>

C903      	Q_CAP_DIFFBUS_C0201	          	          	                    
          	               	1         	173B4     	P5E_CPU0_PE0_TX_C_DP<15>
          	               	2         	173B4     	P5E_CPU0_PE0_TX_DP<15>

C904      	Q_CAP_DIFFBUS_C0201	          	          	                    
          	               	1         	173B4     	P5E_CPU0_PE0_TX_C_DN<14>
          	               	2         	173B4     	P5E_CPU0_PE0_TX_DN<14>

C905      	Q_CAP_DIFFBUS_C0201	          	          	                    
          	               	1         	173B4     	P5E_CPU0_PE0_TX_C_DP<14>
          	               	2         	173B4     	P5E_CPU0_PE0_TX_DP<14>

C906      	Q_CAP_DIFFBUS_C0201	          	          	                    
          	               	1         	173B4     	P5E_CPU0_PE0_TX_C_DN<13>
          	               	2         	173B4     	P5E_CPU0_PE0_TX_DN<13>

C907      	Q_CAP_DIFFBUS_C0201	          	          	                    
          	               	1         	173B4     	P5E_CPU0_PE0_TX_C_DP<13>
          	               	2         	173B4     	P5E_CPU0_PE0_TX_DP<13>

C908      	Q_CAP_DIFFBUS_C0201	          	          	                    
          	               	1         	173B4     	P5E_CPU0_PE0_TX_C_DN<12>
          	               	2         	173B4     	P5E_CPU0_PE0_TX_DN<12>

C909      	Q_CAP_DIFFBUS_C0201	          	          	                    
          	               	1         	173B4     	P5E_CPU0_PE0_TX_C_DP<12>
          	               	2         	173B4     	P5E_CPU0_PE0_TX_DP<12>

C910      	Q_CAP_DIFFBUS_C0201	          	          	                    
          	               	1         	173B4     	P5E_CPU0_PE0_TX_C_DN<11>
          	               	2         	173B4     	P5E_CPU0_PE0_TX_DN<11>

C911      	Q_CAP_DIFFBUS_C0201	          	          	                    
          	               	1         	173B4     	P5E_CPU0_PE0_TX_C_DP<11>
          	               	2         	173B4     	P5E_CPU0_PE0_TX_DP<11>

C912      	Q_CAP_DIFFBUS_C0201	          	          	                    
          	               	1         	173B4     	P5E_CPU0_PE0_TX_C_DN<10>
          	               	2         	173B4     	P5E_CPU0_PE0_TX_DN<10>

C913      	Q_CAP_DIFFBUS_C0201	          	          	                    
          	               	1         	173B4     	P5E_CPU0_PE0_TX_C_DP<10>
          	               	2         	173B4     	P5E_CPU0_PE0_TX_DP<10>

C914      	Q_CAP_DIFFBUS_C0201	          	          	                    
          	               	1         	173B4     	P5E_CPU0_PE0_TX_C_DN<9>
          	               	2         	173B4     	P5E_CPU0_PE0_TX_DN<9>

C915      	Q_CAP_DIFFBUS_C0201	          	          	                    
          	               	1         	173B4     	P5E_CPU0_PE0_TX_C_DP<9>
          	               	2         	173B4     	P5E_CPU0_PE0_TX_DP<9>

C916      	Q_CAP_DIFFBUS_C0201	          	          	                    
          	               	1         	173B4     	P5E_CPU0_PE0_TX_C_DN<8>
          	               	2         	173B4     	P5E_CPU0_PE0_TX_DN<8>

C917      	Q_CAP_DIFFBUS_C0201	          	          	                    
          	               	1         	173B4     	P5E_CPU0_PE0_TX_C_DP<8>
          	               	2         	173B4     	P5E_CPU0_PE0_TX_DP<8>

C918      	Q_CAP_DIFFBUS_C0201	          	          	                    
          	               	1         	173B4     	P5E_CPU0_PE0_TX_C_DN<7>
          	               	2         	173B4     	P5E_CPU0_PE0_TX_DN<7>

C919      	Q_CAP_DIFFBUS_C0201	          	          	                    
          	               	1         	173B4     	P5E_CPU0_PE0_TX_C_DP<7>
          	               	2         	173B4     	P5E_CPU0_PE0_TX_DP<7>

C920      	Q_CAP_DIFFBUS_C0201	          	          	                    
          	               	1         	173B4     	P5E_CPU0_PE0_TX_C_DN<6>
          	               	2         	173B4     	P5E_CPU0_PE0_TX_DN<6>

C921      	Q_CAP_DIFFBUS_C0201	          	          	                    
          	               	1         	173B4     	P5E_CPU0_PE0_TX_C_DP<6>
          	               	2         	173B4     	P5E_CPU0_PE0_TX_DP<6>

C922      	Q_CAP_DIFFBUS_C0201	          	          	                    
          	               	1         	173B4     	P5E_CPU0_PE0_TX_C_DN<5>
          	               	2         	173B4     	P5E_CPU0_PE0_TX_DN<5>

C923      	Q_CAP_DIFFBUS_C0201	          	          	                    
          	               	1         	173B4     	P5E_CPU0_PE0_TX_C_DP<5>
          	               	2         	173B4     	P5E_CPU0_PE0_TX_DP<5>

C924      	Q_CAP_DIFFBUS_C0201	          	          	                    
          	               	1         	173B4     	P5E_CPU0_PE0_TX_C_DN<4>
          	               	2         	173B4     	P5E_CPU0_PE0_TX_DN<4>

C925      	Q_CAP_DIFFBUS_C0201	          	          	                    
          	               	1         	173B4     	P5E_CPU0_PE0_TX_C_DP<4>
          	               	2         	173B4     	P5E_CPU0_PE0_TX_DP<4>

C926      	Q_CAP_DIFFBUS_C0201	          	          	                    
          	               	1         	173B4     	P5E_CPU0_PE0_TX_C_DN<3>
          	               	2         	173B4     	P5E_CPU0_PE0_TX_DN<3>

C927      	Q_CAP_DIFFBUS_C0201	          	          	                    
          	               	1         	173B4     	P5E_CPU0_PE0_TX_C_DP<3>
          	               	2         	173B4     	P5E_CPU0_PE0_TX_DP<3>

C928      	Q_CAP_DIFFBUS_C0201	          	          	                    
          	               	1         	173A4     	P5E_CPU0_PE0_TX_C_DN<2>
          	               	2         	173A4     	P5E_CPU0_PE0_TX_DN<2>

C929      	Q_CAP_DIFFBUS_C0201	          	          	                    
          	               	1         	173A4     	P5E_CPU0_PE0_TX_C_DP<2>
          	               	2         	173A4     	P5E_CPU0_PE0_TX_DP<2>

C930      	Q_CAP_DIFFBUS_C0201	          	          	                    
          	               	1         	173A4     	P5E_CPU0_PE0_TX_C_DN<1>
          	               	2         	173A4     	P5E_CPU0_PE0_TX_DN<1>

C931      	Q_CAP_DIFFBUS_C0201	          	          	                    
          	               	1         	173A4     	P5E_CPU0_PE0_TX_C_DP<1>
          	               	2         	173A4     	P5E_CPU0_PE0_TX_DP<1>

C932      	Q_CAP_DIFFBUS_C0201	          	          	                    
          	               	1         	173A4     	P5E_CPU0_PE0_TX_C_DN<0>
          	               	2         	173A4     	P5E_CPU0_PE0_TX_DN<0>

C933      	Q_CAP_DIFFBUS_C0201	          	          	                    
          	               	1         	173A4     	P5E_CPU0_PE0_TX_C_DP<0>
          	               	2         	173A4     	P5E_CPU0_PE0_TX_DP<0>

C934      	Q_CAP_DIFFBUS_C0201	          	          	                    
          	               	1         	173B2     	P5E_CPU0_PE2_TX_C_DN<15>
          	               	2         	173B2     	P5E_CPU0_PE2_TX_DN<15>

C935      	Q_CAP_DIFFBUS_C0201	          	          	                    
          	               	1         	173B2     	P5E_CPU0_PE2_TX_C_DP<15>
          	               	2         	173B2     	P5E_CPU0_PE2_TX_DP<15>

C936      	Q_CAP_DIFFBUS_C0201	          	          	                    
          	               	1         	173B2     	P5E_CPU0_PE2_TX_C_DN<14>
          	               	2         	173B2     	P5E_CPU0_PE2_TX_DN<14>

C937      	Q_CAP_DIFFBUS_C0201	          	          	                    
          	               	1         	173B2     	P5E_CPU0_PE2_TX_C_DP<14>
          	               	2         	173B2     	P5E_CPU0_PE2_TX_DP<14>

C938      	Q_CAP_DIFFBUS_C0201	          	          	                    
          	               	1         	173B2     	P5E_CPU0_PE2_TX_C_DN<13>
          	               	2         	173B2     	P5E_CPU0_PE2_TX_DN<13>

C939      	Q_CAP_DIFFBUS_C0201	          	          	                    
          	               	1         	173B2     	P5E_CPU0_PE2_TX_C_DP<13>
          	               	2         	173B2     	P5E_CPU0_PE2_TX_DP<13>

C940      	Q_CAP_DIFFBUS_C0201	          	          	                    
          	               	1         	173B2     	P5E_CPU0_PE2_TX_C_DN<12>
          	               	2         	173B2     	P5E_CPU0_PE2_TX_DN<12>

C941      	Q_CAP_DIFFBUS_C0201	          	          	                    
          	               	1         	173B2     	P5E_CPU0_PE2_TX_C_DP<12>
          	               	2         	173B2     	P5E_CPU0_PE2_TX_DP<12>

C942      	Q_CAP_DIFFBUS_C0201	          	          	                    
          	               	1         	173B2     	P5E_CPU0_PE2_TX_C_DN<11>
          	               	2         	173B2     	P5E_CPU0_PE2_TX_DN<11>

C943      	Q_CAP_DIFFBUS_C0201	          	          	                    
          	               	1         	173B2     	P5E_CPU0_PE2_TX_C_DP<11>
          	               	2         	173B2     	P5E_CPU0_PE2_TX_DP<11>

C944      	Q_CAP_DIFFBUS_C0201	          	          	                    
          	               	1         	173B2     	P5E_CPU0_PE2_TX_C_DN<10>
          	               	2         	173B2     	P5E_CPU0_PE2_TX_DN<10>

C945      	Q_CAP_DIFFBUS_C0201	          	          	                    
          	               	1         	173B2     	P5E_CPU0_PE2_TX_C_DP<10>
          	               	2         	173B2     	P5E_CPU0_PE2_TX_DP<10>

C946      	Q_CAP_DIFFBUS_C0201	          	          	                    
          	               	1         	173B2     	P5E_CPU0_PE2_TX_C_DN<9>
          	               	2         	173B2     	P5E_CPU0_PE2_TX_DN<9>

C947      	Q_CAP_DIFFBUS_C0201	          	          	                    
          	               	1         	173B2     	P5E_CPU0_PE2_TX_C_DP<9>
          	               	2         	173B2     	P5E_CPU0_PE2_TX_DP<9>

C948      	Q_CAP_DIFFBUS_C0201	          	          	                    
          	               	1         	173B2     	P5E_CPU0_PE2_TX_C_DN<8>
          	               	2         	173B2     	P5E_CPU0_PE2_TX_DN<8>

C949      	Q_CAP_DIFFBUS_C0201	          	          	                    
          	               	1         	173B2     	P5E_CPU0_PE2_TX_C_DP<8>
          	               	2         	173B2     	P5E_CPU0_PE2_TX_DP<8>

C950      	Q_CAP_DIFFBUS_C0201	          	          	                    
          	               	1         	173B2     	P5E_CPU0_PE2_TX_C_DN<7>
          	               	2         	173B2     	P5E_CPU0_PE2_TX_DN<7>

C951      	Q_CAP_DIFFBUS_C0201	          	          	                    
          	               	1         	173B2     	P5E_CPU0_PE2_TX_C_DP<7>
          	               	2         	173B2     	P5E_CPU0_PE2_TX_DP<7>

C952      	Q_CAP_DIFFBUS_C0201	          	          	                    
          	               	1         	173B2     	P5E_CPU0_PE2_TX_C_DN<6>
          	               	2         	173B2     	P5E_CPU0_PE2_TX_DN<6>

C953      	Q_CAP_DIFFBUS_C0201	          	          	                    
          	               	1         	173B2     	P5E_CPU0_PE2_TX_C_DP<6>
          	               	2         	173B2     	P5E_CPU0_PE2_TX_DP<6>

C954      	Q_CAP_DIFFBUS_C0201	          	          	                    
          	               	1         	173B2     	P5E_CPU0_PE2_TX_C_DN<5>
          	               	2         	173B2     	P5E_CPU0_PE2_TX_DN<5>

C955      	Q_CAP_DIFFBUS_C0201	          	          	                    
          	               	1         	173B2     	P5E_CPU0_PE2_TX_C_DP<5>
          	               	2         	173B2     	P5E_CPU0_PE2_TX_DP<5>

C956      	Q_CAP_DIFFBUS_C0201	          	          	                    
          	               	1         	173B2     	P5E_CPU0_PE2_TX_C_DN<4>
          	               	2         	173B2     	P5E_CPU0_PE2_TX_DN<4>

C957      	Q_CAP_DIFFBUS_C0201	          	          	                    
          	               	1         	173B2     	P5E_CPU0_PE2_TX_C_DP<4>
          	               	2         	173B2     	P5E_CPU0_PE2_TX_DP<4>

C958      	Q_CAP_DIFFBUS_C0201	          	          	                    
          	               	1         	173B2     	P5E_CPU0_PE2_TX_C_DN<3>
          	               	2         	173B2     	P5E_CPU0_PE2_TX_DN<3>

C959      	Q_CAP_DIFFBUS_C0201	          	          	                    
          	               	1         	173B2     	P5E_CPU0_PE2_TX_C_DP<3>
          	               	2         	173B2     	P5E_CPU0_PE2_TX_DP<3>

C960      	Q_CAP_DIFFBUS_C0201	          	          	                    
          	               	1         	173A2     	P5E_CPU0_PE2_TX_C_DN<2>
          	               	2         	173A2     	P5E_CPU0_PE2_TX_DN<2>

C961      	Q_CAP_DIFFBUS_C0201	          	          	                    
          	               	1         	173A2     	P5E_CPU0_PE2_TX_C_DP<2>
          	               	2         	173A2     	P5E_CPU0_PE2_TX_DP<2>

C962      	Q_CAP_DIFFBUS_C0201	          	          	                    
          	               	1         	173A2     	P5E_CPU0_PE2_TX_C_DN<1>
          	               	2         	173A2     	P5E_CPU0_PE2_TX_DN<1>

C963      	Q_CAP_DIFFBUS_C0201	          	          	                    
          	               	1         	173A2     	P5E_CPU0_PE2_TX_C_DP<1>
          	               	2         	173A2     	P5E_CPU0_PE2_TX_DP<1>

C964      	Q_CAP_DIFFBUS_C0201	          	          	                    
          	               	1         	173A2     	P5E_CPU0_PE2_TX_C_DN<0>
          	               	2         	173A2     	P5E_CPU0_PE2_TX_DN<0>

C965      	Q_CAP_DIFFBUS_C0201	          	          	                    
          	               	1         	173A2     	P5E_CPU0_PE2_TX_C_DP<0>
          	               	2         	173A2     	P5E_CPU0_PE2_TX_DP<0>

C966      	Q_CAP_C0402    	          	          	                    
          	               	1         	74B4      	PVCCIN_CPU0         
          	               	2         	74B4      	GND                 

C967      	Q_CAP_C0402    	          	          	                    
          	               	1         	74B4      	PVCCIN_CPU0         
          	               	2         	74B4      	GND                 

C968      	Q_CAP_C0402    	          	          	                    
          	               	1         	74B4      	PVCCIN_CPU0         
          	               	2         	74B4      	GND                 

C969      	Q_CAP_C0402    	          	          	                    
          	               	1         	74B4      	PVCCIN_CPU0         
          	               	2         	74B4      	GND                 

C970      	Q_CAP_C0402    	          	          	                    
          	               	1         	74B4      	PVCCIN_CPU0         
          	               	2         	74B4      	GND                 

C971      	Q_CAP_C0402    	          	          	                    
          	               	1         	74B4      	PVCCIN_CPU0         
          	               	2         	74B4      	GND                 

C972      	Q_CAP_C0402    	          	          	                    
          	               	1         	74B4      	PVCCIN_CPU0         
          	               	2         	74B4      	GND                 

C973      	Q_CAP_C0402    	          	          	                    
          	               	1         	74B4      	PVCCIN_CPU0         
          	               	2         	74B4      	GND                 

C974      	Q_CAP_C0402    	          	          	                    
          	               	1         	74B4      	PVCCIN_CPU0         
          	               	2         	74B4      	GND                 

C975      	Q_CAP_C0402    	          	          	                    
          	               	1         	74B4      	PVCCIN_CPU0         
          	               	2         	74B4      	GND                 

C976      	Q_CAP_C0402    	          	          	                    
          	               	1         	74B4      	PVCCIN_CPU0         
          	               	2         	74B4      	GND                 

C977      	Q_CAP_C0402    	          	          	                    
          	               	1         	74B4      	PVCCIN_CPU0         
          	               	2         	74B4      	GND                 

C978      	Q_CAP_C0402    	          	          	                    
          	               	1         	74B4      	PVCCIN_CPU0         
          	               	2         	74B4      	GND                 

C979      	Q_CAP_C0402    	          	          	                    
          	               	1         	74B4      	PVCCIN_CPU0         
          	               	2         	74B4      	GND                 

C980      	Q_CAP_C0402    	          	          	                    
          	               	1         	74B4      	PVCCIN_CPU0         
          	               	2         	74B4      	GND                 

C981      	Q_CAP_C0402    	          	          	                    
          	               	1         	74B4      	PVCCIN_CPU0         
          	               	2         	74B4      	GND                 

C982      	Q_CAP_C0402    	          	          	                    
          	               	1         	74B4      	PVCCIN_CPU0         
          	               	2         	74B4      	GND                 

C983      	Q_CAP_C0402    	          	          	                    
          	               	1         	74B4      	PVCCIN_CPU0         
          	               	2         	74B4      	GND                 

C984      	Q_CAP_C0402    	          	          	                    
          	               	1         	74B4      	PVCCIN_CPU0         
          	               	2         	74B4      	GND                 

C985      	Q_CAP_C0402    	          	          	                    
          	               	1         	74B4      	PVCCIN_CPU0         
          	               	2         	74B4      	GND                 

C986      	Q_CAP_C0402    	          	          	                    
          	               	1         	74B4      	PVCCIN_CPU0         
          	               	2         	74B4      	GND                 

C987      	Q_CAP_C0402    	          	          	                    
          	               	1         	74B4      	PVCCIN_CPU0         
          	               	2         	74B4      	GND                 

C988      	Q_CAP_C0402    	          	          	                    
          	               	1         	74B4      	PVCCIN_CPU0         
          	               	2         	74B4      	GND                 

C989      	Q_CAP_C0402    	          	          	                    
          	               	1         	74B4      	PVCCIN_CPU0         
          	               	2         	74B4      	GND                 

C990      	Q_CAP_C0402    	          	          	                    
          	               	1         	74B4      	PVCCIN_CPU0         
          	               	2         	74B4      	GND                 

C991      	Q_CAP_C0402    	          	          	                    
          	               	1         	74B4      	PVCCIN_CPU0         
          	               	2         	74B4      	GND                 

C992      	Q_CAP_C0402    	          	          	                    
          	               	1         	74B4      	PVCCIN_CPU0         
          	               	2         	74B4      	GND                 

C993      	Q_CAP_C0402    	          	          	                    
          	               	1         	74B4      	PVCCIN_CPU0         
          	               	2         	74B4      	GND                 

C994      	Q_CAP_C0402    	          	          	                    
          	               	1         	74B3      	PVCCIN_CPU0         
          	               	2         	74B3      	GND                 

C995      	Q_CAP_C0402    	          	          	                    
          	               	1         	74B3      	PVCCIN_CPU0         
          	               	2         	74B3      	GND                 

C996      	Q_CAP_C0402    	          	          	                    
          	               	1         	74B3      	PVCCIN_CPU0         
          	               	2         	74B3      	GND                 

C997      	Q_CAP_C0402    	          	          	                    
          	               	1         	74B3      	PVCCIN_CPU0         
          	               	2         	74B3      	GND                 

C998      	Q_CAP_C0402    	          	          	                    
          	               	1         	74B3      	PVCCIN_CPU0         
          	               	2         	74B3      	GND                 

C999      	Q_CAP_C0402    	          	          	                    
          	               	1         	74B3      	PVCCIN_CPU0         
          	               	2         	74B3      	GND                 

C1000     	Q_CAP_C0402    	          	          	                    
          	               	1         	74B3      	PVCCIN_CPU0         
          	               	2         	74B3      	GND                 

C1001     	Q_CAP_C0402    	          	          	                    
          	               	1         	74B3      	PVCCIN_CPU0         
          	               	2         	74B3      	GND                 

C1002     	Q_CAP_C0402    	          	          	                    
          	               	1         	74B3      	PVCCIN_CPU0         
          	               	2         	74B3      	GND                 

C1003     	Q_CAP_C0402    	          	          	                    
          	               	1         	74B3      	PVCCIN_CPU0         
          	               	2         	74B3      	GND                 

C1004     	Q_CAP_C0402    	          	          	                    
          	               	1         	74B3      	PVCCIN_CPU0         
          	               	2         	74B3      	GND                 

C1005     	Q_CAP_C0402    	          	          	                    
          	               	1         	74B3      	PVCCIN_CPU0         
          	               	2         	74B3      	GND                 

C1006     	Q_CAP_C0402    	          	          	                    
          	               	1         	74B3      	PVCCIN_CPU0         
          	               	2         	74B3      	GND                 

C1007     	Q_CAP_C0402    	          	          	                    
          	               	1         	74B3      	PVCCIN_CPU0         
          	               	2         	74B3      	GND                 

C1008     	Q_CAP_C0402    	          	          	                    
          	               	1         	74B3      	PVCCIN_CPU0         
          	               	2         	74B3      	GND                 

C1009     	Q_CAP_C0402    	          	          	                    
          	               	1         	74B3      	PVCCIN_CPU0         
          	               	2         	74B3      	GND                 

C1010     	Q_CAP_C0402    	          	          	                    
          	               	1         	74B3      	PVCCIN_CPU0         
          	               	2         	74B3      	GND                 

C1011     	Q_CAP_C0402    	          	          	                    
          	               	1         	74B3      	PVCCIN_CPU0         
          	               	2         	74B3      	GND                 

C1012     	Q_CAP_C0402    	          	          	                    
          	               	1         	74B3      	PVCCIN_CPU0         
          	               	2         	74B3      	GND                 

C1013     	Q_CAP_C0402    	          	          	                    
          	               	1         	74B3      	PVCCIN_CPU0         
          	               	2         	74B3      	GND                 

C1014     	Q_CAP_C0402    	          	          	                    
          	               	1         	74B2      	PVCCIN_CPU0         
          	               	2         	74B2      	GND                 

C1015     	Q_CAP_C0402    	          	          	                    
          	               	1         	74B2      	PVCCIN_CPU0         
          	               	2         	74B2      	GND                 

C1016     	Q_CAP_C0402    	          	          	                    
          	               	1         	74B2      	PVCCIN_CPU0         
          	               	2         	74B2      	GND                 

C1017     	Q_CAP_C0402    	          	          	                    
          	               	1         	74B2      	PVCCIN_CPU0         
          	               	2         	74B2      	GND                 

C1018     	Q_CAP_C0402    	          	          	                    
          	               	1         	74B2      	PVCCIN_CPU0         
          	               	2         	74B2      	GND                 

C1019     	Q_CAP_C0402    	          	          	                    
          	               	1         	74B2      	PVCCIN_CPU0         
          	               	2         	74B2      	GND                 

C1020     	Q_CAP_C0402    	          	          	                    
          	               	1         	74B2      	PVCCIN_CPU0         
          	               	2         	74B2      	GND                 

C1021     	Q_CAP_C0402    	          	          	                    
          	               	1         	74B2      	PVCCIN_CPU0         
          	               	2         	74B2      	GND                 

C1022     	Q_CAP_C0402    	          	          	                    
          	               	1         	74B2      	PVCCIN_CPU0         
          	               	2         	74B2      	GND                 

C1023     	Q_CAP_C0402    	          	          	                    
          	               	1         	74B2      	PVCCIN_CPU0         
          	               	2         	74B2      	GND                 

C1024     	Q_CAP_C0402    	          	          	                    
          	               	1         	74B2      	PVCCIN_CPU0         
          	               	2         	74B2      	GND                 

C1025     	Q_CAP_C0402    	          	          	                    
          	               	1         	74B2      	PVCCIN_CPU0         
          	               	2         	74B2      	GND                 

C1026     	Q_CAP_C0402    	          	          	                    
          	               	1         	74B2      	PVCCIN_CPU0         
          	               	2         	74B2      	GND                 

C1027     	Q_CAP_C0402    	          	          	                    
          	               	1         	74B2      	PVCCIN_CPU0         
          	               	2         	74B2      	GND                 

C1028     	Q_CAP_C0402    	          	          	                    
          	               	1         	74B2      	PVCCIN_CPU0         
          	               	2         	74B2      	GND                 

C1029     	Q_CAP_C0402    	          	          	                    
          	               	1         	74B2      	PVCCIN_CPU0         
          	               	2         	74B2      	GND                 

C1030     	Q_CAP_C0402    	          	          	                    
          	               	1         	74B1      	PVCCIN_CPU0         
          	               	2         	74B1      	GND                 

C1031     	Q_CAP_C0402    	          	          	                    
          	               	1         	74B1      	PVCCIN_CPU0         
          	               	2         	74B1      	GND                 

C1032     	Q_CAP_C0402    	          	          	                    
          	               	1         	74B1      	PVCCIN_CPU0         
          	               	2         	74B1      	GND                 

C1033     	Q_CAP_C0402    	          	          	                    
          	               	1         	74B1      	PVCCIN_CPU0         
          	               	2         	74B1      	GND                 

C1034     	Q_CAP_C0402    	          	          	                    
          	               	1         	74B1      	PVCCIN_CPU0         
          	               	2         	74B1      	GND                 

C1035     	Q_CAP_C0402    	          	          	                    
          	               	1         	74B1      	PVCCIN_CPU0         
          	               	2         	74B1      	GND                 

C1036     	Q_CAP_C0402    	          	          	                    
          	               	1         	74B1      	PVCCIN_CPU0         
          	               	2         	74B1      	GND                 

C1037     	Q_CAP_C0402    	          	          	                    
          	               	1         	74B1      	PVCCIN_CPU0         
          	               	2         	74B1      	GND                 

C1038     	Q_CAP_C0402    	          	          	                    
          	               	1         	74B1      	PVCCIN_CPU0         
          	               	2         	74B1      	GND                 

C1039     	Q_CAP_C0402    	          	          	                    
          	               	1         	74B1      	PVCCIN_CPU0         
          	               	2         	74B1      	GND                 

C1040     	Q_CAP_C0402    	          	          	                    
          	               	1         	74B1      	PVCCIN_CPU0         
          	               	2         	74B1      	GND                 

C1041     	Q_CAP_C0402    	          	          	                    
          	               	1         	74B1      	PVCCIN_CPU0         
          	               	2         	74B1      	GND                 

C1042     	Q_CAP_C0402    	          	          	                    
          	               	1         	260B4     	P5V_AUX             
          	               	2         	260B4     	GND                 

C1043     	Q_CAP_C0402    	          	          	                    
          	               	1         	74B1      	PVCCIN_CPU0         
          	               	2         	74B1      	GND                 

C1044     	Q_CAP_C0402    	          	          	                    
          	               	1         	74B1      	PVCCIN_CPU0         
          	               	2         	74B1      	GND                 

C1045     	Q_CAP_C0402    	          	          	                    
          	               	1         	74B1      	PVCCIN_CPU0         
          	               	2         	74B1      	GND                 

C1096     	Q_CAP_C0201    	          	          	                    
          	               	1         	181B2     	USB3_PCH_TX_DP<4>   
          	               	2         	181B2     	USB3_PCH_TX_C_DP<4> 

C1097     	Q_CAP_C0201    	          	          	                    
          	               	1         	181B2     	USB3_PCH_TX_DN<4>   
          	               	2         	181B2     	USB3_PCH_TX_C_DN<4> 

C1098     	Q_CAP_DIFFBUS_C0201	          	          	                    
          	               	1         	181B2     	P3E_PCH_M2_TX_DP<3> 
          	               	2         	181B2     	P3E_PCH_M2_TX_C_DP<3>

C1099     	Q_CAP_DIFFBUS_C0201	          	          	                    
          	               	1         	181B2     	P3E_PCH_M2_TX_DN<3> 
          	               	2         	181B2     	P3E_PCH_M2_TX_C_DN<3>

C1100     	Q_CAP_DIFFBUS_C0201	          	          	                    
          	               	1         	181B2     	P3E_PCH_M2_TX_DP<2> 
          	               	2         	181B2     	P3E_PCH_M2_TX_C_DP<2>

C1101     	Q_CAP_DIFFBUS_C0201	          	          	                    
          	               	1         	181B2     	P3E_PCH_M2_TX_DN<2> 
          	               	2         	181B2     	P3E_PCH_M2_TX_C_DN<2>

C1102     	Q_CAP_DIFFBUS_C0201	          	          	                    
          	               	1         	181B2     	P3E_PCH_M2_TX_DP<1> 
          	               	2         	181B2     	P3E_PCH_M2_TX_C_DP<1>

C1103     	Q_CAP_DIFFBUS_C0201	          	          	                    
          	               	1         	181B2     	P3E_PCH_M2_TX_DN<1> 
          	               	2         	181B2     	P3E_PCH_M2_TX_C_DN<1>

C1104     	Q_CAP_DIFFBUS_C0201	          	          	                    
          	               	1         	181B2     	P3E_PCH_M2_TX_DP<0> 
          	               	2         	181B2     	P3E_PCH_M2_TX_C_DP<0>

C1105     	Q_CAP_DIFFBUS_C0201	          	          	                    
          	               	1         	181B2     	P3E_PCH_M2_TX_DN<0> 
          	               	2         	181B2     	P3E_PCH_M2_TX_C_DN<0>

C1113     	Q_CAP_C0402    	          	          	                    
          	               	1         	217A4     	P3V3_AUX_FPGA_VCCIO3
          	               	2         	217A4     	GND                 

C1118     	Q_CAP_C0402    	          	          	                    
          	               	1         	217A4     	P3V3_AUX_FPGA_VCCIO3
          	               	2         	217A4     	GND                 

C1122     	Q_CAP_0402     	          	          	                    
          	               	1         	217A2     	P3V3_AUX_FPGA_VCCIO2
          	               	2         	217A2     	GND                 

C1124     	Q_CAP_C0402    	          	          	                    
          	               	1         	217A4     	P3V3_AUX_FPGA_VCCIO3
          	               	2         	217A4     	GND                 

C1127     	Q_CAP_C0402    	          	          	                    
          	               	1         	217A2     	P3V3_AUX_FPGA_VCCIO2
          	               	2         	217A2     	GND                 

C1133     	Q_CAP_C0402    	          	          	                    
          	               	1         	217A1     	P3V3_AUX_FPGA_VCCIO2
          	               	2         	217A1     	GND                 

C1138     	Q_CAP_C0402    	          	          	                    
          	               	1         	217A1     	P3V3_AUX_FPGA_VCCIO2
          	               	2         	217A1     	GND                 

C1142     	Q_CAP_C0402    	          	          	                    
          	               	1         	217A1     	P3V3_AUX_FPGA_VCCIO2
          	               	2         	217A1     	GND                 

C1146     	Q_CAP_C0402    	          	          	                    
          	               	1         	217A1     	P3V3_AUX_FPGA_VCCIO2
          	               	2         	217A1     	GND                 

C1150     	Q_CAP_0402     	          	          	                    
          	               	1         	217B1     	VCC_PLD_CORE        
          	               	2         	217B1     	GND                 

C1152     	Q_CAP_C0402    	          	          	                    
          	               	1         	217B1     	VCC_PLD_CORE        
          	               	2         	217B1     	GND                 

C1154     	Q_CAP_C0402    	          	          	                    
          	               	1         	217B1     	VCC_PLD_CORE        
          	               	2         	217B1     	GND                 

C1170     	Q_CAP_C0805    	          	          	                    
          	               	1         	260B4     	P5V_AUX             
          	               	2         	260B4     	GND                 

C1171     	Q_CAP_C0805    	          	          	                    
          	               	1         	260B4     	P5V_AUX             
          	               	2         	260B4     	GND                 

C1172     	Q_CAP_C0402    	          	          	                    
          	               	1         	260A3     	P5V                 
          	               	2         	260A3     	GND                 

C1173     	Q_CAP_0402     	          	          	                    
          	               	1         	155B4     	P3V3_AUX            
          	               	2         	155B4     	GND                 

C1175     	Q_CAP_0402     	          	          	                    
          	               	1         	155B4     	P3V3_AUX            
          	               	2         	155B4     	GND                 

C1177     	Q_CAP_C0402    	          	          	                    
          	               	1         	201B2     	RST_RTCRST_N        
          	               	2         	201B2     	GND                 

C1178     	Q_CAP_C0603    	          	          	                    
          	               	1         	189B4     	P1V05_PCH_AUX       
          	               	2         	189B4     	GND                 

C1181     	Q_CAP_C0603    	          	          	                    
          	               	1         	189B4     	P1V8_PCH_AUX        
          	               	2         	189B4     	GND                 

C1182     	Q_CAP_C0603    	          	          	                    
          	               	1         	189B4     	P1V05_PCH_AUX       
          	               	2         	189B4     	GND                 

C1183     	Q_CAP_C0402    	          	          	                    
          	               	1         	189A4     	P1V05_PCH_AUX       
          	               	2         	189A4     	GND                 

C1184     	Q_CAP_C0603    	          	          	                    
          	               	1         	189A4     	P3V3_AUX            
          	               	2         	189A4     	GND                 

C1185     	Q_CAP_C0603    	          	          	                    
          	               	1         	189B4     	P1V05_PCH_AUX       
          	               	2         	189B4     	GND                 

C1186     	Q_CAP_C0603    	          	          	                    
          	               	1         	189B4     	P1V8_PCH_AUX        
          	               	2         	189B4     	GND                 

C1187     	Q_CAP_C0603    	          	          	                    
          	               	1         	189B4     	P1V05_PCH_AUX       
          	               	2         	189B4     	GND                 

C1189     	Q_CAP_C0402    	          	          	                    
          	               	1         	189A4     	P1V05_PCH_AUX       
          	               	2         	189A4     	GND                 

C1191     	Q_CAP_C0603    	          	          	                    
          	               	1         	189A4     	P3V3_AUX            
          	               	2         	189A4     	GND                 

C1192     	Q_CAP_C0603    	          	          	                    
          	               	1         	189B4     	P1V05_PCH_AUX       
          	               	2         	189B4     	GND                 

C1197     	Q_CAP_C0603    	          	          	                    
          	               	1         	189B4     	P1V8_PCH_AUX        
          	               	2         	189B4     	GND                 

C1198     	Q_CAP_C0603    	          	          	                    
          	               	1         	189B4     	P1V05_PCH_AUX       
          	               	2         	189B4     	GND                 

C1200     	Q_CAP_C0402    	          	          	                    
          	               	1         	189A4     	P1V05_PCH_AUX       
          	               	2         	189A4     	GND                 

C1201     	Q_CAP_C0603    	          	          	                    
          	               	1         	189A4     	P3V3_AUX            
          	               	2         	189A4     	GND                 

C1202     	Q_CAP_C0603    	          	          	                    
          	               	1         	189B4     	P1V8_PCH_AUX        
          	               	2         	189B4     	GND                 

C1203     	Q_CAP_C0402    	          	          	                    
          	               	1         	189B4     	P1V05_PCH_AUX       
          	               	2         	189B4     	GND                 

C1204     	Q_CAP_C0402    	          	          	                    
          	               	1         	189A4     	P1V05_PCH_AUX       
          	               	2         	189A4     	GND                 

C1205     	Q_CAP_C0402    	          	          	                    
          	               	1         	189B4     	P1V05_PCH_AUX       
          	               	2         	189B4     	GND                 

C1206     	Q_CAP_C0402    	          	          	                    
          	               	1         	189A4     	P3V3_AUX            
          	               	2         	189A4     	GND                 

C1207     	Q_CAP_C0402    	          	          	                    
          	               	1         	189B4     	P1V8_PCH_AUX        
          	               	2         	189B4     	GND                 

C1209     	Q_CAP_0402     	          	          	                    
          	               	1         	220A4     	PWRGD_SYS_PWROK_R   
          	               	2         	220A4     	GND                 

C1210     	Q_CAP_C0402    	          	          	                    
          	               	1         	189B4     	P1V05_PCH_AUX       
          	               	2         	189B4     	GND                 

C1211     	Q_CAP_0402     	          	          	                    
          	               	1         	220A4     	PWRGD_PCH_PWROK_R   
          	               	2         	220A4     	GND                 

C1213     	Q_CAP_C0805    	          	          	                    
          	               	1         	153A2     	P12V_OCP_SFF        
          	               	2         	153A2     	GND                 

C1214     	Q_CAP_C0402    	          	          	                    
          	               	1         	189A4     	P1V05_PCH_AUX       
          	               	2         	189A4     	GND                 

C1226     	Q_CAP_C0402    	          	          	                    
          	               	1         	260B3     	VR_P5V_EN_D_R       
          	               	2         	260B3     	GND                 

C1227     	Q_CAP_C0402    	          	          	                    
          	               	1         	260B3     	P5V                 
          	               	2         	260B3     	GND                 

C1228     	Q_CAP_C0402    	          	          	                    
          	               	1         	189B4     	P1V05_PCH_AUX       
          	               	2         	189B4     	GND                 

C1231     	Q_CAP_C0402    	          	          	                    
          	               	1         	189B4     	P1V05_PCH_AUX       
          	               	2         	189B4     	GND                 

C1232     	Q_CAP_C0805    	          	          	                    
          	               	1         	153A2     	P12V_OCP_SFF        
          	               	2         	153A2     	GND                 

C1233     	Q_CAP_0402     	          	          	                    
          	               	1         	153A2     	P12V_OCP_SFF        
          	               	2         	153A2     	GND                 

C1234     	Q_CAP_0402     	          	          	                    
          	               	1         	153A2     	P12V_OCP_SFF        
          	               	2         	153A2     	GND                 

C1235     	Q_CAP_0402     	          	          	                    
          	               	1         	153A2     	P12V_OCP_SFF        
          	               	2         	153A2     	GND                 

C1236     	Q_CAP_0402     	          	          	                    
          	               	1         	153A2     	P12V_OCP_SFF        
          	               	2         	153A2     	GND                 

C1237     	Q_CAP_0402     	          	          	                    
          	               	1         	153A1     	P3V3_OCP_SFF        
          	               	2         	153A1     	GND                 

C1238     	Q_CAP_0402     	          	          	                    
          	               	1         	153A1     	P3V3_OCP_SFF        
          	               	2         	153A1     	GND                 

C1239     	Q_CAP_0402     	          	          	                    
          	               	1         	153A1     	P3V3_OCP_SFF        
          	               	2         	153A1     	GND                 

C1240     	Q_CAP_0402     	          	          	                    
          	               	1         	153A1     	P3V3_OCP_SFF        
          	               	2         	153A1     	GND                 

C1242     	Q_CAP_C0402    	          	          	                    
          	               	1         	189A4     	P1V05_PCH_AUX       
          	               	2         	189A4     	GND                 

C1243     	Q_CAP_C0805    	          	          	                    
          	               	1         	189A4     	P3V3_AUX            
          	               	2         	189A4     	GND                 

C1244     	Q_CAP_C0805    	          	          	                    
          	               	1         	189B4     	P1V05_PCH_AUX       
          	               	2         	189B4     	GND                 

C1245     	Q_CAP_C0805    	          	          	                    
          	               	1         	189A3     	P3V3_AUX            
          	               	2         	189A3     	GND                 

C1246     	Q_CAP_C0805    	          	          	                    
          	               	1         	189B3     	P1V05_PCH_AUX       
          	               	2         	189B3     	GND                 

C1247     	Q_CAP_C0805    	          	          	                    
          	               	1         	189B3     	P1V05_PCH_AUX       
          	               	2         	189B3     	GND                 

C1248     	Q_CAP_C0805    	          	          	                    
          	               	1         	189B3     	P1V05_PCH_AUX       
          	               	2         	189B3     	GND                 

C1249     	Q_CAP_C0805    	          	          	                    
          	               	1         	189B3     	P1V05_PCH_AUX       
          	               	2         	189B3     	GND                 

C1250     	Q_CAP_0402     	          	          	                    
          	               	1         	189B3     	P1V05_PCH_AUX       
          	               	2         	189B3     	GND                 

C1251     	Q_CAP_C0603    	          	          	                    
          	               	1         	189B3     	P1V05_PCH_PLL_AUX   
          	               	2         	189B3     	GND                 

C1252     	Q_CAP_C0603    	          	          	                    
          	               	1         	189A2     	P1V8_PCH_PLL_AUX    
          	               	2         	189A2     	GND                 

C1253     	Q_CAP_0402     	          	          	                    
          	               	1         	189B2     	P1V8_PCH_AUX        
          	               	2         	189B2     	GND                 

C1254     	Q_CAP_C0603    	          	          	                    
          	               	1         	189B2     	P1V05_PCH_PLL_AUX   
          	               	2         	189B2     	GND                 

C1255     	Q_CAP_C0603    	          	          	                    
          	               	1         	189A2     	P1V8_PCH_PLL_AUX    
          	               	2         	189A2     	GND                 

C1256     	Q_CAP_0402     	          	          	                    
          	               	1         	189B2     	P1V05_PCH_PLL_AUX   
          	               	2         	189B2     	GND                 

C1257     	Q_CAP_0402     	          	          	                    
          	               	1         	189B2     	P1V8_PCH_PLL_AUX    
          	               	2         	189B2     	GND                 

C1258     	Q_CAP_C0805    	          	          	                    
          	               	1         	189B2     	P1V05_PCH_PLL_AUX   
          	               	2         	189B2     	GND                 

C1259     	Q_CAP_C0805    	          	          	                    
          	               	1         	189A2     	P1V8_PCH_PLL_AUX    
          	               	2         	189A2     	GND                 

C1260     	Q_CAP_C0603    	          	          	                    
          	               	1         	189B2     	P1V05_PCH_PLL_AUX   
          	               	2         	189B2     	GND                 

C1261     	Q_CAP_C0603    	          	          	                    
          	               	1         	189B2     	P1V8_PCH_PLL_AUX    
          	               	2         	189B2     	GND                 

C1262     	Q_CAP_C0402    	          	          	                    
          	               	1         	189B2     	P1V05_PCH_PLL_AUX   
          	               	2         	189B2     	GND                 

C1263     	Q_CAP_C0402    	          	          	                    
          	               	1         	189A2     	P1V8_PCH_PLL_AUX    
          	               	2         	189A2     	GND                 

C1264     	Q_CAP_0402     	          	          	                    
          	               	1         	189B2     	P1V05_PCH_PLL_AUX   
          	               	2         	189B2     	GND                 

C1265     	Q_CAP_0402     	          	          	                    
          	               	1         	189B2     	P1V8_PCH_PLL_AUX    
          	               	2         	189B2     	GND                 

C1266     	Q_CAP_C0402    	          	          	                    
          	               	1         	189A2     	P1V8_PCH_PLL_AUX    
          	               	2         	189A2     	GND                 

C1272     	Q_CAP_C0805    	          	          	                    
          	               	1         	189B1     	P1V05_PCH_PLL_AUX   
          	               	2         	189B1     	GND                 

C1273     	Q_CAP_C0805    	          	          	                    
          	               	1         	189A1     	P1V8_PCH_PLL_AUX    
          	               	2         	189A1     	GND                 

C1274     	Q_CAP_0402     	          	          	                    
          	               	1         	155A4     	P3V3_AUX            
          	               	2         	155A4     	GND                 

C1275     	Q_CAP_0402     	          	          	                    
          	               	1         	155A3     	P3V3_AUX            
          	               	2         	155A3     	GND                 

C1276     	Q_CAP_C0805    	          	          	                    
          	               	1         	191B2     	P12V_E1S_0          
          	               	2         	191B2     	GND                 

C1277     	Q_CAP_C0805    	          	          	                    
          	               	1         	191B2     	P12V_E1S_0          
          	               	2         	191B2     	GND                 

C1278     	Q_CAP_0402     	          	          	                    
          	               	1         	191B2     	P12V_E1S_0          
          	               	2         	191B2     	GND                 

C1279     	Q_CAP_0402     	          	          	                    
          	               	1         	191B1     	P12V_E1S_0          
          	               	2         	191B1     	GND                 

C1282     	Q_CAP_0402     	          	          	                    
          	               	1         	191B1     	P3V3_E1S_0          
          	               	2         	191B1     	GND                 

C1283     	Q_CAP_0402     	          	          	                    
          	               	1         	191B1     	P3V3_E1S_0          
          	               	2         	191B1     	GND                 

C1288     	Q_CAP_0402     	          	          	                    
          	               	1         	134B4     	P3V3_AUX            
          	               	2         	134B4     	GND                 

C1289     	Q_CAP_C0402    	          	          	                    
          	               	1         	134B4     	P3V3_AUX            
          	               	2         	134B4     	GND                 

C1290     	Q_CAP_C0402    	          	          	                    
          	               	1         	239B3     	P3V3_AUX            
          	               	2         	239B3     	GND                 

C1291     	Q_CAP_C0402    	          	          	                    
          	               	1         	239B3     	P3V3_AUX            
          	               	2         	239B3     	GND                 

C1292     	Q_CAP_0402     	          	          	                    
          	               	1         	134B2     	P3V3_AUX            
          	               	2         	134B2     	GND                 

C1293     	Q_CAP_C0402    	          	          	                    
          	               	1         	134B3     	FM_BMC_EN_DET       
          	               	2         	134B3     	GND                 

C1296     	Q_CAP_0402     	          	          	                    
          	               	1         	282B2     	PWRGD_PVNN_MAIN_CPU0
          	               	2         	282B2     	GND                 

C1297     	Q_CAP_0402     	          	          	                    
          	               	1         	300B2     	PWRGD_PVNN_MAIN_CPU1
          	               	2         	300B2     	GND                 

C1300     	Q_CAP_0402     	          	          	                    
          	               	1         	281B4     	FM_PVPP_HBM_CPU0_EN 
          	               	2         	281B4     	GND                 

C1301     	Q_CAP_0402     	          	          	                    
          	               	1         	281B2     	PWRGD_PVPP_HBM_CPU0_R
          	               	2         	281B2     	GND                 

C1302     	Q_CAP_C0402    	          	          	                    
          	               	1         	240B4     	PVNN_TERM_CPU0      
          	               	2         	240B4     	GND                 

C1305     	Q_CAP_0402     	          	          	                    
          	               	1         	194B4     	P3V3_AUX            
          	               	2         	194B4     	GND                 

C1307     	Q_CAP_0402     	          	          	                    
          	               	1         	282B4     	FM_PVNN_MAIN_CPU0_EN
          	               	2         	282B4     	GND                 

C1308     	Q_CAP_0402     	          	          	                    
          	               	1         	300B4     	FM_PVNN_MAIN_CPU1_EN
          	               	2         	300A4     	GND                 

C1309     	Q_CAP_C0603    	          	          	                    
          	               	1         	210B4     	P3V3_AUX_CLK_GEN_VDDXTAL_CK440
          	               	2         	210B4     	GND                 

C1310     	Q_CAP_C0603    	          	          	                    
          	               	1         	210B4     	P3V3_AUX_CLK_GEN_VDDMXCK_CK440
          	               	2         	210A4     	GND                 

C1311     	Q_CAP_C0402    	          	          	                    
          	               	1         	210B4     	P3V3_AUX_CLK_GEN_VDDXTAL_CK440
          	               	2         	210B4     	GND                 

C1312     	Q_CAP_C0402    	          	          	                    
          	               	1         	210B4     	P3V3_AUX_CLK_GEN_VDDMXCK_CK440
          	               	2         	210A4     	GND                 

C1313     	Q_CAP_C0603    	          	          	                    
          	               	1         	210B3     	P3V3_AUX_CLK_GEN_VDDA25M_CK440
          	               	2         	210B3     	GND                 

C1314     	Q_CAP_C0603    	          	          	                    
          	               	1         	210B3     	P3V3_AUX_CLK_GEN_VDDPT_CK440
          	               	2         	210A3     	GND                 

C1315     	Q_CAP_C0402    	          	          	                    
          	               	1         	244B3     	P3V3_AUX            
          	               	2         	244B3     	GND                 

C1316     	Q_CAP_C0402    	          	          	                    
          	               	1         	244B2     	FM_COMP_P3V3_STBY_CEXT
          	               	2         	244B2     	GND                 

C1317     	Q_CAP_0402     	          	          	                    
          	               	1         	244A4     	P3V3_AUX            
          	               	2         	244A4     	GND                 

C1318     	Q_CAP_C0402    	          	          	                    
          	               	1         	244A4     	PWRGD_DSW_PWROK_R1  
          	               	2         	244A4     	GND                 

C1319     	Q_CAP_C0402    	          	          	                    
          	               	1         	244A2     	PWRGD_DSW_PWROK     
          	               	2         	244A2     	GND                 

C1320     	Q_CAP_0402     	          	          	                    
          	               	1         	214A4     	P3V3_AUX            
          	               	2         	214A4     	GND                 

C1321     	Q_CAP_0402     	          	          	                    
          	               	1         	239B3     	P3V3_AUX            
          	               	2         	239A3     	GND                 

C1322     	Q_CAP_0402     	          	          	                    
          	               	1         	239B1     	P3V3_AUX            
          	               	2         	239A1     	GND                 

C1323     	Q_CAP_0402     	          	          	                    
          	               	1         	194B3     	P1V8_PCH_AUX        
          	               	2         	194B3     	GND                 

C1324     	Q_CAP_0402     	          	          	                    
          	               	1         	208A3     	FM_CK440Q_DEV_25M_EN
          	               	2         	208A3     	GND                 

C1325     	Q_CAP_0402     	          	          	                    
          	               	1         	215B2     	FM_PLD_REV_N        
          	               	2         	215B2     	GND                 

C1331     	Q_CAP_C0805    	          	          	                    
          	               	1         	260B3     	P5V                 
          	               	2         	260B3     	GND                 

C1332     	Q_CAP_C0402    	          	          	                    
          	               	1         	260B2     	P3V3_AUX            
          	               	2         	260B2     	GND                 

C1333     	Q_CAP_C0805    	          	          	                    
          	               	1         	260B2     	P3V3_AUX            
          	               	2         	260B2     	GND                 

C1336     	Q_CAP_C0402    	          	          	                    
          	               	1         	296B4     	PVNN_TERM_CPU1      
          	               	2         	296B4     	GND                 

C1337     	Q_CAP_0402     	          	          	                    
          	               	1         	296B4     	PVNN_TERM_CPU1      
          	               	2         	296B4     	GND                 

C1338     	Q_CAP_C0805    	          	          	                    
          	               	1         	260B1     	P3V3_AUX            
          	               	2         	260B1     	GND                 

C1339     	Q_CAP_C0402    	          	          	                    
          	               	1         	260B1     	P3V3                
          	               	2         	260B1     	GND                 

C1340     	Q_CAP_C0805    	          	          	                    
          	               	1         	260B1     	P3V3                
          	               	2         	260B1     	GND                 

C1344     	Q_CAP_0402     	          	          	                    
          	               	1         	250A4     	P12V_AUX_ADC_MAM    
          	               	2         	250A4     	GND                 

C1347     	Q_CAP_0402     	          	          	                    
          	               	1         	250B3     	MAX11617_VREF       
          	               	2         	250B3     	GND                 

C1353     	Q_CAP_C0402    	          	          	                    
          	               	1         	79B3      	PVNN_MAIN_CPU1      
          	               	2         	79B3      	GND                 

C1362     	Q_CAP_C0402    	          	          	                    
          	               	1         	76B4      	PVNN_MAIN_CPU0      
          	               	2         	76B4      	GND                 

C1363     	Q_CAP_C0402    	          	          	                    
          	               	1         	80B4      	PVNN_MAIN_CPU0      
          	               	2         	80B4      	GND                 

C1364     	Q_CAP_C0402    	          	          	                    
          	               	1         	80B4      	PVNN_MAIN_CPU0      
          	               	2         	80B4      	GND                 

C1365     	Q_CAP_C0402    	          	          	                    
          	               	1         	80B3      	PVNN_MAIN_CPU1      
          	               	2         	80B3      	GND                 

C1366     	Q_CAP_C0402    	          	          	                    
          	               	1         	80B2      	PVNN_MAIN_CPU1      
          	               	2         	80B2      	GND                 

C1387     	Q_CAP_C0805    	          	          	                    
          	               	1         	78B3      	PVNN_MAIN_CPU1      
          	               	2         	78B3      	GND                 

C1388     	Q_CAP_C0805    	          	          	                    
          	               	1         	78A3      	PVPP_HBM_CPU1       
          	               	2         	78A3      	GND                 

C1389     	Q_CAP_C0603    	          	          	                    
          	               	1         	78B3      	PVNN_MAIN_CPU1      
          	               	2         	78B3      	GND                 

C1390     	Q_CAP_C0805    	          	          	                    
          	               	1         	78A3      	PVPP_HBM_CPU1       
          	               	2         	78A3      	GND                 

C1391     	Q_CAP_C0603    	          	          	                    
          	               	1         	78B2      	PVNN_MAIN_CPU1      
          	               	2         	78B2      	GND                 

C1392     	Q_CAP_C0805    	          	          	                    
          	               	1         	78A2      	PVPP_HBM_CPU1       
          	               	2         	78A2      	GND                 

C1393     	Q_CAP_C0603    	          	          	                    
          	               	1         	78B2      	PVNN_MAIN_CPU1      
          	               	2         	78B2      	GND                 

C1396     	Q_CAP_C0805    	          	          	                    
          	               	1         	75A3      	PVPP_HBM_CPU0       
          	               	2         	75A3      	GND                 

C1397     	Q_CAP_C0805    	          	          	                    
          	               	1         	75A2      	PVPP_HBM_CPU0       
          	               	2         	75A2      	GND                 

C1398     	Q_CAP_C0805    	          	          	                    
          	               	1         	75A2      	PVPP_HBM_CPU0       
          	               	2         	75A2      	GND                 

C1399     	Q_CAP_C0805    	          	          	                    
          	               	1         	76B4      	PVNN_MAIN_CPU0      
          	               	2         	76B4      	GND                 

C1400     	Q_CAP_C0805    	          	          	                    
          	               	1         	76B4      	PVNN_MAIN_CPU0      
          	               	2         	76B4      	GND                 

C1403     	Q_CAP_C0805    	          	          	                    
          	               	1         	79B3      	PVNN_MAIN_CPU1      
          	               	2         	79B3      	GND                 

C1404     	Q_CAP_C0805    	          	          	                    
          	               	1         	79B3      	PVNN_MAIN_CPU1      
          	               	2         	79B3      	GND                 

C1405     	Q_CAP_C0603    	          	          	                    
          	               	1         	75B2      	PVNN_MAIN_CPU0      
          	               	2         	75B2      	GND                 

C1406     	Q_CAP_C0603    	          	          	                    
          	               	1         	75B2      	PVNN_MAIN_CPU0      
          	               	2         	75B2      	GND                 

C1407     	Q_CAP_C0603    	          	          	                    
          	               	1         	75B2      	PVNN_MAIN_CPU0      
          	               	2         	75B2      	GND                 

C1409     	Q_CAP_C0603    	          	          	                    
          	               	1         	206B4     	P3V3_DB2000_VDD     
          	               	2         	206B4     	GND                 

C1436     	Q_CAP_C0201    	          	          	                    
          	               	1         	75A2      	PVPP_HBM_CPU0       
          	               	2         	75A2      	GND                 

C1437     	Q_CAP_C0201    	          	          	                    
          	               	1         	78A2      	PVPP_HBM_CPU1       
          	               	2         	78A2      	GND                 

C1507     	Q_CAP_0402     	          	          	                    
          	               	1         	179A3     	XTAL_PCH_RTC2_R     
          	               	2         	179A3     	GND                 

C1508     	Q_CAP_0402     	          	          	                    
          	               	1         	179A2     	XTAL_PCH_RTC1       
          	               	2         	179A2     	GND                 

C1516     	Q_CAP_DIFFBUS_C0201	          	          	                    
          	               	1         	177B4     	P5E_CPU1_PE3_TX_C_DN<15>
          	               	2         	177B4     	P5E_CPU1_PE3_TX_DN<15>

C1517     	Q_CAP_DIFFBUS_C0201	          	          	                    
          	               	1         	177B4     	P5E_CPU1_PE3_TX_C_DP<15>
          	               	2         	177B4     	P5E_CPU1_PE3_TX_DP<15>

C1518     	Q_CAP_DIFFBUS_C0201	          	          	                    
          	               	1         	177B4     	P5E_CPU1_PE3_TX_C_DN<14>
          	               	2         	177B4     	P5E_CPU1_PE3_TX_DN<14>

C1519     	Q_CAP_DIFFBUS_C0201	          	          	                    
          	               	1         	177B4     	P5E_CPU1_PE3_TX_C_DP<14>
          	               	2         	177B4     	P5E_CPU1_PE3_TX_DP<14>

C1520     	Q_CAP_DIFFBUS_C0201	          	          	                    
          	               	1         	177B4     	P5E_CPU1_PE3_TX_C_DN<13>
          	               	2         	177B4     	P5E_CPU1_PE3_TX_DN<13>

C1521     	Q_CAP_DIFFBUS_C0201	          	          	                    
          	               	1         	177B4     	P5E_CPU1_PE3_TX_C_DP<13>
          	               	2         	177B4     	P5E_CPU1_PE3_TX_DP<13>

C1522     	Q_CAP_DIFFBUS_C0201	          	          	                    
          	               	1         	177B4     	P5E_CPU1_PE3_TX_C_DN<12>
          	               	2         	177B4     	P5E_CPU1_PE3_TX_DN<12>

C1523     	Q_CAP_DIFFBUS_C0201	          	          	                    
          	               	1         	177B4     	P5E_CPU1_PE3_TX_C_DP<12>
          	               	2         	177B4     	P5E_CPU1_PE3_TX_DP<12>

C1524     	Q_CAP_DIFFBUS_C0201	          	          	                    
          	               	1         	177B4     	P5E_CPU1_PE3_TX_C_DN<11>
          	               	2         	177B4     	P5E_CPU1_PE3_TX_DN<11>

C1525     	Q_CAP_DIFFBUS_C0201	          	          	                    
          	               	1         	177B4     	P5E_CPU1_PE3_TX_C_DP<11>
          	               	2         	177B4     	P5E_CPU1_PE3_TX_DP<11>

C1526     	Q_CAP_DIFFBUS_C0201	          	          	                    
          	               	1         	177B4     	P5E_CPU1_PE3_TX_C_DN<10>
          	               	2         	177B4     	P5E_CPU1_PE3_TX_DN<10>

C1527     	Q_CAP_DIFFBUS_C0201	          	          	                    
          	               	1         	177B4     	P5E_CPU1_PE3_TX_C_DP<10>
          	               	2         	177B4     	P5E_CPU1_PE3_TX_DP<10>

C1528     	Q_CAP_DIFFBUS_C0201	          	          	                    
          	               	1         	177B4     	P5E_CPU1_PE3_TX_C_DN<9>
          	               	2         	177B4     	P5E_CPU1_PE3_TX_DN<9>

C1529     	Q_CAP_DIFFBUS_C0201	          	          	                    
          	               	1         	177B4     	P5E_CPU1_PE3_TX_C_DP<9>
          	               	2         	177B4     	P5E_CPU1_PE3_TX_DP<9>

C1530     	Q_CAP_DIFFBUS_C0201	          	          	                    
          	               	1         	177B4     	P5E_CPU1_PE3_TX_C_DN<8>
          	               	2         	177B4     	P5E_CPU1_PE3_TX_DN<8>

C1531     	Q_CAP_DIFFBUS_C0201	          	          	                    
          	               	1         	177B4     	P5E_CPU1_PE3_TX_C_DP<8>
          	               	2         	177B4     	P5E_CPU1_PE3_TX_DP<8>

C1532     	Q_CAP_DIFFBUS_C0201	          	          	                    
          	               	1         	177B4     	P5E_CPU1_PE3_TX_C_DN<7>
          	               	2         	177B4     	P5E_CPU1_PE3_TX_DN<7>

C1533     	Q_CAP_DIFFBUS_C0201	          	          	                    
          	               	1         	177B4     	P5E_CPU1_PE3_TX_C_DP<7>
          	               	2         	177B4     	P5E_CPU1_PE3_TX_DP<7>

C1534     	Q_CAP_DIFFBUS_C0201	          	          	                    
          	               	1         	177B4     	P5E_CPU1_PE3_TX_C_DN<6>
          	               	2         	177B4     	P5E_CPU1_PE3_TX_DN<6>

C1535     	Q_CAP_DIFFBUS_C0201	          	          	                    
          	               	1         	177B4     	P5E_CPU1_PE3_TX_C_DP<6>
          	               	2         	177B4     	P5E_CPU1_PE3_TX_DP<6>

C1536     	Q_CAP_DIFFBUS_C0201	          	          	                    
          	               	1         	177B4     	P5E_CPU1_PE3_TX_C_DN<5>
          	               	2         	177B4     	P5E_CPU1_PE3_TX_DN<5>

C1537     	Q_CAP_DIFFBUS_C0201	          	          	                    
          	               	1         	177B4     	P5E_CPU1_PE3_TX_C_DP<5>
          	               	2         	177B4     	P5E_CPU1_PE3_TX_DP<5>

C1538     	Q_CAP_DIFFBUS_C0201	          	          	                    
          	               	1         	177B4     	P5E_CPU1_PE3_TX_C_DN<4>
          	               	2         	177B4     	P5E_CPU1_PE3_TX_DN<4>

C1539     	Q_CAP_DIFFBUS_C0201	          	          	                    
          	               	1         	177B4     	P5E_CPU1_PE3_TX_C_DP<4>
          	               	2         	177B4     	P5E_CPU1_PE3_TX_DP<4>

C1540     	Q_CAP_DIFFBUS_C0201	          	          	                    
          	               	1         	177B4     	P5E_CPU1_PE3_TX_C_DN<3>
          	               	2         	177B4     	P5E_CPU1_PE3_TX_DN<3>

C1541     	Q_CAP_DIFFBUS_C0201	          	          	                    
          	               	1         	177A4     	P5E_CPU1_PE3_TX_C_DP<3>
          	               	2         	177A4     	P5E_CPU1_PE3_TX_DP<3>

C1542     	Q_CAP_DIFFBUS_C0201	          	          	                    
          	               	1         	177A4     	P5E_CPU1_PE3_TX_C_DN<2>
          	               	2         	177A4     	P5E_CPU1_PE3_TX_DN<2>

C1543     	Q_CAP_DIFFBUS_C0201	          	          	                    
          	               	1         	177A4     	P5E_CPU1_PE3_TX_C_DP<2>
          	               	2         	177A4     	P5E_CPU1_PE3_TX_DP<2>

C1544     	Q_CAP_DIFFBUS_C0201	          	          	                    
          	               	1         	177A4     	P5E_CPU1_PE3_TX_C_DN<1>
          	               	2         	177A4     	P5E_CPU1_PE3_TX_DN<1>

C1545     	Q_CAP_DIFFBUS_C0201	          	          	                    
          	               	1         	177A4     	P5E_CPU1_PE3_TX_C_DP<1>
          	               	2         	177A4     	P5E_CPU1_PE3_TX_DP<1>

C1546     	Q_CAP_DIFFBUS_C0201	          	          	                    
          	               	1         	177A4     	P5E_CPU1_PE3_TX_C_DN<0>
          	               	2         	177A4     	P5E_CPU1_PE3_TX_DN<0>

C1547     	Q_CAP_DIFFBUS_C0201	          	          	                    
          	               	1         	177A4     	P5E_CPU1_PE3_TX_C_DP<0>
          	               	2         	177A4     	P5E_CPU1_PE3_TX_DP<0>

C1548     	Q_CAP_DIFFBUS_C0201	          	          	                    
          	               	1         	175B4     	P5E_CPU0_PE4_TX_C_DN<15>
          	               	2         	175B4     	P5E_CPU0_PE4_TX_DN<15>

C1549     	Q_CAP_DIFFBUS_C0201	          	          	                    
          	               	1         	175B4     	P5E_CPU0_PE4_TX_C_DP<15>
          	               	2         	175B4     	P5E_CPU0_PE4_TX_DP<15>

C1550     	Q_CAP_DIFFBUS_C0201	          	          	                    
          	               	1         	175B4     	P5E_CPU0_PE4_TX_C_DN<14>
          	               	2         	175B4     	P5E_CPU0_PE4_TX_DN<14>

C1552     	Q_CAP_DIFFBUS_C0201	          	          	                    
          	               	1         	175B4     	P5E_CPU0_PE4_TX_C_DN<13>
          	               	2         	175B4     	P5E_CPU0_PE4_TX_DN<13>

C1553     	Q_CAP_DIFFBUS_C0201	          	          	                    
          	               	1         	175B4     	P5E_CPU0_PE4_TX_C_DP<13>
          	               	2         	175B4     	P5E_CPU0_PE4_TX_DP<13>

C1554     	Q_CAP_DIFFBUS_C0201	          	          	                    
          	               	1         	175B4     	P5E_CPU0_PE4_TX_C_DN<12>
          	               	2         	175B4     	P5E_CPU0_PE4_TX_DN<12>

C1555     	Q_CAP_DIFFBUS_C0201	          	          	                    
          	               	1         	175B4     	P5E_CPU0_PE4_TX_C_DP<12>
          	               	2         	175B4     	P5E_CPU0_PE4_TX_DP<12>

C1556     	Q_CAP_DIFFBUS_C0201	          	          	                    
          	               	1         	175B4     	P5E_CPU0_PE4_TX_C_DN<11>
          	               	2         	175B4     	P5E_CPU0_PE4_TX_DN<11>

C1557     	Q_CAP_DIFFBUS_C0201	          	          	                    
          	               	1         	175B4     	P5E_CPU0_PE4_TX_C_DP<11>
          	               	2         	175B4     	P5E_CPU0_PE4_TX_DP<11>

C1558     	Q_CAP_DIFFBUS_C0201	          	          	                    
          	               	1         	175B4     	P5E_CPU0_PE4_TX_C_DN<10>
          	               	2         	175B4     	P5E_CPU0_PE4_TX_DN<10>

C1559     	Q_CAP_DIFFBUS_C0201	          	          	                    
          	               	1         	175B4     	P5E_CPU0_PE4_TX_C_DP<10>
          	               	2         	175B4     	P5E_CPU0_PE4_TX_DP<10>

C1560     	Q_CAP_DIFFBUS_C0201	          	          	                    
          	               	1         	175B4     	P5E_CPU0_PE4_TX_C_DN<9>
          	               	2         	175B4     	P5E_CPU0_PE4_TX_DN<9>

C1561     	Q_CAP_C0402    	          	          	                    
          	               	1         	306A3     	U206_VDD            
          	               	2         	306A3     	GND                 

C1562     	Q_CAP_C0402    	          	          	                    
          	               	1         	306A4     	U205_VDD            
          	               	2         	306A4     	GND                 

C1563     	Q_CAP_DIFFBUS_C0201	          	          	                    
          	               	1         	175B4     	P5E_CPU0_PE4_TX_C_DP<8>
          	               	2         	175B4     	P5E_CPU0_PE4_TX_DP<8>

C1564     	Q_CAP_DIFFBUS_C0201	          	          	                    
          	               	1         	175B4     	P5E_CPU0_PE4_TX_C_DN<7>
          	               	2         	175B4     	P5E_CPU0_PE4_TX_DN<7>

C1565     	Q_CAP_DIFFBUS_C0201	          	          	                    
          	               	1         	175B4     	P5E_CPU0_PE4_TX_C_DP<7>
          	               	2         	175B4     	P5E_CPU0_PE4_TX_DP<7>

C1566     	Q_CAP_DIFFBUS_C0201	          	          	                    
          	               	1         	175B4     	P5E_CPU0_PE4_TX_C_DN<6>
          	               	2         	175B4     	P5E_CPU0_PE4_TX_DN<6>

C1567     	Q_CAP_DIFFBUS_C0201	          	          	                    
          	               	1         	175B4     	P5E_CPU0_PE4_TX_C_DP<6>
          	               	2         	175B4     	P5E_CPU0_PE4_TX_DP<6>

C1568     	Q_CAP_DIFFBUS_C0201	          	          	                    
          	               	1         	175B4     	P5E_CPU0_PE4_TX_C_DN<5>
          	               	2         	175B4     	P5E_CPU0_PE4_TX_DN<5>

C1569     	Q_CAP_DIFFBUS_C0201	          	          	                    
          	               	1         	175B4     	P5E_CPU0_PE4_TX_C_DP<5>
          	               	2         	175B4     	P5E_CPU0_PE4_TX_DP<5>

C1570     	Q_CAP_DIFFBUS_C0201	          	          	                    
          	               	1         	175B4     	P5E_CPU0_PE4_TX_C_DN<4>
          	               	2         	175B4     	P5E_CPU0_PE4_TX_DN<4>

C1571     	Q_CAP_DIFFBUS_C0201	          	          	                    
          	               	1         	175B4     	P5E_CPU0_PE4_TX_C_DP<4>
          	               	2         	175B4     	P5E_CPU0_PE4_TX_DP<4>

C1572     	Q_CAP_DIFFBUS_C0201	          	          	                    
          	               	1         	175B4     	P5E_CPU0_PE4_TX_C_DN<3>
          	               	2         	175B4     	P5E_CPU0_PE4_TX_DN<3>

C1573     	Q_CAP_DIFFBUS_C0201	          	          	                    
          	               	1         	175A4     	P5E_CPU0_PE4_TX_C_DP<3>
          	               	2         	175A4     	P5E_CPU0_PE4_TX_DP<3>

C1574     	Q_CAP_DIFFBUS_C0201	          	          	                    
          	               	1         	175A4     	P5E_CPU0_PE4_TX_C_DN<2>
          	               	2         	175A4     	P5E_CPU0_PE4_TX_DN<2>

C1575     	Q_CAP_DIFFBUS_C0201	          	          	                    
          	               	1         	175A4     	P5E_CPU0_PE4_TX_C_DP<2>
          	               	2         	175A4     	P5E_CPU0_PE4_TX_DP<2>

C1576     	Q_CAP_DIFFBUS_C0201	          	          	                    
          	               	1         	175A4     	P5E_CPU0_PE4_TX_C_DN<1>
          	               	2         	175A4     	P5E_CPU0_PE4_TX_DN<1>

C1577     	Q_CAP_DIFFBUS_C0201	          	          	                    
          	               	1         	175A4     	P5E_CPU0_PE4_TX_C_DP<1>
          	               	2         	175A4     	P5E_CPU0_PE4_TX_DP<1>

C1578     	Q_CAP_DIFFBUS_C0201	          	          	                    
          	               	1         	175A4     	P5E_CPU0_PE4_TX_C_DN<0>
          	               	2         	175A4     	P5E_CPU0_PE4_TX_DN<0>

C1579     	Q_CAP_DIFFBUS_C0201	          	          	                    
          	               	1         	175A4     	P5E_CPU0_PE4_TX_C_DP<0>
          	               	2         	175A4     	P5E_CPU0_PE4_TX_DP<0>

C1592     	Q_CAP_0402     	          	          	                    
          	               	1         	191A3     	P3V3_AUX            
          	               	2         	191A3     	GND                 

C1612     	Q_CAP_C0402    	          	          	                    
          	               	1         	197B2     	P3V3_AUX            
          	               	2         	197B2     	GND                 

C1613     	Q_CAP_0402     	          	          	                    
          	               	1         	236B3     	P3V3_AUX            
          	               	2         	236B3     	GND                 

C1614     	Q_CAP_0402     	          	          	                    
          	               	1         	191B1     	P3V3_AUX            
          	               	2         	191B1     	GND                 

C1619     	Q_CAP_0402     	          	          	                    
          	               	1         	224B3     	P3V3_AUX            
          	               	2         	224B3     	GND                 

C1647     	Q_CAP_0402     	          	          	                    
          	               	1         	202B3     	P3V3_AUX            
          	               	2         	202B3     	GND                 

C1663     	Q_CAP_0402     	          	          	                    
          	               	1         	155B2     	P3V3_AUX            
          	               	2         	155B2     	GND                 

C1664     	Q_CAP_0402     	          	          	                    
          	               	1         	239B2     	P0V7_JTAG_VREF_2    
          	               	2         	239B2     	GND                 

C1707     	Q_CAP_0402     	          	          	                    
          	               	1         	234B3     	P3V3_AUX            
          	               	2         	234B3     	GND                 

C1708     	Q_CAP_0402     	          	          	                    
          	               	1         	234A2     	P3V3_AUX            
          	               	2         	234A2     	GND                 

C1713     	Q_CAP_0402     	          	          	                    
          	               	1         	227B2     	P3V3_AUX            
          	               	2         	227B2     	GND                 

C1751     	Q_CAP_0402     	          	          	                    
          	               	1         	245A2     	P3V3_AUX            
          	               	2         	245A2     	GND                 

C1754     	Q_CAP_0402     	          	          	                    
          	               	1         	148B3     	FM_SWB_BIC_READY_ISO_N
          	               	2         	148B3     	GND                 

C1756     	Q_CAP_0402     	          	          	                    
          	               	1         	148B1     	FM_GPU_PWRGD_ISO    
          	               	2         	148B1     	GND                 

C1757     	Q_CAP_0402     	          	          	                    
          	               	1         	250B1     	P3V3_MAX11617_VDD   
          	               	2         	250B1     	GND                 

C1766     	Q_CAP_0402     	          	          	                    
          	               	1         	234B2     	P3V3_AUX            
          	               	2         	234B2     	GND                 

C1767     	Q_CAP_C0805    	          	          	                    
          	               	1         	250B2     	MAX11617_VREF       
          	               	2         	250B2     	GND                 

C1768     	Q_CAP_C0805    	          	          	                    
          	               	1         	250B1     	P3V3_MAX11617_VDD   
          	               	2         	250B1     	GND                 

C1769     	Q_CAP_0402     	          	          	                    
          	               	1         	151B3     	P3V3_AUX            
          	               	2         	151B3     	GND                 

C1770     	Q_CAP_0402     	          	          	                    
          	               	1         	151B3     	P3V3_AUX            
          	               	2         	151B3     	GND                 

C1772     	Q_CAP_0402     	          	          	                    
          	               	1         	148B3     	RST_BMC_FROM_SWB_ISO_N
          	               	2         	148B3     	GND                 

C1773     	Q_CAP_0402     	          	          	                    
          	               	1         	148B3     	BIC_MONITER_ISO     
          	               	2         	148B3     	GND                 

C1774     	Q_CAP_0402     	          	          	                    
          	               	1         	148B1     	FM_SWB_PWRGD_ISO    
          	               	2         	148B1     	GND                 

C1775     	Q_CAP_0402     	          	          	                    
          	               	1         	246B3     	P3V3_AUX            
          	               	2         	246B3     	GND                 

C1791     	Q_CAP_DIFFBUS_C0201	          	          	                    
          	               	1         	178B3     	DMI_CPU0_PCH_TX_C_DP<7>
          	               	2         	178B3     	DMI_CPU0_PCH_TX_DP<7>

C1792     	Q_CAP_DIFFBUS_C0201	          	          	                    
          	               	1         	175B4     	P5E_CPU0_PE4_TX_C_DP<14>
          	               	2         	175B4     	P5E_CPU0_PE4_TX_DP<14>

C1793     	Q_CAP_DIFFBUS_C0201	          	          	                    
          	               	1         	175B4     	P5E_CPU0_PE4_TX_C_DP<9>
          	               	2         	175B4     	P5E_CPU0_PE4_TX_DP<9>

C1794     	Q_CAP_DIFFBUS_C0201	          	          	                    
          	               	1         	175B4     	P5E_CPU0_PE4_TX_C_DN<8>
          	               	2         	175B4     	P5E_CPU0_PE4_TX_DN<8>

C1796     	Q_CAP_0402     	          	          	                    
          	               	1         	234B3     	P3V3_AUX            
          	               	2         	234B3     	GND                 

C1797     	Q_CAP_0402     	          	          	                    
          	               	1         	301A4     	PDB_PRSNT_N         
          	               	2         	301A4     	GND                 

C1802     	Q_CAP_0402     	          	          	                    
          	               	1         	148A3     	FM_SMB_1_ALERT_GPU_ISO_N
          	               	2         	148A3     	GND                 

C1803     	Q_CAP_0402     	          	          	                    
          	               	1         	151A4     	P3V3_AUX            
          	               	2         	151A4     	GND                 

C1804     	Q_CAP_0402     	          	          	                    
          	               	1         	148B1     	FM_SMB_2_ALERT_GPU_ISO_N
          	               	2         	148A1     	GND                 

C1809     	Q_CAP_0402     	          	          	                    
          	               	1         	162A3     	P3V3_AUX            
          	               	2         	162A3     	GND                 

C1810     	Q_CAP_0402     	          	          	                    
          	               	1         	162A3     	P3V3_AUX            
          	               	2         	162A3     	GND                 

C1817     	Q_CAP_0402     	          	          	                    
          	               	1         	164B4     	P3V3_AUX            
          	               	2         	164B4     	GND                 

C1818     	Q_CAP_0402     	          	          	                    
          	               	1         	164A4     	P3V3_AUX            
          	               	2         	164A4     	GND                 

C1819     	Q_CAP_0402     	          	          	                    
          	               	1         	164B4     	P3V3_OCP_V3_2       
          	               	2         	164B4     	GND                 

C1820     	Q_CAP_0402     	          	          	                    
          	               	1         	164B1     	P3V3_AUX            
          	               	2         	164B1     	GND                 

C1821     	Q_CAP_0402     	          	          	                    
          	               	1         	161B4     	P3V3_AUX            
          	               	2         	161B4     	GND                 

C1822     	Q_CAP_0402     	          	          	                    
          	               	1         	161B4     	P3V3_AUX            
          	               	2         	161B4     	GND                 

C1823     	Q_CAP_0402     	          	          	                    
          	               	1         	161B3     	P3V3_AUX            
          	               	2         	161B3     	GND                 

C1824     	Q_CAP_0402     	          	          	                    
          	               	1         	161B2     	P3V3_AUX            
          	               	2         	161B2     	GND                 

C1825     	Q_CAP_0402     	          	          	                    
          	               	1         	160B4     	P3V3_AUX            
          	               	2         	160B4     	GND                 

C1826     	Q_CAP_0402     	          	          	                    
          	               	1         	160B3     	P3V3_AUX            
          	               	2         	160B3     	GND                 

C1827     	Q_CAP_0402     	          	          	                    
          	               	1         	160B3     	P3V3_AUX            
          	               	2         	160B3     	GND                 

C1829     	Q_CAP_C0805    	          	          	                    
          	               	1         	159A2     	P12V_OCP_V3_2       
          	               	2         	159A2     	GND                 

C1830     	Q_CAP_C0805    	          	          	                    
          	               	1         	159A2     	P12V_OCP_V3_2       
          	               	2         	159A2     	GND                 

C1831     	Q_CAP_0402     	          	          	                    
          	               	1         	159A2     	P12V_OCP_V3_2       
          	               	2         	159A2     	GND                 

C1832     	Q_CAP_0402     	          	          	                    
          	               	1         	159A2     	P12V_OCP_V3_2       
          	               	2         	159A2     	GND                 

C1833     	Q_CAP_0402     	          	          	                    
          	               	1         	159A2     	P12V_OCP_V3_2       
          	               	2         	159A2     	GND                 

C1834     	Q_CAP_0402     	          	          	                    
          	               	1         	159A1     	P12V_OCP_V3_2       
          	               	2         	159A1     	GND                 

C1835     	Q_CAP_0402     	          	          	                    
          	               	1         	159A1     	P3V3_OCP_V3_2       
          	               	2         	159A1     	GND                 

C1836     	Q_CAP_0402     	          	          	                    
          	               	1         	159A1     	P3V3_OCP_V3_2       
          	               	2         	159A1     	GND                 

C1837     	Q_CAP_0402     	          	          	                    
          	               	1         	159A1     	P3V3_OCP_V3_2       
          	               	2         	159A1     	GND                 

C1838     	Q_CAP_0402     	          	          	                    
          	               	1         	159A1     	P3V3_OCP_V3_2       
          	               	2         	159A1     	GND                 

C1839     	Q_CAP_0402     	          	          	                    
          	               	1         	159A2     	P12V_OCP_V3_2       
          	               	2         	159A2     	GND                 

C1840     	Q_CAP_0402     	          	          	                    
          	               	1         	154A4     	P3V3_AUX            
          	               	2         	154A4     	GND                 

C1841     	Q_CAP_0402     	          	          	                    
          	               	1         	161A4     	P3V3_AUX            
          	               	2         	161A4     	GND                 

C1842     	Q_CAP_C0402    	          	          	                    
          	               	1         	217A4     	P3V3_AUX_FPGA_VCCIO3
          	               	2         	217A4     	GND                 

C1859     	Q_CAP_0402     	          	          	                    
          	               	1         	238B3     	P3V3_AUX            
          	               	2         	238B3     	GND                 

C1860     	Q_CAP_0402     	          	          	                    
          	               	1         	238B3     	P3V3_AUX            
          	               	2         	238B3     	GND                 

C1861     	Q_CAP_0402     	          	          	                    
          	               	1         	238B3     	P3V3_OCP_V3_2       
          	               	2         	238B3     	GND                 

C1862     	Q_CAP_0402     	          	          	                    
          	               	1         	238B3     	P3V3_OCP_SFF        
          	               	2         	238B3     	GND                 

C1863     	Q_CAP_0402     	          	          	                    
          	               	1         	166B4     	P3V3_AUX            
          	               	2         	166B4     	GND                 

C1864     	Q_CAP_0402     	          	          	                    
          	               	1         	166B4     	P3V3_AUX            
          	               	2         	166B4     	GND                 

C1865     	Q_CAP_0402     	          	          	                    
          	               	1         	166B4     	P3V3_AUX            
          	               	2         	166B4     	GND                 

C1866     	Q_CAP_0402     	          	          	                    
          	               	1         	166B4     	P3V3_AUX            
          	               	2         	166B4     	GND                 

C1867     	Q_CAP_C0805    	          	          	                    
          	               	1         	166B4     	P3V3_AUX            
          	               	2         	166B4     	GND                 

C1868     	Q_CAP_0402     	          	          	                    
          	               	1         	167B4     	P2E_MB_BMC_RX_BUF_C_DP<0>
          	               	2         	167B4     	P2E_MB_BMC_RX_BUF_DP<0>

C1869     	Q_CAP_0402     	          	          	                    
          	               	1         	167B4     	P2E_MB_BMC_RX_BUF_C_DN<0>
          	               	2         	167B4     	P2E_MB_BMC_RX_BUF_DN<0>

C1870     	Q_CAP_0402     	          	          	                    
          	               	1         	167B4     	P2E_MB_BMC_TX_BUF_DP<0>
          	               	2         	167B4     	P2E_MB_BMC_TX_BUF_C_DP<0>

C1871     	Q_CAP_0402     	          	          	                    
          	               	1         	167B4     	P2E_MB_BMC_TX_BUF_DN<0>
          	               	2         	167B4     	P2E_MB_BMC_TX_BUF_C_DN<0>

C1873     	Q_CAP_0402     	          	          	                    
          	               	1         	190B3     	P3V3_AUX            
          	               	2         	190B3     	GND                 

C1874     	Q_CAP_0402     	          	          	                    
          	               	1         	165B4     	P3V3_AUX            
          	               	2         	165B4     	GND                 

C1875     	Q_CAP_0402     	          	          	                    
          	               	1         	165B4     	P3V3_AUX            
          	               	2         	165B4     	GND                 

C1876     	Q_CAP_0402     	          	          	                    
          	               	1         	165B3     	P3V3_AUX            
          	               	2         	165B3     	GND                 

C1877     	Q_CAP_0402     	          	          	                    
          	               	1         	165B2     	P3V3_AUX            
          	               	2         	165B2     	GND                 

C1878     	Q_CAP_0402     	          	          	                    
          	               	1         	165B2     	P3V3_AUX            
          	               	2         	165B2     	GND                 

C1879     	Q_CAP_0402     	          	          	                    
          	               	1         	165A2     	P3V3_AUX            
          	               	2         	165A2     	GND                 

C1880     	Q_CAP_0402     	          	          	                    
          	               	1         	165B2     	P3V3_AUX            
          	               	2         	165B2     	GND                 

C1881     	Q_CAP_0402     	          	          	                    
          	               	1         	148A1     	GPU_FPGA_READY_ISO  
          	               	2         	148A1     	GND                 

C1882     	Q_CAP_0402     	          	          	                    
          	               	1         	212B3     	P3V3_AUX            
          	               	2         	212B3     	GND                 

C1883     	Q_CAP_C0805    	          	          	                    
          	               	1         	212B3     	VFG3P3_CLK_GEN      
          	               	2         	212B3     	GND                 

C1884     	Q_CAP_C0402    	          	          	                    
          	               	1         	212B3     	VFG_3P3A_CLK_GEN    
          	               	2         	212B3     	GND                 

C1886     	Q_CAP_0402     	          	          	                    
          	               	1         	212B3     	VFG3P3_CLK_GEN      
          	               	2         	212B3     	GND                 

C1889     	Q_CAP_0402     	          	          	                    
          	               	1         	212B3     	VFG3P3_CLK_GEN      
          	               	2         	212B3     	GND                 

C1893     	Q_CAP_C0402    	          	          	                    
          	               	1         	217A3     	P3V3_AUX_FPGA_VCCIO4
          	               	2         	217A3     	GND                 

C1894     	Q_CAP_C0402    	          	          	                    
          	               	1         	217A2     	P3V3_AUX_FPGA_VCCIO2
          	               	2         	217A2     	GND                 

C1895     	Q_CAP_C0402    	          	          	                    
          	               	1         	217B2     	P3V3_AUX_FPGA_VCCIO0
          	               	2         	217B2     	GND                 

C1896     	Q_CAP_C0402    	          	          	                    
          	               	1         	217B2     	P3V3_AUX_FPGA_VCCIO1
          	               	2         	217B2     	GND                 

C1897     	Q_CAP_C0402    	          	          	                    
          	               	1         	217B2     	VCC_PLD_CORE        
          	               	2         	217B2     	GND                 

C1898     	Q_CAP_C0402    	          	          	                    
          	               	1         	217A1     	P3V3_AUX_FPGA_VCCIO5
          	               	2         	217A1     	GND                 

C1899     	Q_CAP_C0402    	          	          	                    
          	               	1         	217A2     	P3V3_AUX_FPGA_VCCIO4
          	               	2         	217A2     	GND                 

C1900     	Q_CAP_C0402    	          	          	                    
          	               	1         	217A2     	P3V3_AUX_FPGA_VCCIO2
          	               	2         	217A2     	GND                 

C1901     	Q_CAP_C0402    	          	          	                    
          	               	1         	217B2     	P3V3_AUX_FPGA_VCCIO0
          	               	2         	217B2     	GND                 

C1902     	Q_CAP_C0402    	          	          	                    
          	               	1         	217B2     	P3V3_AUX_FPGA_VCCIO1
          	               	2         	217B2     	GND                 

C1903     	Q_CAP_C0402    	          	          	                    
          	               	1         	217B2     	VCC_PLD_CORE        
          	               	2         	217B2     	GND                 

C1904     	Q_CAP_C0402    	          	          	                    
          	               	1         	217A1     	P3V3_AUX_FPGA_VCCIO5
          	               	2         	217A1     	GND                 

C1905     	Q_CAP_0402     	          	          	                    
          	               	1         	217B2     	P3V3_AUX_FPGA_VCCIO0
          	               	2         	217B2     	GND                 

C1906     	Q_CAP_0402     	          	          	                    
          	               	1         	217B2     	P3V3_AUX_FPGA_VCCIO1
          	               	2         	217B2     	GND                 

C1907     	Q_CAP_0402     	          	          	                    
          	               	1         	217B2     	VCC_PLD_CORE        
          	               	2         	217B2     	GND                 

C1908     	Q_CAP_C0402    	          	          	                    
          	               	1         	217A3     	P3V3_AUX_FPGA_VCCIO4
          	               	2         	217A3     	GND                 

C1909     	Q_CAP_C0402    	          	          	                    
          	               	1         	217A2     	P3V3_AUX_FPGA_VCCIO2
          	               	2         	217A2     	GND                 

C1910     	Q_CAP_C0402    	          	          	                    
          	               	1         	217B2     	P3V3_AUX_FPGA_VCCIO0
          	               	2         	217B2     	GND                 

C1911     	Q_CAP_C0402    	          	          	                    
          	               	1         	217B2     	P3V3_AUX_FPGA_VCCIO1
          	               	2         	217B2     	GND                 

C1912     	Q_CAP_C0402    	          	          	                    
          	               	1         	217B2     	VCC_PLD_CORE        
          	               	2         	217B2     	GND                 

C1913     	Q_CAP_C0402    	          	          	                    
          	               	1         	217A1     	P3V3_AUX_FPGA_VCCIO5
          	               	2         	217A1     	GND                 

C1914     	Q_CAP_C0402    	          	          	                    
          	               	1         	217B2     	P3V3_AUX_FPGA_VCCIO0
          	               	2         	217B2     	GND                 

C1915     	Q_CAP_C0402    	          	          	                    
          	               	1         	217B2     	P3V3_AUX_FPGA_VCCIO1
          	               	2         	217B2     	GND                 

C1916     	Q_CAP_C0402    	          	          	                    
          	               	1         	217B2     	VCC_PLD_CORE        
          	               	2         	217B2     	GND                 

C1917     	Q_CAP_C0402    	          	          	                    
          	               	1         	217B1     	P3V3_AUX_FPGA_VCCIO0
          	               	2         	217B1     	GND                 

C1918     	Q_CAP_C0402    	          	          	                    
          	               	1         	217B1     	P3V3_AUX_FPGA_VCCIO1
          	               	2         	217B1     	GND                 

C1919     	Q_CAP_C0402    	          	          	                    
          	               	1         	217B1     	VCC_PLD_CORE        
          	               	2         	217B1     	GND                 

C1920     	Q_CAP_C0603    	          	          	                    
          	               	1         	190B2     	P3V3_M2_0           
          	               	2         	190B2     	GND                 

C1921     	Q_CAP_C0603    	          	          	                    
          	               	1         	190B2     	P3V3_M2_0           
          	               	2         	190B2     	GND                 

C1922     	Q_CAP_C0603    	          	          	                    
          	               	1         	190B1     	P3V3_M2_0           
          	               	2         	190B1     	GND                 

C1923     	Q_CAP_0402     	          	          	                    
          	               	1         	190B1     	P3V3_M2_0           
          	               	2         	190B1     	GND                 

C1924     	Q_CAP_0402     	          	          	                    
          	               	1         	190B1     	P3V3_M2_0           
          	               	2         	190B1     	GND                 

C1925     	Q_CAP_0402     	          	          	                    
          	               	1         	190B1     	P3V3_M2_0           
          	               	2         	190B1     	GND                 

C1926     	Q_CAP_C0402    	          	          	                    
          	               	1         	217B1     	P3V3_AUX_FPGA_VCCIO0
          	               	2         	217B1     	GND                 

C1927     	Q_CAP_C0402    	          	          	                    
          	               	1         	217B1     	P3V3_AUX_FPGA_VCCIO1
          	               	2         	217B1     	GND                 

C1928     	Q_CAP_C0402    	          	          	                    
          	               	1         	217B1     	VCC_PLD_CORE        
          	               	2         	217B1     	GND                 

C1929     	Q_CAP_C0402    	          	          	                    
          	               	1         	217B1     	P3V3_AUX_FPGA_VCCIO0
          	               	2         	217B1     	GND                 

C1930     	Q_CAP_C0402    	          	          	                    
          	               	1         	217B1     	P3V3_AUX_FPGA_VCCIO1
          	               	2         	217B1     	GND                 

C1931     	Q_CAP_C0402    	          	          	                    
          	               	1         	217B1     	VCC_PLD_CORE        
          	               	2         	217B1     	GND                 

C1932     	Q_CAP_C0402    	          	          	                    
          	               	1         	217B1     	P3V3_AUX_FPGA_VCCIO0
          	               	2         	217B1     	GND                 

C1933     	Q_CAP_C0402    	          	          	                    
          	               	1         	217B1     	P3V3_AUX_FPGA_VCCIO1
          	               	2         	217B1     	GND                 

C1934     	Q_CAP_C0402    	          	          	                    
          	               	1         	217B1     	VCC_PLD_CORE        
          	               	2         	217B1     	GND                 

C1935     	Q_CAP_C0402    	          	          	                    
          	               	1         	217A3     	P3V3_AUX_FPGA_VCCIO4
          	               	2         	217A3     	GND                 

C1936     	Q_CAP_C0402    	          	          	                    
          	               	1         	217B2     	VCC_PLD_CORE        
          	               	2         	217B2     	GND                 

C1937     	Q_CAP_C0402    	          	          	                    
          	               	1         	217A2     	P3V3_AUX_FPGA_VCCIO2
          	               	2         	217A2     	GND                 

C1938     	Q_CAP_C0402    	          	          	                    
          	               	1         	217B2     	P3V3_AUX_FPGA_VCCIO0
          	               	2         	217B2     	GND                 

C1939     	Q_CAP_C0402    	          	          	                    
          	               	1         	217B2     	P3V3_AUX_FPGA_VCCIO1
          	               	2         	217B2     	GND                 

C1940     	Q_CAP_C0402    	          	          	                    
          	               	1         	217A2     	P3V3_AUX_FPGA_VCCIO5
          	               	2         	217A2     	GND                 

C1941     	Q_CAP_0402     	          	          	                    
          	               	1         	217A4     	P3V3_AUX_FPGA_VCCIO3
          	               	2         	217A4     	GND                 

C1942     	Q_CAP_0402     	          	          	                    
          	               	1         	217A3     	P3V3_AUX_FPGA_VCCIO4
          	               	2         	217A3     	GND                 

C1943     	Q_CAP_0402     	          	          	                    
          	               	1         	217B2     	VCC_PLD_CORE        
          	               	2         	217B2     	GND                 

C1944     	Q_CAP_0402     	          	          	                    
          	               	1         	217A2     	P3V3_AUX_FPGA_VCCIO2
          	               	2         	217A2     	GND                 

C1945     	Q_CAP_0402     	          	          	                    
          	               	1         	217B2     	P3V3_AUX_FPGA_VCCIO0
          	               	2         	217B2     	GND                 

C1946     	Q_CAP_0402     	          	          	                    
          	               	1         	217B2     	P3V3_AUX_FPGA_VCCIO1
          	               	2         	217B2     	GND                 

C1947     	Q_CAP_0402     	          	          	                    
          	               	1         	217A1     	P3V3_AUX_FPGA_VCCIO5
          	               	2         	217A1     	GND                 

C1957     	Q_CAP_0402     	          	          	                    
          	               	1         	149B3     	P3V3_AUX            
          	               	2         	149B3     	GND                 

C1958     	Q_CAP_0402     	          	          	                    
          	               	1         	149B3     	P3V3_AUX            
          	               	2         	149B3     	GND                 

C1963     	Q_CAP_0402     	          	          	                    
          	               	1         	150B3     	P3V3_AUX            
          	               	2         	150B3     	GND                 

C1973     	Q_CAP_0402     	          	          	                    
          	               	1         	147B3     	GPU_BASE_HMC_READY_ISO
          	               	2         	147B3     	GND                 

C1974     	Q_CAP_0402     	          	          	                    
          	               	1         	147B3     	GPU_FPGA_THERM_OVERT_ISO_N
          	               	2         	147B3     	GND                 

C1975     	Q_CAP_0402     	          	          	                    
          	               	1         	147B3     	GPU_HMC_PRSNT_ISO_N 
          	               	2         	147B3     	GND                 

C1976     	Q_CAP_0402     	          	          	                    
          	               	1         	147A3     	GPU_FPGA_OVERT_ISO_N
          	               	2         	147A3     	GND                 

C1977     	Q_CAP_0402     	          	          	                    
          	               	1         	149A3     	P3V3_AUX            
          	               	2         	149A3     	GND                 

C1978     	Q_CAP_0402     	          	          	                    
          	               	1         	147B1     	GPU_PRSNT_N_ISO     
          	               	2         	147B1     	GND                 

C1979     	Q_CAP_0402     	          	          	                    
          	               	1         	150A3     	P3V3_AUX            
          	               	2         	150A3     	GND                 

C1988     	Q_CAP_0402     	          	          	                    
          	               	1         	147B1     	GPU_FPGA_EROT_FATALERR_ISO_N
          	               	2         	147A1     	GND                 

C1989     	Q_CAP_DIFFBUS_C0201	          	          	                    
          	               	1         	181B2     	P3E_PCH_E1S_TX_DP<3>
          	               	2         	181B2     	P3E_PCH_E1S_TX_C_DP<3>

C1990     	Q_CAP_DIFFBUS_C0201	          	          	                    
          	               	1         	181B2     	P3E_PCH_E1S_TX_DN<3>
          	               	2         	181B2     	P3E_PCH_E1S_TX_C_DN<3>

C1991     	Q_CAP_DIFFBUS_C0201	          	          	                    
          	               	1         	181B2     	P3E_PCH_E1S_TX_DP<2>
          	               	2         	181B2     	P3E_PCH_E1S_TX_C_DP<2>

C1992     	Q_CAP_DIFFBUS_C0201	          	          	                    
          	               	1         	181B2     	P3E_PCH_E1S_TX_DN<2>
          	               	2         	181B2     	P3E_PCH_E1S_TX_C_DN<2>

C1993     	Q_CAP_DIFFBUS_C0201	          	          	                    
          	               	1         	181B2     	P3E_PCH_E1S_TX_DP<1>
          	               	2         	181B2     	P3E_PCH_E1S_TX_C_DP<1>

C1994     	Q_CAP_DIFFBUS_C0201	          	          	                    
          	               	1         	181B2     	P3E_PCH_E1S_TX_DN<1>
          	               	2         	181B2     	P3E_PCH_E1S_TX_C_DN<1>

C1995     	Q_CAP_DIFFBUS_C0201	          	          	                    
          	               	1         	181B2     	P3E_PCH_E1S_TX_DP<0>
          	               	2         	181B2     	P3E_PCH_E1S_TX_C_DP<0>

C1996     	Q_CAP_DIFFBUS_C0201	          	          	                    
          	               	1         	181B2     	P3E_PCH_E1S_TX_DN<0>
          	               	2         	181B2     	P3E_PCH_E1S_TX_C_DN<0>

C1997     	Q_CAP_0402     	          	          	                    
          	               	1         	194B4     	P3V3_AUX            
          	               	2         	194B4     	GND                 

C1998     	Q_CAP_0402     	          	          	                    
          	               	1         	194B3     	P3V3_E1S_0          
          	               	2         	194B3     	GND                 

C2007     	Q_CAP_C0402    	          	          	                    
          	               	1         	190A3     	P3V3_AUX            
          	               	2         	190A3     	GND                 

C2010     	Q_CAP_0402     	          	          	                    
          	               	1         	170B3     	P3V3_AUX            
          	               	2         	170B3     	GND                 

C2012     	Q_CAP_0402     	          	          	                    
          	               	1         	172B3     	P3V3_AUX            
          	               	2         	172B3     	GND                 

C2013     	Q_CAP_0402     	          	          	                    
          	               	1         	172B3     	P3V3_AUX            
          	               	2         	172B3     	GND                 

C2014     	Q_CAP_0402     	          	          	                    
          	               	1         	172A3     	P3V3_AUX            
          	               	2         	172A3     	GND                 

C2015     	Q_CAP_0402     	          	          	                    
          	               	1         	171B3     	P3V3_AUX            
          	               	2         	171B3     	GND                 

C2017     	Q_CAP_0402     	          	          	                    
          	               	1         	172B4     	P3V3_OCP_V3_2_R     
          	               	2         	172B4     	GND                 

C2018     	Q_CAP_0402     	          	          	                    
          	               	1         	172B4     	P3V3                
          	               	2         	172B4     	GND                 

C2019     	Q_CAP_0402     	          	          	                    
          	               	1         	172A4     	P12V_SCM_R          
          	               	2         	172A4     	GND                 

C2020     	Q_CAP_0402     	          	          	                    
          	               	1         	172B3     	VSENSE_P12V_INA230_3_INP
          	               	2         	172B3     	VSENSE_P12V_INA230_3_INN

C2021     	Q_CAP_0402     	          	          	                    
          	               	1         	172B3     	VSENSE_P12V_INA230_4_INP
          	               	2         	172B3     	VSENSE_P12V_INA230_4_INN

C2022     	Q_CAP_0402     	          	          	                    
          	               	1         	172A3     	VSENSE_P12V_INA230_5_INP
          	               	2         	172A3     	VSENSE_P12V_INA230_5_INN

C2024     	Q_CAP_0402     	          	          	                    
          	               	1         	171B4     	P3V3_OCP_SFF_R      
          	               	2         	171B4     	GND                 

C2027     	Q_CAP_0402     	          	          	                    
          	               	1         	171B3     	VSENSE_P3V3_INA230_1_INP
          	               	2         	171B3     	VSENSE_P3V3_INA230_1_INN

C2029     	Q_CAP_0402     	          	          	                    
          	               	1         	152B1     	USB_HUB_XTAL_IN     
          	               	2         	152B1     	GND                 

C2030     	Q_CAP_0402     	          	          	                    
          	               	1         	152B1     	USB_HUB_XTAL_OUT    
          	               	2         	152B1     	GND                 

C2031     	Q_CAP_C0402    	          	          	                    
          	               	1         	152B4     	P3V3_AUX_USB_HUB    
          	               	2         	152B4     	GND                 

C2032     	Q_CAP_0402     	          	          	                    
          	               	1         	152B4     	P3V3_AUX_USB_HUB    
          	               	2         	152B4     	GND                 

C2033     	Q_CAP_0402     	          	          	                    
          	               	1         	152B4     	P3V3_AUX_USB_HUB    
          	               	2         	152B4     	GND                 

C2034     	Q_CAP_0402     	          	          	                    
          	               	1         	152B4     	P3V3_AUX_USB_HUB    
          	               	2         	152B4     	GND                 

C2035     	Q_CAP_C0402    	          	          	                    
          	               	1         	152B3     	P3V3_AUX_USB_HUB    
          	               	2         	152B3     	GND                 

C2036     	Q_CAP_C0402    	          	          	                    
          	               	1         	208A4     	XTAL_CLK_GEN1_25M_X1_R
          	               	2         	208A4     	GND                 

C2037     	Q_CAP_C0402    	          	          	                    
          	               	1         	208A4     	XTAL_CLK_GEN1_25M_X2
          	               	2         	208A4     	GND                 

C2038     	Q_CAP_C0402    	          	          	                    
          	               	1         	152B4     	P3V3_AUX_USB_HUB    
          	               	2         	152B4     	GND                 

C2039     	Q_CAP_0402     	          	          	                    
          	               	1         	152B4     	P3V3_AUX_USB_HUB    
          	               	2         	152B4     	GND                 

C2040     	Q_CAP_0402     	          	          	                    
          	               	1         	152B4     	P3V3_AUX_USB_HUB    
          	               	2         	152B4     	GND                 

C2041     	Q_CAP_C0402    	          	          	                    
          	               	1         	152B4     	RST_USB_HUB_R_N     
          	               	2         	152B4     	GND                 

C2042     	Q_CAP_0402     	          	          	                    
          	               	1         	250B4     	P3V3_AUX_ADC_MAM    
          	               	2         	250B4     	GND                 

C2043     	Q_CAP_0402     	          	          	                    
          	               	1         	250B4     	P3V3_ADC_MAM        
          	               	2         	250B4     	GND                 

C2044     	Q_CAP_0402     	          	          	                    
          	               	1         	250B4     	P5V_ADC_MAM         
          	               	2         	250B4     	GND                 

C2045     	Q_CAP_0402     	          	          	                    
          	               	1         	250A4     	P3V3_PDB_AUX_ADC_MAM
          	               	2         	250A4     	GND                 

C2046     	Q_CAP_0402     	          	          	                    
          	               	1         	250A4     	P12V_AUX_ADC_TIC    
          	               	2         	250A4     	GND                 

C2047     	Q_CAP_0402     	          	          	                    
          	               	1         	250B4     	P3V3_AUX_ADC_TIC    
          	               	2         	250B4     	GND                 

C2048     	Q_CAP_0402     	          	          	                    
          	               	1         	250B4     	P3V3_ADC_TIC        
          	               	2         	250B4     	GND                 

C2049     	Q_CAP_0402     	          	          	                    
          	               	1         	250B4     	P5V_ADC_TIC         
          	               	2         	250B4     	GND                 

C2050     	Q_CAP_0402     	          	          	                    
          	               	1         	250A4     	P3V3_PDB_AUX_ADC_TIC
          	               	2         	250A4     	GND                 

C2051     	Q_CAP_0402     	          	          	                    
          	               	1         	250B3     	P3V3_ADC128_VCC     
          	               	2         	250A3     	GND                 

C2052     	Q_CAP_0402     	          	          	                    
          	               	1         	250B2     	P3V3_ADC128_VCC     
          	               	2         	250A2     	GND                 

C2056     	Q_CAP_0402     	          	          	                    
          	               	1         	233B3     	P3V3_AUX            
          	               	2         	233B3     	GND                 

C2067     	Q_CAP_0402     	          	          	                    
          	               	1         	171B3     	P3V3_AUX            
          	               	2         	171B3     	GND                 

C2069     	Q_CAP_0402     	          	          	                    
          	               	1         	171A4     	P3V3_E1S_0_R        
          	               	2         	171A4     	GND                 

C2071     	Q_CAP_0402     	          	          	                    
          	               	1         	171A3     	VSENSE_P3V3_INA230_2_INP
          	               	2         	171A3     	VSENSE_P3V3_INA230_2_INN

C2073     	Q_CAP_DIFFBUS_C0201	          	          	                    
          	               	1         	181B2     	P3E_PCH_NVS_TX_DP<1>
          	               	2         	181B2     	P3E_PCH_NVS_TX_C_DP<1>

C2074     	Q_CAP_DIFFBUS_C0201	          	          	                    
          	               	1         	181B2     	P3E_PCH_NVS_TX_DN<1>
          	               	2         	181B2     	P3E_PCH_NVS_TX_C_DN<1>

C2075     	Q_CAP_DIFFBUS_C0201	          	          	                    
          	               	1         	181B2     	P3E_PCH_NVS_TX_DP<0>
          	               	2         	181B2     	P3E_PCH_NVS_TX_C_DP<0>

C2076     	Q_CAP_DIFFBUS_C0201	          	          	                    
          	               	1         	181B2     	P3E_PCH_NVS_TX_DN<0>
          	               	2         	181B2     	P3E_PCH_NVS_TX_C_DN<0>

C2077     	Q_CAP_DIFFBUS_C0201	          	          	                    
          	               	1         	181B2     	P3E_PCH_BMC_TX_DP   
          	               	2         	181B2     	P3E_PCH_BMC_TX_C_DP 

C2078     	Q_CAP_DIFFBUS_C0201	          	          	                    
          	               	1         	181B2     	P3E_PCH_BMC_TX_DN   
          	               	2         	181B2     	P3E_PCH_BMC_TX_C_DN 

C2148     	Q_CAP_C0402    	          	          	                    
          	               	1         	162B2     	P12V_OCP_V3_2       
          	               	2         	162B2     	P12V_OCP_GATE_2     

C2175     	Q_CAP_0402     	          	          	                    
          	               	1         	250B3     	P12V_OCP_V3_2_ISENSE_MAM
          	               	2         	250B3     	GND                 

C2176     	Q_CAP_0402     	          	          	                    
          	               	1         	250B3     	P12V_OCP_SFF_ISENSE_MAM
          	               	2         	250B3     	GND                 

C2177     	Q_CAP_0402     	          	          	                    
          	               	1         	250B3     	P12V_OCP_V3_2_ISENSE_TIC
          	               	2         	250B3     	GND                 

C2178     	Q_CAP_0402     	          	          	                    
          	               	1         	250B3     	P12V_OCP_SFF_ISENSE_TIC
          	               	2         	250B3     	GND                 

C2179     	Q_CAP_C0402    	          	          	                    
          	               	1         	301A3     	HSC_EN              
          	               	2         	301A3     	AGND_HSC            

C2194     	Q_CAP_0402     	          	          	                    
          	               	1         	250B3     	P12V_E1S_0_ISENSE_TIC
          	               	2         	250B3     	GND                 

C2195     	Q_CAP_0402     	          	          	                    
          	               	1         	250B3     	P12V_E1S_0_ISENSE_MAM
          	               	2         	250B3     	GND                 

C2243     	Q_CAP_C0402    	          	          	                    
          	               	1         	226B3     	P3V3                
          	               	2         	226B3     	GND                 

C2246     	Q_CAP_C0402    	          	          	                    
          	               	1         	225B3     	P3V3_AUX            
          	               	2         	225B3     	GND                 

C2247     	Q_CAP_C0402    	          	          	                    
          	               	1         	225B3     	P3V3_AUX            
          	               	2         	225B3     	GND                 

C2248     	Q_CAP_C0402    	          	          	                    
          	               	1         	225A3     	P3V3                
          	               	2         	225A3     	GND                 

C2249     	Q_CAP_0402     	          	          	                    
          	               	1         	226B3     	P0V62_CPU0_ERRS_VREF
          	               	2         	226B3     	GND                 

C2252     	Q_CAP_0402     	          	          	                    
          	               	1         	225B2     	P0V62_CPU0_RST_DDR_VREF
          	               	2         	225B2     	GND                 

C2253     	Q_CAP_0402     	          	          	                    
          	               	1         	225B2     	P0V62_CPU1_RST_DDR_VREF
          	               	2         	225B2     	GND                 

C2254     	Q_CAP_0402     	          	          	                    
          	               	1         	225A2     	P0V62_CPU0_ERRS_U306_VREF
          	               	2         	225A2     	GND                 

C2255     	Q_CAP_C0402    	          	          	                    
          	               	1         	212B4     	CLK_GEN2_XTAL_IN_R  
          	               	2         	212B4     	GND                 

C2256     	Q_CAP_C0402    	          	          	                    
          	               	1         	212B4     	CLK_GEN2_XTAL_OUT   
          	               	2         	212B4     	GND                 

C2257     	Q_CAP_0402     	          	          	                    
          	               	1         	212B3     	VFG3P3_CLK_GEN      
          	               	2         	212B3     	GND                 

C2258     	Q_CAP_0402     	          	          	                    
          	               	1         	212B3     	VFG3P3_CLK_GEN      
          	               	2         	212B3     	GND                 

C2259     	Q_CAP_0402     	          	          	                    
          	               	1         	212B2     	VFG_3P3A_CLK_GEN    
          	               	2         	212B2     	GND                 

C2264     	Q_CAP_0402     	          	          	                    
          	               	1         	146B3     	GPU_3V3IO_RSVD0_FFU_ISO
          	               	2         	146B3     	GND                 

C2265     	Q_CAP_0402     	          	          	                    
          	               	1         	146B3     	PRSNT_CABLE_GPU_B3_ISO_N
          	               	2         	146B3     	GND                 

C2266     	Q_CAP_0402     	          	          	                    
          	               	1         	146B3     	GPU_3V3IO_RSVD1_FFU_ISO
          	               	2         	146B3     	GND                 

C2267     	Q_CAP_0402     	          	          	                    
          	               	1         	146B1     	GPU_3V3IO_RSVD3_FFU_ISO
          	               	2         	146B1     	GND                 

C2268     	Q_CAP_0402     	          	          	                    
          	               	1         	146B1     	GPU_3V3IO_RSVD5_FFU_ISO
          	               	2         	146B1     	GND                 

C2269     	Q_CAP_0402     	          	          	                    
          	               	1         	146B1     	PRSNT_CABLE_GPU_A2_ISO_N
          	               	2         	146B1     	GND                 

C2270     	Q_CAP_0402     	          	          	                    
          	               	1         	146A3     	PRSNT_CABLE_GPU_A1_ISO_N
          	               	2         	146A3     	GND                 

C2271     	Q_CAP_0402     	          	          	                    
          	               	1         	145B3     	GPU_3V3IO_RSVD1_ISO 
          	               	2         	145B3     	GND                 

C2272     	Q_CAP_0402     	          	          	                    
          	               	1         	145B3     	GPU_3V3IO_RSVD4_ISO 
          	               	2         	145B3     	GND                 

C2273     	Q_CAP_0402     	          	          	                    
          	               	1         	145B3     	GPU_3V3IO_RSVD3_ISO 
          	               	2         	145B3     	GND                 

C2274     	Q_CAP_0402     	          	          	                    
          	               	1         	170A3     	P3V3_AUX            
          	               	2         	170A3     	GND                 

C2275     	Q_CAP_0402     	          	          	                    
          	               	1         	170B3     	P3V3_AUX            
          	               	2         	170B3     	GND                 

C2276     	Q_CAP_0402     	          	          	                    
          	               	1         	170B3     	P3V3_AUX            
          	               	2         	170B3     	GND                 

C2283     	Q_CAP_0402     	          	          	                    
          	               	1         	246B2     	P3V3_AUX            
          	               	2         	246B2     	GND                 

C2284     	Q_CAP_C0805    	          	          	                    
          	               	1         	169B4     	P3V3_AUX_USB_BUF    
          	               	2         	169B4     	GND                 

C2285     	Q_CAP_0402     	          	          	                    
          	               	1         	169B4     	P3V3_AUX_USB_BUF    
          	               	2         	169B4     	GND                 

C2286     	Q_CAP_0402     	          	          	                    
          	               	1         	169B3     	P3V3_AUX_USB_BUF    
          	               	2         	169B3     	GND                 

C2287     	Q_CAP_C0402    	          	          	                    
          	               	1         	263B2     	PWRGD_P1V8_PCH_AUX  
          	               	2         	263B2     	GND                 

C2289     	Q_CAP_C0201    	          	          	                    
          	               	1         	169B2     	USB3_PCH_TX_BUF_DP<4>
          	               	2         	169B2     	USB3_PCH_TX_BUF_C_DP<4>

C2290     	Q_CAP_C0201    	          	          	                    
          	               	1         	169B2     	USB3_PCH_TX_BUF_DN<4>
          	               	2         	169B2     	USB3_PCH_TX_BUF_C_DN<4>

C2291     	Q_CAP_C0201    	          	          	                    
          	               	1         	169B2     	USB3_PCH_RX_BUF_C_DP<4>
          	               	2         	169B2     	USB3_PCH_RX_BUF_DP<4>

C2292     	Q_CAP_C0201    	          	          	                    
          	               	1         	169B2     	USB3_PCH_RX_BUF_C_DN<4>
          	               	2         	169B2     	USB3_PCH_RX_BUF_DN<4>

C2293     	Q_CAP_0402     	          	          	                    
          	               	1         	245B1     	RST_SMB_SWITCH_R_N  
          	               	2         	245B1     	GND                 

C2294     	Q_CAP_0402     	          	          	                    
          	               	1         	245B1     	PDB_PRSNT_N         
          	               	2         	245B1     	GND                 

C2295     	Q_CAP_0402     	          	          	                    
          	               	1         	245B1     	HPDB_HSC_PWRGD_R    
          	               	2         	245B1     	GND                 

C2296     	Q_CAP_0402     	          	          	                    
          	               	1         	245B1     	FM_FAN_PWR_EN_R     
          	               	2         	245B1     	GND                 

C2297     	Q_CAP_0402     	          	          	                    
          	               	1         	245B1     	FM_GPU_HSC_EN_BUF_R1
          	               	2         	245B1     	GND                 

C2313     	Q_CAP_C0402    	          	          	                    
          	               	1         	196B4     	P3V3_AUX_USB_HUB_2  
          	               	2         	196B4     	GND                 

C2314     	Q_CAP_0402     	          	          	                    
          	               	1         	196B4     	P3V3_AUX_USB_HUB_2  
          	               	2         	196B4     	GND                 

C2315     	Q_CAP_0402     	          	          	                    
          	               	1         	196B4     	P3V3_AUX_USB_HUB_2  
          	               	2         	196B4     	GND                 

C2316     	Q_CAP_C0402    	          	          	                    
          	               	1         	196B4     	P3V3_AUX_USB_HUB_2  
          	               	2         	196B4     	GND                 

C2317     	Q_CAP_C0402    	          	          	                    
          	               	1         	196B4     	RST_USB_HUB_2_R_N   
          	               	2         	196B4     	GND                 

C2318     	Q_CAP_0402     	          	          	                    
          	               	1         	196B4     	P3V3_AUX_USB_HUB_2  
          	               	2         	196B4     	GND                 

C2319     	Q_CAP_0402     	          	          	                    
          	               	1         	196B4     	P3V3_AUX_USB_HUB_2  
          	               	2         	196B4     	GND                 

C2320     	Q_CAP_0402     	          	          	                    
          	               	1         	196B4     	P3V3_AUX_USB_HUB_2  
          	               	2         	196B4     	GND                 

C2321     	Q_CAP_0402     	          	          	                    
          	               	1         	196A3     	PD_USB_HUB_2_RSTN   
          	               	2         	196A3     	GND                 

C2322     	Q_CAP_C0402    	          	          	                    
          	               	1         	196B3     	P3V3_AUX_USB_HUB_2  
          	               	2         	196B3     	GND                 

C2323     	Q_CAP_C0402    	          	          	                    
          	               	1         	196A3     	P3V3_AUX            
          	               	2         	196A3     	GND                 

C2324     	Q_CAP_0402     	          	          	                    
          	               	1         	196A3     	P3V3_AUX            
          	               	2         	196A3     	GND                 

C2325     	Q_CAP_0402     	          	          	                    
          	               	1         	196A2     	PD_USB_HUB_2_VREG   
          	               	2         	196A2     	GND                 

C2326     	Q_CAP_C0402    	          	          	                    
          	               	1         	196B1     	USB_HUB_2_XTAL_IN   
          	               	2         	196B1     	GND                 

C2327     	Q_CAP_C0402    	          	          	                    
          	               	1         	196B1     	USB_HUB_2_XTAL_OUT  
          	               	2         	196B1     	GND                 

C2328     	Q_CAP_C0603    	          	          	                    
          	               	1         	211B3     	P3V3_9ZXL045_VDD    
          	               	2         	211B3     	GND                 

C2329     	Q_CAP_0402     	          	          	                    
          	               	1         	211B3     	P3V3_9ZXL045_VDD    
          	               	2         	211B3     	GND                 

C2330     	Q_CAP_0402     	          	          	                    
          	               	1         	211B3     	P3V3_9ZXL045_VDD    
          	               	2         	211B3     	GND                 

C2331     	Q_CAP_C0603    	          	          	                    
          	               	1         	211B4     	P3V3_9ZXL045_VDDA   
          	               	2         	211B4     	GND                 

C2332     	Q_CAP_C0603    	          	          	                    
          	               	1         	211B4     	P3V3_9ZXL045_VDDR   
          	               	2         	211B4     	GND                 

C2333     	Q_CAP_0402     	          	          	                    
          	               	1         	211B2     	P3V3_9ZXL045_VDD    
          	               	2         	211B2     	GND                 

C2334     	Q_CAP_0402     	          	          	                    
          	               	1         	211B4     	P3V3_9ZXL045_VDDA   
          	               	2         	211B4     	GND                 

C2335     	Q_CAP_0402     	          	          	                    
          	               	1         	211B4     	P3V3_9ZXL045_VDDR   
          	               	2         	211B4     	GND                 

C2336     	Q_CAP_0402     	          	          	                    
          	               	1         	211B2     	P3V3_9ZXL045_VDD    
          	               	2         	211B2     	GND                 

C2337     	Q_CAP_0402     	          	          	                    
          	               	1         	237B4     	P3V3_AUX            
          	               	2         	237B4     	GND                 

C2338     	Q_CAP_0402     	          	          	                    
          	               	1         	237B3     	P3V3                
          	               	2         	237B3     	GND                 

C2339     	Q_CAP_0402     	          	          	                    
          	               	1         	211B2     	P3V3_9ZXL045_VDD    
          	               	2         	211B2     	GND                 

C2340     	Q_CAP_0402     	          	          	                    
          	               	1         	145A3     	HGX_DETECT_N_ISO    
          	               	2         	145A3     	GND                 

C2341     	Q_CAP_0402     	          	          	                    
          	               	1         	145B2     	P3V3_AUX            
          	               	2         	145B2     	GND                 

C2342     	Q_CAP_0402     	          	          	                    
          	               	1         	246A2     	HPDB_HSC_PWRGD_ISO  
          	               	2         	246A2     	GND                 

C2343     	Q_CAP_0402     	          	          	                    
          	               	1         	146A1     	SWB_HSC_PWRGD_ISO   
          	               	2         	146A1     	GND                 

C2344     	Q_CAP_0402     	          	          	                    
          	               	1         	155A1     	P3V3_AUX            
          	               	2         	155A1     	GND                 

C2345     	Q_CAP_0402     	          	          	                    
          	               	1         	161A1     	P3V3_AUX            
          	               	2         	161A1     	GND                 

C2346     	Q_CAP_0402     	          	          	                    
          	               	1         	158B2     	P3V3_AUX            
          	               	2         	158B2     	GND                 

C2347     	Q_CAP_0402     	          	          	                    
          	               	1         	164B2     	P3V3_AUX            
          	               	2         	164B2     	GND                 

C2348     	Q_CAP_0402     	          	          	                    
          	               	1         	248B2     	P3V3_AUX            
          	               	2         	248B2     	GND                 

C2349     	Q_CAP_DIFFBUS_C0402	          	          	                    
          	               	1         	169B4     	USB3_PCH_RX_DP<4>   
          	               	2         	169B4     	USB3_PCH_RX_C_DP<4> 

C2350     	Q_CAP_DIFFBUS_C0402	          	          	                    
          	               	1         	169B4     	USB3_PCH_RX_DN<4>   
          	               	2         	169B4     	USB3_PCH_RX_C_DN<4> 

C2351     	Q_CAP_0402     	          	          	                    
          	               	1         	167B4     	P2E_MB_BMC_TX_BUF2_DP<0>
          	               	2         	167B4     	P2E_MB_BMC_TX_BUF_C_DP<0>

C2352     	Q_CAP_0402     	          	          	                    
          	               	1         	167B4     	P2E_MB_BMC_TX_BUF2_DN<0>
          	               	2         	167B4     	P2E_MB_BMC_TX_BUF_C_DN<0>

C2353     	Q_CAP_0402     	          	          	                    
          	               	1         	167B4     	P2E_MB_BMC_RX_BUF2_C_DP<0>
          	               	2         	167B4     	P2E_MB_BMC_RX_BUF_DP<0>

C2354     	Q_CAP_0402     	          	          	                    
          	               	1         	167B4     	P2E_MB_BMC_RX_BUF2_C_DN<0>
          	               	2         	167B4     	P2E_MB_BMC_RX_BUF_DN<0>

C2355     	Q_CAP_C0402    	          	          	                    
          	               	1         	167B3     	P3V3_AUX            
          	               	2         	167B3     	GND                 

C2356     	Q_CAP_C0805    	          	          	                    
          	               	1         	167B3     	P3V3_AUX            
          	               	2         	167B3     	GND                 

C2357     	Q_CAP_0402     	          	          	                    
          	               	1         	167B3     	P2E_BUF2_VDD        
          	               	2         	167B3     	GND                 

C2358     	Q_CAP_0402     	          	          	                    
          	               	1         	167B2     	P2E_BUF2_VDD        
          	               	2         	167B2     	GND                 

C2359     	Q_CAP_C0402    	          	          	                    
          	               	1         	260B1     	PWRGD_P5V_ISO_R     
          	               	2         	260A1     	GND                 

C2360     	Q_CAP_0402     	          	          	                    
          	               	1         	260A4     	P3V3                
          	               	2         	260A4     	GND                 

C2363     	Q_CAP_0402     	          	          	                    
          	               	1         	251B3     	HSC_TYPE_ADC        
          	               	2         	251B3     	GND                 

C2364     	Q_CAP_0402     	          	          	                    
          	               	1         	251B3     	P3V3_AUX            
          	               	2         	251B3     	GND                 

C2369     	Q_CAP_C0402    	          	          	                    
          	               	1         	224A4     	FM_AC_PWR_BTN_R_N   
          	               	2         	224A4     	GND                 

C2370     	Q_CAP_0402     	          	          	                    
          	               	1         	224A2     	P3V3_AUX            
          	               	2         	224A2     	GND                 

C2371     	Q_CAP_0402     	          	          	                    
          	               	1         	245B1     	FM_AC_PWR_BTN_PDB_N 
          	               	2         	245B1     	GND                 

C2372     	Q_CAP_0402     	          	          	                    
          	               	1         	144B3     	PRSNT_SWB_ISO_N     
          	               	2         	144B3     	GND                 

C2373     	Q_CAP_0402     	          	          	                    
          	               	1         	144B3     	PRSNT_CABLE_SWB_B2_ISO_N
          	               	2         	144B3     	GND                 

C2374     	Q_CAP_0402     	          	          	                    
          	               	1         	144A3     	PRSNT_CABLE_SWB_B1_ISO_N
          	               	2         	144A3     	GND                 

C2376     	Q_CAP_0402     	          	          	                    
          	               	1         	158A2     	P3V3_AUX            
          	               	2         	158A2     	GND                 

C2377     	Q_CAP_0402     	          	          	                    
          	               	1         	164A2     	P3V3_AUX            
          	               	2         	164A2     	GND                 

C2378     	Q_CAP_0402     	          	          	                    
          	               	1         	191A4     	P3V3_E1S_0          
          	               	2         	191A4     	GND                 

C2379     	Q_CAP_C0402    	          	          	                    
          	               	1         	307B3     	UV_ADR_P2V5_COMP    
          	               	2         	307B3     	GND                 

C2380     	Q_CAP_C0402    	          	          	                    
          	               	1         	307B3     	UV_P2V5_COMP        
          	               	2         	307A3     	GND                 

C2381     	Q_CAP_C0402    	          	          	                    
          	               	1         	307B3     	P12V_AUX_UV_ADR_TRIGGER
          	               	2         	307B3     	GND                 

C2382     	Q_CAP_C0402    	          	          	                    
          	               	1         	307B3     	P12V_AUX_UV_TRIGGER 
          	               	2         	307A3     	GND                 

C2383     	Q_CAP_C0402    	          	          	                    
          	               	1         	307B3     	P12V_AUX            
          	               	2         	307B3     	GND                 

C2384     	Q_CAP_C0402    	          	          	                    
          	               	1         	307B3     	P12V_AUX            
          	               	2         	307B3     	GND                 

C2385     	Q_CAP_C0402    	          	          	                    
          	               	1         	307A3     	DSW_PWROK_P2V5_COMP 
          	               	2         	307A3     	GND                 

C2386     	Q_CAP_C0402    	          	          	                    
          	               	1         	307A3     	PWRGD_DSW_PWROK_TRIGGER
          	               	2         	307A3     	GND                 

C2387     	Q_CAP_C0402    	          	          	                    
          	               	1         	307A3     	P12V_AUX            
          	               	2         	307A3     	GND                 

C2388     	Q_CAP_C0402    	          	          	                    
          	               	1         	306B3     	OC_P2V5_COMP        
          	               	2         	306B3     	GND                 

C2389     	Q_CAP_C0402    	          	          	                    
          	               	1         	306B3     	HSC_OC_VOL          
          	               	2         	306B3     	GND                 

C2390     	Q_CAP_C0402    	          	          	                    
          	               	1         	306B3     	P12V_AUX            
          	               	2         	306B3     	GND                 

C2391     	Q_CAP_0402     	          	          	                    
          	               	1         	144A3     	PRSNT_CABLE_GPU_A3_ISO_N
          	               	2         	144A3     	GND                 

C2392     	Q_CAP_0402     	          	          	                    
          	               	1         	306A4     	U205_VDD            
          	               	2         	306A4     	GND                 

C2393     	Q_CAP_0402     	          	          	                    
          	               	1         	306B3     	U369_VDD            
          	               	2         	306B3     	GND                 

C2394     	Q_CAP_0402     	          	          	                    
          	               	1         	306A3     	U206_VDD            
          	               	2         	306A3     	GND                 

C2443     	Q_CAP_C0402    	          	          	                    
          	               	1         	278B4     	PVNN_TERM_CPU0      
          	               	2         	278B4     	GND                 

C2444     	Q_CAP_0402     	          	          	                    
          	               	1         	278B4     	PVNN_TERM_CPU0      
          	               	2         	278B4     	GND                 

C2445     	Q_CAP_0402     	          	          	                    
          	               	1         	299B4     	FM_PVPP_HBM_CPU1_EN 
          	               	2         	299B4     	GND                 

C2446     	Q_CAP_0402     	          	          	                    
          	               	1         	284A3     	PVCCFA_EHV_FIVRA_CPU1_EN_R
          	               	2         	284A3     	GND                 

C2447     	Q_CAP_0402     	          	          	                    
          	               	1         	284A3     	PWRGD_PVCCFA_EHV_FIVRA_CPU1_R
          	               	2         	284A3     	GND                 

C2448     	Q_CAP_C0603    	          	          	                    
          	               	1         	284B1     	PVNN_TERM_CPU1      
          	               	2         	284B1     	GND                 

C2449     	Q_CAP_C0402    	          	          	                    
          	               	1         	284B1     	PVNN_TERM_CPU1      
          	               	2         	284B1     	GND                 

C2450     	Q_CAP_0402     	          	          	                    
          	               	1         	292B4     	PWRGD_PVCCINFAON_CPU1_R
          	               	2         	292B3     	GND                 

C2451     	Q_CAP_0402     	          	          	                    
          	               	1         	292B4     	PVCCINFAON_CPU1_EN_R
          	               	2         	292B4     	GND                 

C2452     	Q_CAP_0402     	          	          	                    
          	               	1         	292A4     	PVCCFA_EHV_CPU1_EN_R
          	               	2         	292A3     	GND                 

C2453     	Q_CAP_0402     	          	          	                    
          	               	1         	292A4     	PWRGD_PVCCFA_EHV_CPU1_R
          	               	2         	292A3     	GND                 

C2454     	Q_CAP_0402     	          	          	                    
          	               	1         	296B4     	PWRGD_PVCCD_HV_CPU1_R
          	               	2         	296B3     	GND                 

C2458     	Q_CAP_0402     	          	          	                    
          	               	1         	305B2     	P3V3_AUX            
          	               	2         	305A2     	GND                 

C2459     	Q_CAP_0603     	          	          	                    
          	               	1         	305A3     	P12V_HSC_TEMP_D+    
          	               	2         	305A3     	P12V_HSC_TEMP_D-    

C2460     	Q_CAP_0402     	          	          	                    
          	               	1         	299B3     	PWRGD_PVPP_HBM_CPU1_R
          	               	2         	299B2     	GND                 

C2541     	Q_CAP_C0402    	          	          	                    
          	               	1         	259A4     	P3V3_AUX_EN         
          	               	2         	259A4     	GND                 

C2859     	Q_CAP_0402     	          	          	                    
          	               	1         	284B4     	PWRGD_PVCCIN_CPU1_R 
          	               	2         	284B3     	GND                 

C2860     	Q_CAP_0402     	          	          	                    
          	               	1         	284B4     	PVCCIN_CPU1_EN_R    
          	               	2         	284B3     	GND                 

C3266     	Q_CAP_0402     	          	          	                    
          	               	1         	266B4     	PWRGD_PVCCIN_CPU0_R 
          	               	2         	266B3     	GND                 

C3267     	Q_CAP_0402     	          	          	                    
          	               	1         	266B4     	PVCCIN_CPU0_EN_R    
          	               	2         	266B3     	GND                 

C3268     	Q_CAP_0402     	          	          	                    
          	               	1         	266A3     	PVCCFA_EHV_FIVRA_CPU0_EN_R
          	               	2         	266A3     	GND                 

C3269     	Q_CAP_0402     	          	          	                    
          	               	1         	266A3     	PWRGD_PVCCFA_EHV_FIVRA_CPU0_R
          	               	2         	266A3     	GND                 

C3270     	Q_CAP_C0603    	          	          	                    
          	               	1         	266A1     	PVNN_TERM_CPU0      
          	               	2         	266A1     	GND                 

C3271     	Q_CAP_C0402    	          	          	                    
          	               	1         	266A1     	PVNN_TERM_CPU0      
          	               	2         	266A1     	GND                 

C3273     	Q_CAP_0402     	          	          	                    
          	               	1         	274B4     	PWRGD_PVCCINFAON_CPU0_R
          	               	2         	274B3     	GND                 

C3274     	Q_CAP_0402     	          	          	                    
          	               	1         	274B4     	PVCCINFAON_CPU0_EN_R
          	               	2         	274B3     	GND                 

C3275     	Q_CAP_0402     	          	          	                    
          	               	1         	274A4     	PVCCFA_EHV_CPU0_EN_R
          	               	2         	274A3     	GND                 

C3276     	Q_CAP_0402     	          	          	                    
          	               	1         	274A4     	PWRGD_PVCCFA_EHV_CPU0_R
          	               	2         	274A3     	GND                 

C4562     	Q_CAP_C0402    	          	          	                    
          	               	1         	306B3     	U369_VDD            
          	               	2         	306B3     	GND                 

C5229     	Q_CAP_C0402    	          	          	                    
          	               	1         	152A3     	P3V3_AUX            
          	               	2         	152A3     	GND                 

C5232     	Q_CAP_0402     	          	          	                    
          	               	1         	152A3     	PD_U5201_RSTN       
          	               	2         	152A3     	GND                 

C5234     	Q_CAP_0402     	          	          	                    
          	               	1         	152A3     	P3V3_AUX            
          	               	2         	152A3     	GND                 

C5236     	Q_CAP_0402     	          	          	                    
          	               	1         	152A2     	PD_U5201_VREG       
          	               	2         	152A2     	GND                 

D0        	Q_LED_SMLF     	          	          	                    
          	               	A         	218B4     	PU_PLD_HEARTBEAT_LVC3
          	               	C         	218B3     	FM_PLD_HEARTBEAT_LVC3_D

D6        	Q_LED_SMLF     	          	          	                    
          	               	A         	218B2     	LED_CPU_RMCA_CATERR 
          	               	C         	218B2     	GND                 

D7        	BAT547F        	          	          	                    
          	               	1         	260A4     	P3V3                
          	               	3         	260A4     	P5V                 

D42       	SCHOTTKY_12    	          	          	                    
          	               	1         	115B3     	PWRGD_FAIL_CPU0_AB_R1
          	               	2         	115B2     	P3V3_AUX            

D43       	SCHOTTKY_12    	          	          	                    
          	               	1         	115B3     	PWRGD_FAIL_CPU0_CD_R1
          	               	2         	115B2     	P3V3_AUX            

D44       	SCHOTTKY_12    	          	          	                    
          	               	1         	115B3     	PWRGD_FAIL_CPU0_EF_R1
          	               	2         	115B2     	P3V3_AUX            

D45       	SCHOTTKY_12    	          	          	                    
          	               	1         	115B3     	PWRGD_FAIL_CPU0_GH_R1
          	               	2         	115B2     	P3V3_AUX            

D46       	SCHOTTKY_12    	          	          	                    
          	               	1         	115B3     	PWRGD_FAIL_CPU1_AB_R1
          	               	2         	115B2     	P3V3_AUX            

D47       	SCHOTTKY_12    	          	          	                    
          	               	1         	115B3     	PWRGD_FAIL_CPU1_CD_R1
          	               	2         	115B2     	P3V3_AUX            

D48       	SCHOTTKY_12    	          	          	                    
          	               	1         	115A3     	PWRGD_FAIL_CPU1_EF_R1
          	               	2         	115A2     	P3V3_AUX            

D49       	SCHOTTKY_12    	          	          	                    
          	               	1         	115A3     	PWRGD_FAIL_CPU1_GH_R1
          	               	2         	115A2     	P3V3_AUX            

D65       	Q_LED_SMLF     	          	          	                    
          	               	A         	256B4     	LED_RST_PLD_CPU0_DRAM_AB_N
          	               	C         	256B4     	LED_RST_PLD_CPU0_DRAM_AB_N_D

D66       	Q_LED_SMLF     	          	          	                    
          	               	A         	256B4     	LED_RST_PLD_CPU0_DRAM_CD_N
          	               	C         	256B4     	LED_RST_PLD_CPU0_DRAM_CD_N_D

D67       	Q_LED_SMLF     	          	          	                    
          	               	A         	256B4     	LED_RST_PLD_CPU0_DRAM_EF_N
          	               	C         	256B4     	LED_RST_PLD_CPU0_DRAM_EF_N_D

D68       	Q_LED_SMLF     	          	          	                    
          	               	A         	256A4     	LED_RST_PLD_CPU0_DRAM_GH_N
          	               	C         	256A4     	LED_RST_PLD_CPU0_DRAM_GH_N_D

D69       	Q_LED_SMLF     	          	          	                    
          	               	A         	256B2     	LED_RST_PLD_CPU1_DRAM_AB_N
          	               	C         	256B2     	LED_RST_PLD_CPU1_DRAM_AB_N_D

D70       	Q_LED_SMLF     	          	          	                    
          	               	A         	256B2     	LED_RST_PLD_CPU1_DRAM_CD_N
          	               	C         	256B2     	LED_RST_PLD_CPU1_DRAM_CD_N_D

D71       	Q_LED_SMLF     	          	          	                    
          	               	A         	256B2     	LED_RST_PLD_CPU1_DRAM_EF_N
          	               	C         	256B2     	LED_RST_PLD_CPU1_DRAM_EF_N_D

D72       	Q_LED_SMLF     	          	          	                    
          	               	A         	256A2     	LED_RST_PLD_CPU1_DRAM_GH_N
          	               	C         	256A2     	LED_RST_PLD_CPU1_DRAM_GH_N_D

D73       	Q_LED_SMLF     	          	          	                    
          	               	A         	253B4     	LED_PWRGD_PVCCD_HV_CPU0
          	               	C         	253B4     	LED_PWRGD_PVCCD_HV_CPU0_D

D74       	Q_LED_SMLF     	          	          	                    
          	               	A         	253B4     	LED_PWRGD_PVPP_HBM_CPU0
          	               	C         	253B4     	LED_PWRGD_PVPP_HBM_CPU0_D

D75       	Q_LED_SMLF     	          	          	                    
          	               	A         	253B4     	LED_PWRGD_PVCCFA_EHV_CPU0
          	               	C         	253B4     	LED_PWRGD_PVCCFA_EHV_CPU0_D

D76       	Q_LED_SMLF     	          	          	                    
          	               	A         	253A4     	LED_PWRGD_PVCCFA_EHV_FIVRA_CPU0
          	               	C         	253A4     	LED_PWRGD_PVCCFA_EHV_FIVRA_CP_1

D77       	Q_LED_SMLF     	          	          	                    
          	               	A         	253B1     	LED_PWRGD_PVCCINFAON_CPU0
          	               	C         	253B2     	LED_PWRGD_PVCCINFAON_CPU0_D

D78       	Q_LED_SMLF     	          	          	                    
          	               	A         	253B1     	LED_PWRGD_PVNN_MAIN_CPU0
          	               	C         	253B2     	LED_PWRGD_PVNN_MAIN_CPU0_D

D79       	Q_LED_SMLF     	          	          	                    
          	               	A         	253B1     	LED_PWRGD_PVCCIN_CPU0
          	               	C         	253B2     	LED_PWRGD_PVCCIN_CPU0_D

D80       	Q_LED_SMLF     	          	          	                    
          	               	A         	254B4     	LED_PWRGD_PVCCD_HV_CPU1
          	               	C         	254B4     	LED_PWRGD_PVCCD_HV_CPU1_D

D81       	Q_LED_SMLF     	          	          	                    
          	               	A         	254B4     	LED_PWRGD_PVPP_HBM_CPU1
          	               	C         	254B4     	LED_PWRGD_PVPP_HBM_CPU1_D

D82       	Q_LED_SMLF     	          	          	                    
          	               	A         	254B4     	LED_PWRGD_PVCCFA_EHV_CPU1
          	               	C         	254B4     	LED_PWRGD_PVCCFA_EHV_CPU1_D

D83       	Q_LED_SMLF     	          	          	                    
          	               	A         	254A4     	LED_PWRGD_PVCCFA_EHV_FIVRA_CPU1
          	               	C         	254A4     	LED_PWRGD_PVCCFA_EHV_FIVRA_CP_2

D84       	Q_LED_SMLF     	          	          	                    
          	               	A         	254B1     	LED_PWRGD_PVCCINFAON_CPU1
          	               	C         	254B2     	LED_PWRGD_PVCCINFAON_CPU1_D

D85       	Q_LED_SMLF     	          	          	                    
          	               	A         	254B1     	LED_PWRGD_PVNN_MAIN_CPU1
          	               	C         	254B2     	LED_PWRGD_PVNN_MAIN_CPU1_D

D86       	Q_LED_SMLF     	          	          	                    
          	               	A         	254B1     	LED_PWRGD_PVCCIN_CPU1
          	               	C         	254B2     	LED_PWRGD_PVCCIN_CPU1_D

D87       	Q_LED_SMLF     	          	          	                    
          	               	A         	255B4     	LED_PWRGD_PCH_PWROK_R
          	               	C         	255B4     	LED_PWRGD_PCH_PWROK_R_D

D88       	Q_LED_SMLF     	          	          	                    
          	               	A         	255B4     	LED_PWRGD_SYS_PWROK_R
          	               	C         	255B4     	LED_PWRGD_SYS_PWROK_R_D

D89       	Q_LED_SMLF     	          	          	                    
          	               	A         	255B4     	LED_PWRGD_CPUPWRGD_GTL
          	               	C         	255B4     	LED_PWRGD_CPUPWRGD_GTL_D

D90       	Q_LED_SMLF     	          	          	                    
          	               	A         	255A4     	LED_RST_PLTRST_N    
          	               	C         	255A4     	LED_RST_PLTRST_N_D  

D91       	Q_LED_SMLF     	          	          	                    
          	               	A         	252B4     	LED_PWRGD_P1V8_PCH_AUX
          	               	C         	252B4     	LED_PWRGD_P1V8_PCH_AUX_D

D92       	Q_LED_SMLF     	          	          	                    
          	               	A         	252B4     	LED_PWRGD_P1V05_PCH_AUX
          	               	C         	252B4     	LED_PWRGD_P1V05_PCH_AUX_D

D93       	Q_LED_SMLF     	          	          	                    
          	               	A         	252B4     	LED_RST_RSMRST_PLD_R_N
          	               	C         	252B4     	LED_RST_RSMRST_PLD_R_N_D

D94       	Q_LED_SMLF     	          	          	                    
          	               	A         	252A4     	LED_FM_PCH_SLP_S4_N 
          	               	C         	252A4     	LED_FM_PCH_SLP_S4_N_D

D95       	Q_LED_SMLF     	          	          	                    
          	               	A         	252B1     	LED_FM_PCH_SLP_S3_N 
          	               	C         	252B2     	LED_FM_PCH_SLP_S3_N_D

D96       	Q_LED_SMLF     	          	          	                    
          	               	A         	252B1     	LED_PWRGD_PS_PWROK_PLD
          	               	C         	252B2     	LED_PWRGD_PS_PWROK_PLD_D

D97       	Q_LED_SMLF     	          	          	                    
          	               	A         	252B2     	LED_P5V_AUX         
          	               	C         	252B2     	GND                 

D98       	Q_LED_SMLF     	          	          	                    
          	               	A         	252A2     	LED_P5V             
          	               	C         	252A2     	GND                 

D99       	Q_LED_SMLF     	          	          	                    
          	               	A         	252A2     	LED_P3V3            
          	               	C         	252A2     	GND                 

D141      	SCHOTTKY_12    	          	          	                    
          	               	1         	221B4     	P3V3_AUX            
          	               	2         	221B4     	P3V3_AUX_BMC_D      

D142      	Q_LED_SMLF     	          	          	                    
          	               	A         	255B2     	LED_P12V_AUX_R1     
          	               	C         	255B2     	GND                 

D143      	Q_LED_SMLF     	          	          	                    
          	               	A         	255B2     	LED_P12V_PSU_R1     
          	               	C         	255B2     	GND                 

D144      	Q_LED_SMLF     	          	          	                    
          	               	A         	255B1     	LED_P12V_SCM_FAULT  
          	               	C         	255B1     	LED_P12V_SCM_FAULT_D2

D145      	Q_DIODE_SMLF   	          	          	                    
          	               	1         	259B4     	MB0_P12V_STBY_PWRGD 
          	               	2         	259B4     	P3V3_AUX_EN         

DB1       	TDR_3P_TH2     	          	          	                    
          	               	1         	309B4     	T1_GND              
          	               	2         	309B4     	TDR_SE_40_OHM_TOP   
          	               	3         	309B4     	TDR_SE_40_OHM_TOP   

DB2       	TDR_3P_TH2     	          	          	                    
          	               	1         	309B4     	T1_GND              
          	               	2         	309B4     	TDR_SE_40_OHM_IN1   
          	               	3         	309B4     	TDR_SE_40_OHM_IN1   

DB3       	TDR_3P_TH2     	          	          	                    
          	               	1         	309B4     	T1_GND              
          	               	2         	309B4     	TDR_SE_40_OHM_IN2   
          	               	3         	309B4     	TDR_SE_40_OHM_IN2   

DB4       	TDR_3P_TH2     	          	          	                    
          	               	1         	309B4     	T1_GND              
          	               	2         	309B4     	TDR_SE_40_OHM_IN3   
          	               	3         	309B4     	TDR_SE_40_OHM_IN3   

DB5       	TDR_3P_TH2     	          	          	                    
          	               	1         	309B4     	T1_GND              
          	               	2         	309B4     	TDR_SE_40_OHM_IN4   
          	               	3         	309B4     	TDR_SE_40_OHM_IN4   

DB6       	TDR_3P_TH2     	          	          	                    
          	               	1         	309A4     	T1_GND              
          	               	2         	309A4     	TDR_SE_40_OHM_BOT   
          	               	3         	309A4     	TDR_SE_40_OHM_BOT   

DB7       	TDR_3P_TH2     	          	          	                    
          	               	1         	309B4     	T1_GND              
          	               	2         	309B4     	TDR_SE_50_OHM_TOP   
          	               	3         	309B4     	TDR_SE_50_OHM_TOP   

DB8       	TDR_3P_TH2     	          	          	                    
          	               	1         	309B4     	T1_GND              
          	               	2         	309B4     	TDR_SE_50_OHM_IN1   
          	               	3         	309B4     	TDR_SE_50_OHM_IN1   

DB9       	TDR_3P_TH2     	          	          	                    
          	               	1         	309B4     	T1_GND              
          	               	2         	309B4     	TDR_SE_50_OHM_IN2   
          	               	3         	309B4     	TDR_SE_50_OHM_IN2   

DB10      	TDR_3P_TH2     	          	          	                    
          	               	1         	309B4     	T1_GND              
          	               	2         	309B4     	TDR_SE_50_OHM_IN3   
          	               	3         	309B4     	TDR_SE_50_OHM_IN3   

DB11      	TDR_3P_TH2     	          	          	                    
          	               	1         	309B4     	T1_GND              
          	               	2         	309B4     	TDR_SE_50_OHM_IN4   
          	               	3         	309B4     	TDR_SE_50_OHM_IN4   

DB12      	TDR_3P_TH2     	          	          	                    
          	               	1         	309A4     	T1_GND              
          	               	2         	309A4     	TDR_SE_50_OHM_BOT   
          	               	3         	309A4     	TDR_SE_50_OHM_BOT   

DB13      	TDR_3P_TH2     	          	          	                    
          	               	1         	309B4     	T1_GND              
          	               	2         	309B4     	TDR_SE_40_OHM_IN5   
          	               	3         	309B4     	TDR_SE_40_OHM_IN5   

DB14      	TDR_3P_TH2     	          	          	                    
          	               	1         	309B4     	T1_GND              
          	               	2         	309B4     	TDR_SE_40_OHM_IN6   
          	               	3         	309B4     	TDR_SE_40_OHM_IN6   

DB15      	TDR_3P_TH2     	          	          	                    
          	               	1         	309B4     	T1_GND              
          	               	2         	309B4     	TDR_SE_50_OHM_IN5   
          	               	3         	309B4     	TDR_SE_50_OHM_IN5   

DB16      	TDR_3P_TH2     	          	          	                    
          	               	1         	309B4     	T1_GND              
          	               	2         	309B4     	TDR_SE_50_OHM_IN6   
          	               	3         	309B4     	TDR_SE_50_OHM_IN6   

DM9       	DUMMY_SYMBOL   	          	          	                    
          	               	1         	311B3     	NC                  

DM13      	DUMMY_SYMBOL   	          	          	                    
          	               	1         	311B2     	NC                  

FS1       	Q_FUSE_SMLF    	          	          	                    
          	               	1         	304B3     	P12V_PSU            
          	               	2         	304B3     	P12V_PSU_FUSE       

H15       	HOLE_TH        	          	          	                    
          	               	1         	310B4     	NC                  

H16       	HOLE_TH        	          	          	                    
          	               	1         	310A4     	NC                  

H17       	HOLE_TH        	          	          	                    
          	               	1         	310B4     	NC                  

H18       	HOLE_TH        	          	          	                    
          	               	1         	310A4     	NC                  

H19       	HOLE_TH        	          	          	                    
          	               	1         	310B4     	NC                  

H20       	HOLE_TH        	          	          	                    
          	               	1         	310A4     	NC                  

H21       	HOLE_TH        	          	          	                    
          	               	1         	310B4     	NC                  

H22       	HOLE_TH        	          	          	                    
          	               	1         	310A4     	NC                  

H23       	HOLE_TH        	          	          	                    
          	               	1         	310B4     	NC                  

H24       	HOLE_TH        	          	          	                    
          	               	1         	310A4     	NC                  

H25       	HOLE_TH        	          	          	                    
          	               	1         	310B4     	NC                  

H26       	HOLE_TH        	          	          	                    
          	               	1         	310A4     	NC                  

H27       	HOLE_TH        	          	          	                    
          	               	1         	310B4     	NC                  

H28       	HOLE_TH        	          	          	                    
          	               	1         	310B3     	NC                  

H29       	HOLE_TH        	          	          	                    
          	               	1         	310B3     	NC                  

H30       	HOLE_TH        	          	          	                    
          	               	1         	310B3     	NC                  

H31       	HOLE_TH        	          	          	                    
          	               	1         	310B2     	GND                 

H32       	HOLE_TH        	          	          	                    
          	               	1         	310B1     	GND                 

H36       	HOLE_TH        	          	          	                    
          	               	1         	310B2     	NC                  

H38       	HOLE_TH        	          	          	                    
          	               	1         	310B2     	NC                  

H44       	HOLE_TH        	          	          	                    
          	               	1         	310B4     	GND                 

H45       	HOLE_TH        	          	          	                    
          	               	1         	310B4     	GND                 

H47       	HOLE_TH        	          	          	                    
          	               	1         	310B4     	GND                 

H49       	HOLE_TH        	          	          	                    
          	               	1         	310B4     	GND                 

H74       	HOLE_TH        	          	          	                    
          	               	1         	310B2     	NC                  

H75       	HOLE_TH        	          	          	                    
          	               	1         	310B2     	NC                  

H76       	HOLE_TH        	          	          	                    
          	               	1         	310A3     	GND                 

H77       	HOLE_TH        	          	          	                    
          	               	1         	310A3     	GND                 

H86       	HOLE_TH        	          	          	                    
          	               	1         	310B4     	GND                 

H87       	HOLE_TH        	          	          	                    
          	               	1         	310B4     	GND                 

H88       	HOLE_TH        	          	          	                    
          	               	1         	310B4     	GND                 

H89       	HOLE_TH        	          	          	                    
          	               	1         	310B4     	GND                 

H90       	HOLE_TH        	          	          	                    
          	               	1         	310B1     	NC                  

H91       	HOLE_TH        	          	          	                    
          	               	1         	310B4     	GND                 

H92       	HOLE_TH        	          	          	                    
          	               	1         	310B4     	GND                 

H93       	HOLE_TH        	          	          	                    
          	               	1         	310B4     	GND                 

H94       	HOLE_TH        	          	          	                    
          	               	1         	310B4     	GND                 

H95       	HOLE_TH        	          	          	                    
          	               	1         	310B4     	GND                 

H96       	HOLE_TH        	          	          	                    
          	               	1         	310B4     	GND                 

H97       	HOLE_TH        	          	          	                    
          	               	1         	310B3     	GND                 

H98       	HOLE_TH        	          	          	                    
          	               	1         	310B3     	GND                 

H99       	HOLE_TH        	          	          	                    
          	               	1         	310B3     	GND                 

H100      	HOLE_TH        	          	          	                    
          	               	1         	310B3     	GND                 

H101      	HOLE_TH        	          	          	                    
          	               	1         	310B3     	GND                 

H102      	HOLE_TH        	          	          	                    
          	               	1         	310B3     	GND                 

H103      	HOLE_TH        	          	          	                    
          	               	1         	310B2     	GND                 

H104      	HOLE_TH        	          	          	                    
          	               	1         	310B2     	GND                 

H105      	HOLE_TH        	          	          	                    
          	               	1         	310B2     	GND                 

H106      	HOLE_TH        	          	          	                    
          	               	1         	310B2     	GND                 

H111      	GND_HOLE_TH    	          	          	                    
          	               	2         	310A4     	GND                 
          	               	3         	310A4     	GND                 
          	               	4         	310A4     	GND                 
          	               	5         	310A4     	GND                 
          	               	6         	310A4     	GND                 
          	               	7         	310A4     	GND                 
          	               	8         	310A4     	GND                 
          	               	9         	310A4     	GND                 

H112      	GND_HOLE_TH    	          	          	                    
          	               	2         	310A4     	GND                 
          	               	3         	310A4     	GND                 
          	               	4         	310A4     	GND                 
          	               	5         	310A4     	GND                 
          	               	6         	310A4     	GND                 
          	               	7         	310A4     	GND                 
          	               	8         	310A4     	GND                 
          	               	9         	310A4     	GND                 

H113      	GND_HOLE_TH    	          	          	                    
          	               	2         	310A4     	GND                 
          	               	3         	310A4     	GND                 
          	               	4         	310A4     	GND                 
          	               	5         	310A4     	GND                 
          	               	6         	310A4     	GND                 
          	               	7         	310A4     	GND                 
          	               	8         	310A4     	GND                 
          	               	9         	310A4     	GND                 

H114      	GND_HOLE_TH    	          	          	                    
          	               	2         	310A3     	GND                 
          	               	3         	310A3     	GND                 
          	               	4         	310A3     	GND                 
          	               	5         	310A4     	GND                 
          	               	6         	310A4     	GND                 
          	               	7         	310A3     	GND                 
          	               	8         	310A3     	GND                 
          	               	9         	310A3     	GND                 

H115      	GND_HOLE_TH    	          	          	                    
          	               	2         	310A3     	GND                 
          	               	3         	310A3     	GND                 
          	               	4         	310A3     	GND                 
          	               	5         	310A3     	GND                 
          	               	6         	310A3     	GND                 
          	               	7         	310A3     	GND                 
          	               	8         	310A3     	GND                 
          	               	9         	310A3     	GND                 

H120      	HOLE_TH        	          	          	                    
          	               	1         	310A2     	NC                  

H122      	HOLE_TH        	          	          	                    
          	               	1         	310A2     	NC                  

H124      	HOLE_TH        	          	          	                    
          	               	1         	310A2     	NC                  

H125      	HOLE_TH        	          	          	                    
          	               	1         	310A2     	NC                  

H126      	HOLE_TH        	          	          	                    
          	               	1         	310A1     	NC                  

H127      	HOLE_TH        	          	          	                    
          	               	1         	310A1     	NC                  

H128      	HOLE_TH        	          	          	                    
          	               	1         	310B2     	GND                 

H129      	HOLE_TH        	          	          	                    
          	               	1         	310B1     	GND                 

J1        	SCONN288_ADR50017P130CC	          	          	                    
          	               	1         	82B1      	P12V_S3_AUX_CPU0_NVDIMM
          	               	2         	82B4      	TP_CHA_CPU0_DIMM1_FRU_0
          	               	3         	82B4      	P3V3_AUX            
          	               	4         	82B4      	I3C_SPD_DDRABCD_CPU0_LVC1_SCL_R
          	               	5         	82B4      	I3C_SPD_DDRABCD_CPU0_LVC1_SDA
          	               	6         	82B1      	GND                 
          	               	7         	82B4      	M_A_CPU0_SA_DQ<0>   
          	               	8         	82B1      	GND                 
          	               	9         	82B4      	M_A_CPU0_SA_DQ<1>   
          	               	10        	82B1      	GND                 
          	               	11        	82B2      	M_A_CPU0_SA_DQS_DP<0>
          	               	12        	82B2      	M_A_CPU0_SA_DQS_DN<0>
          	               	13        	82B1      	GND                 
          	               	14        	82B4      	M_A_CPU0_SA_DQ<4>   
          	               	15        	82B1      	GND                 
          	               	16        	82B4      	M_A_CPU0_SA_DQ<5>   
          	               	17        	82B1      	GND                 
          	               	18        	82B4      	M_A_CPU0_SA_DQ<8>   
          	               	19        	82B1      	GND                 
          	               	20        	82B4      	M_A_CPU0_SA_DQ<9>   
          	               	21        	82B1      	GND                 
          	               	22        	82B2      	M_A_CPU0_SA_DQS_DP<1>
          	               	23        	82B2      	M_A_CPU0_SA_DQS_DN<1>
          	               	24        	82B1      	GND                 
          	               	25        	82B4      	M_A_CPU0_SA_DQ<12>  
          	               	26        	82B1      	GND                 
          	               	27        	82B4      	M_A_CPU0_SA_DQ<13>  
          	               	28        	82B1      	GND                 
          	               	29        	82B4      	M_A_CPU0_SA_DQ<16>  
          	               	30        	82B1      	GND                 
          	               	31        	82B4      	M_A_CPU0_SA_DQ<17>  
          	               	32        	82B1      	GND                 
          	               	33        	82B2      	M_A_CPU0_SA_DQS_DP<2>
          	               	34        	82B2      	M_A_CPU0_SA_DQS_DN<2>
          	               	35        	82B1      	GND                 
          	               	36        	82B4      	M_A_CPU0_SA_DQ<20>  
          	               	37        	82B1      	GND                 
          	               	38        	82B4      	M_A_CPU0_SA_DQ<21>  
          	               	39        	82B1      	GND                 
          	               	40        	82B4      	M_A_CPU0_SA_DQ<24>  
          	               	41        	82B1      	GND                 
          	               	42        	82B4      	M_A_CPU0_SA_DQ<25>  
          	               	43        	82B1      	GND                 
          	               	44        	82B2      	M_A_CPU0_SA_DQS_DP<3>
          	               	45        	82B2      	M_A_CPU0_SA_DQS_DN<3>
          	               	46        	82B1      	GND                 
          	               	47        	82B4      	M_A_CPU0_SA_DQ<28>  
          	               	48        	82B1      	GND                 
          	               	49        	82B4      	M_A_CPU0_SA_DQ<29>  
          	               	50        	82B1      	GND                 
          	               	51        	82B4      	M_A_CPU0_SA_CB<0>   
          	               	52        	82B1      	GND                 
          	               	53        	82B4      	M_A_CPU0_SA_CB<1>   
          	               	54        	82B1      	GND                 
          	               	55        	82B2      	M_A_CPU0_SA_DQS_DP<4>
          	               	56        	82B2      	M_A_CPU0_SA_DQS_DN<4>
          	               	57        	82B1      	GND                 
          	               	58        	82B4      	M_A_CPU0_SA_CB<4>   
          	               	59        	82B1      	GND                 
          	               	60        	82B4      	M_A_CPU0_SA_CB<5>   
          	               	61        	82B1      	GND                 
          	               	62        	82B4      	M_A_CPU0_ALERT_N    
          	               	63        	82B1      	GND                 
          	               	64        	82B4      	M_A_CPU0_SA_CS_N<0> 
          	               	65        	82B1      	GND                 
          	               	66        	82B4      	M_A_CPU0_SA_CA<0>   
          	               	67        	82B1      	GND                 
          	               	68        	82B4      	M_A_CPU0_SA_CA<2>   
          	               	69        	82B1      	GND                 
          	               	70        	82B4      	M_A_CPU0_SA_CA<4>   
          	               	71        	82B1      	GND                 
          	               	72        	82B4      	M_A_CPU0_SA_CA<6>   
          	               	73        	82B1      	GND                 
          	               	74        	82B4      	M_A_CPU0_SA_PAR     
          	               	75        	82B1      	GND                 
          	               	76        	82B4      	M_A_CPU0_SB_CA<0>   
          	               	77        	82B1      	GND                 
          	               	78        	82B4      	M_A_CPU0_SB_CA<2>   
          	               	79        	82B1      	GND                 
          	               	80        	82B4      	M_A_CPU0_SB_CA<4>   
          	               	81        	82B1      	GND                 
          	               	82        	82B4      	M_A_CPU0_SB_CA<6>   
          	               	83        	82B1      	GND                 
          	               	84        	82B4      	M_A_CPU0_SB_CS_N<0> 
          	               	85        	82B1      	GND                 
          	               	86        	82A4      	M_A_CPU0_SA_RSP<0>  
          	               	87        	82A4      	M_A_CPU0_SB_RSP<0>  
          	               	88        	82B1      	GND                 
          	               	89        	82B4      	M_A_CPU0_SB_CB<4>   
          	               	90        	82B1      	GND                 
          	               	91        	82B4      	M_A_CPU0_SB_CB<5>   
          	               	92        	82B1      	GND                 
          	               	93        	82B2      	M_A_CPU0_SB_DQS_DP<9>
          	               	94        	82B2      	M_A_CPU0_SB_DQS_DN<9>
          	               	95        	82B1      	GND                 
          	               	96        	82B4      	M_A_CPU0_SB_CB<0>   
          	               	97        	82B1      	GND                 
          	               	98        	82B4      	M_A_CPU0_SB_CB<1>   
          	               	99        	82B1      	GND                 
          	               	100       	82B4      	M_A_CPU0_SB_DQ<0>   
          	               	101       	82B1      	GND                 
          	               	102       	82B4      	M_A_CPU0_SB_DQ<1>   
          	               	103       	82B1      	GND                 
          	               	104       	82B2      	M_A_CPU0_SB_DQS_DP<0>
          	               	105       	82B2      	M_A_CPU0_SB_DQS_DN<0>
          	               	106       	82B1      	GND                 
          	               	107       	82B4      	M_A_CPU0_SB_DQ<4>   
          	               	108       	82B1      	GND                 
          	               	109       	82B4      	M_A_CPU0_SB_DQ<5>   
          	               	110       	82B1      	GND                 
          	               	111       	82B4      	M_A_CPU0_SB_DQ<8>   
          	               	112       	82B1      	GND                 
          	               	113       	82B4      	M_A_CPU0_SB_DQ<9>   
          	               	114       	82B1      	GND                 
          	               	115       	82B2      	M_A_CPU0_SB_DQS_DP<1>
          	               	116       	82B2      	M_A_CPU0_SB_DQS_DN<1>
          	               	117       	82B1      	GND                 
          	               	118       	82B4      	M_A_CPU0_SB_DQ<12>  
          	               	119       	82B1      	GND                 
          	               	120       	82B4      	M_A_CPU0_SB_DQ<13>  
          	               	121       	82B1      	GND                 
          	               	122       	82B4      	M_A_CPU0_SB_DQ<16>  
          	               	123       	82B1      	GND                 
          	               	124       	82B4      	M_A_CPU0_SB_DQ<17>  
          	               	125       	82B1      	GND                 
          	               	126       	82B2      	M_A_CPU0_SB_DQS_DP<2>
          	               	127       	82B2      	M_A_CPU0_SB_DQS_DN<2>
          	               	128       	82B1      	GND                 
          	               	129       	82B4      	M_A_CPU0_SB_DQ<20>  
          	               	130       	82B1      	GND                 
          	               	131       	82B4      	M_A_CPU0_SB_DQ<21>  
          	               	132       	82B1      	GND                 
          	               	133       	82B4      	M_A_CPU0_SB_DQ<24>  
          	               	134       	82B1      	GND                 
          	               	135       	82B4      	M_A_CPU0_SB_DQ<25>  
          	               	136       	82B1      	GND                 
          	               	137       	82B2      	M_A_CPU0_SB_DQS_DP<3>
          	               	138       	82B2      	M_A_CPU0_SB_DQS_DN<3>
          	               	139       	82B1      	GND                 
          	               	140       	82B4      	M_A_CPU0_SB_DQ<28>  
          	               	141       	82B1      	GND                 
          	               	142       	82B4      	M_A_CPU0_SB_DQ<29>  
          	               	143       	82B1      	GND                 
          	               	144       	82B4      	TP_CHA_CPU0_DIMM1_FRU_1
          	               	145       	82B1      	P12V_S3_AUX_CPU0_NVDIMM
          	               	146       	82B1      	P12V_S3_AUX_CPU0_NVDIMM
          	               	147       	82B4      	PWRGD_CHA_CPU0_DIMM1
          	               	148       	82B4      	PD_CHA_CPU0_DIMM1_SAA
          	               	149       	82B4      	TP_CHA_CPU0_DIMM1_FRU_2
          	               	150       	82B4      	TP_CHA_CPU0_DIMM1_FRU_3
          	               	151       	82B1      	GND                 
          	               	152       	82B4      	M_A_CPU0_SA_DQ<2>   
          	               	153       	82B1      	GND                 
          	               	154       	82B4      	M_A_CPU0_SA_DQ<3>   
          	               	155       	82B1      	GND                 
          	               	156       	82B2      	M_A_CPU0_SA_DQS_DN<5>
          	               	157       	82B2      	M_A_CPU0_SA_DQS_DP<5>
          	               	158       	82B1      	GND                 
          	               	159       	82B4      	M_A_CPU0_SA_DQ<6>   
          	               	160       	82B1      	GND                 
          	               	161       	82B4      	M_A_CPU0_SA_DQ<7>   
          	               	162       	82B1      	GND                 
          	               	163       	82B4      	M_A_CPU0_SA_DQ<10>  
          	               	164       	82B1      	GND                 
          	               	165       	82B4      	M_A_CPU0_SA_DQ<11>  
          	               	166       	82B1      	GND                 
          	               	167       	82B2      	M_A_CPU0_SA_DQS_DN<6>
          	               	168       	82B2      	M_A_CPU0_SA_DQS_DP<6>
          	               	169       	82B1      	GND                 
          	               	170       	82B4      	M_A_CPU0_SA_DQ<14>  
          	               	171       	82B1      	GND                 
          	               	172       	82B4      	M_A_CPU0_SA_DQ<15>  
          	               	173       	82B1      	GND                 
          	               	174       	82B4      	M_A_CPU0_SA_DQ<18>  
          	               	175       	82B1      	GND                 
          	               	176       	82B4      	M_A_CPU0_SA_DQ<19>  
          	               	177       	82B1      	GND                 
          	               	178       	82B2      	M_A_CPU0_SA_DQS_DN<7>
          	               	179       	82B2      	M_A_CPU0_SA_DQS_DP<7>
          	               	180       	82B1      	GND                 
          	               	181       	82B4      	M_A_CPU0_SA_DQ<22>  
          	               	182       	82B1      	GND                 
          	               	183       	82B4      	M_A_CPU0_SA_DQ<23>  
          	               	184       	82B1      	GND                 
          	               	185       	82B4      	M_A_CPU0_SA_DQ<26>  
          	               	186       	82B1      	GND                 
          	               	187       	82B4      	M_A_CPU0_SA_DQ<27>  
          	               	188       	82B1      	GND                 
          	               	189       	82B2      	M_A_CPU0_SA_DQS_DN<8>
          	               	190       	82B2      	M_A_CPU0_SA_DQS_DP<8>
          	               	191       	82B1      	GND                 
          	               	192       	82B4      	M_A_CPU0_SA_DQ<30>  
          	               	193       	82B1      	GND                 
          	               	194       	82B4      	M_A_CPU0_SA_DQ<31>  
          	               	195       	82B1      	GND                 
          	               	196       	82B4      	M_A_CPU0_SA_CB<2>   
          	               	197       	82B1      	GND                 
          	               	198       	82B4      	M_A_CPU0_SA_CB<3>   
          	               	199       	82B1      	GND                 
          	               	200       	82B2      	M_A_CPU0_SA_DQS_DN<9>
          	               	201       	82B2      	M_A_CPU0_SA_DQS_DP<9>
          	               	202       	82B1      	GND                 
          	               	203       	82B4      	M_A_CPU0_SA_CB<6>   
          	               	204       	82B1      	GND                 
          	               	205       	82B4      	M_A_CPU0_SA_CB<7>   
          	               	206       	82B1      	GND                 
          	               	207       	82B4      	RST_M_AB_CPU0_FPGA_N
          	               	208       	82B1      	GND                 
          	               	209       	82B4      	M_A_CPU0_SA_CS_N<1> 
          	               	210       	82B1      	GND                 
          	               	211       	82B4      	M_A_CPU0_SA_CA<1>   
          	               	212       	82B1      	GND                 
          	               	213       	82B4      	M_A_CPU0_SA_CA<3>   
          	               	214       	82B1      	GND                 
          	               	215       	82B4      	M_A_CPU0_SA_CA<5>   
          	               	216       	82B1      	GND                 
          	               	217       	82B4      	M_A_CPU0_CLK_DP<0>  
          	               	218       	82B4      	M_A_CPU0_CLK_DN<0>  
          	               	219       	82B1      	GND                 
          	               	220       	82B4      	TP_CHA_CPU0_DIMM1_FRU_4
          	               	221       	82B4      	M_A_CPU0_SB_CA<1>   
          	               	222       	82B1      	GND                 
          	               	223       	82B4      	M_A_CPU0_SB_CA<3>   
          	               	224       	82B1      	GND                 
          	               	225       	82B4      	M_A_CPU0_SB_CA<5>   
          	               	226       	82B1      	GND                 
          	               	227       	82B4      	M_A_CPU0_SB_PAR     
          	               	228       	82B1      	GND                 
          	               	229       	82B4      	M_A_CPU0_SB_CS_N<1> 
          	               	230       	82B1      	GND                 
          	               	231       	82B4      	TP_CHA_CPU0_DIMM1_FRU_5
          	               	232       	82B4      	TP_CHA_CPU0_DIMM1_FRU_6
          	               	233       	82B1      	GND                 
          	               	234       	82B4      	M_A_CPU0_SB_CB<6>   
          	               	235       	82B1      	GND                 
          	               	236       	82B4      	M_A_CPU0_SB_CB<7>   
          	               	237       	82B1      	GND                 
          	               	238       	82B2      	M_A_CPU0_SB_DQS_DN<4>
          	               	239       	82B2      	M_A_CPU0_SB_DQS_DP<4>
          	               	240       	82B1      	GND                 
          	               	241       	82B4      	M_A_CPU0_SB_CB<2>   
          	               	242       	82B1      	GND                 
          	               	243       	82B4      	M_A_CPU0_SB_CB<3>   
          	               	244       	82B1      	GND                 
          	               	245       	82B4      	M_A_CPU0_SB_DQ<2>   
          	               	246       	82B1      	GND                 
          	               	247       	82B4      	M_A_CPU0_SB_DQ<3>   
          	               	248       	82B1      	GND                 
          	               	249       	82B2      	M_A_CPU0_SB_DQS_DN<5>
          	               	250       	82B2      	M_A_CPU0_SB_DQS_DP<5>
          	               	251       	82B1      	GND                 
          	               	252       	82B4      	M_A_CPU0_SB_DQ<6>   
          	               	253       	82B1      	GND                 
          	               	254       	82B4      	M_A_CPU0_SB_DQ<7>   
          	               	255       	82B1      	GND                 
          	               	256       	82B4      	M_A_CPU0_SB_DQ<10>  
          	               	257       	82B1      	GND                 
          	               	258       	82B4      	M_A_CPU0_SB_DQ<11>  
          	               	259       	82B1      	GND                 
          	               	260       	82B2      	M_A_CPU0_SB_DQS_DN<6>
          	               	261       	82B2      	M_A_CPU0_SB_DQS_DP<6>
          	               	262       	82B1      	GND                 
          	               	263       	82B4      	M_A_CPU0_SB_DQ<14>  
          	               	264       	82B1      	GND                 
          	               	265       	82B4      	M_A_CPU0_SB_DQ<15>  
          	               	266       	82B1      	GND                 
          	               	267       	82B4      	M_A_CPU0_SB_DQ<18>  
          	               	268       	82B1      	GND                 
          	               	269       	82B4      	M_A_CPU0_SB_DQ<19>  
          	               	270       	82B1      	GND                 
          	               	271       	82B2      	M_A_CPU0_SB_DQS_DN<7>
          	               	272       	82B2      	M_A_CPU0_SB_DQS_DP<7>
          	               	273       	82B1      	GND                 
          	               	274       	82B4      	M_A_CPU0_SB_DQ<22>  
          	               	275       	82B1      	GND                 
          	               	276       	82B4      	M_A_CPU0_SB_DQ<23>  
          	               	277       	82B1      	GND                 
          	               	278       	82B4      	M_A_CPU0_SB_DQ<26>  
          	               	279       	82B1      	GND                 
          	               	280       	82B4      	M_A_CPU0_SB_DQ<27>  
          	               	281       	82B1      	GND                 
          	               	282       	82B2      	M_A_CPU0_SB_DQS_DN<8>
          	               	283       	82B2      	M_A_CPU0_SB_DQS_DP<8>
          	               	284       	82B1      	GND                 
          	               	285       	82B4      	M_A_CPU0_SB_DQ<30>  
          	               	286       	82B1      	GND                 
          	               	287       	82B4      	M_A_CPU0_SB_DQ<31>  
          	               	288       	82B1      	GND                 
          	               	G1        	82B1      	GND                 
          	               	G2        	82A1      	GND                 
          	               	G3        	82A1      	GND                 

J2        	SCONN288_ADR50017P087CC	          	          	                    
          	               	1         	83B1      	P12V_S3_AUX_CPU0_NVDIMM
          	               	2         	83B4      	TP_CHA_CPU0_DIMM2_FRU_0
          	               	3         	83B4      	P3V3_AUX            
          	               	4         	83B4      	I3C_SPD_DDRABCD_CPU0_LVC1_SCL_1
          	               	5         	83B4      	I3C_SPD_DDRABCD_CPU0_LVC1_SDA
          	               	6         	83B1      	GND                 
          	               	7         	83B4      	M_A_CPU0_SA_DQ<0>   
          	               	8         	83B1      	GND                 
          	               	9         	83B4      	M_A_CPU0_SA_DQ<1>   
          	               	10        	83B1      	GND                 
          	               	11        	83B2      	M_A_CPU0_SA_DQS_DP<0>
          	               	12        	83B2      	M_A_CPU0_SA_DQS_DN<0>
          	               	13        	83B1      	GND                 
          	               	14        	83B4      	M_A_CPU0_SA_DQ<4>   
          	               	15        	83B1      	GND                 
          	               	16        	83B4      	M_A_CPU0_SA_DQ<5>   
          	               	17        	83B1      	GND                 
          	               	18        	83B4      	M_A_CPU0_SA_DQ<8>   
          	               	19        	83B1      	GND                 
          	               	20        	83B4      	M_A_CPU0_SA_DQ<9>   
          	               	21        	83B1      	GND                 
          	               	22        	83B2      	M_A_CPU0_SA_DQS_DP<1>
          	               	23        	83B2      	M_A_CPU0_SA_DQS_DN<1>
          	               	24        	83B1      	GND                 
          	               	25        	83B4      	M_A_CPU0_SA_DQ<12>  
          	               	26        	83B1      	GND                 
          	               	27        	83B4      	M_A_CPU0_SA_DQ<13>  
          	               	28        	83B1      	GND                 
          	               	29        	83B4      	M_A_CPU0_SA_DQ<16>  
          	               	30        	83B1      	GND                 
          	               	31        	83B4      	M_A_CPU0_SA_DQ<17>  
          	               	32        	83B1      	GND                 
          	               	33        	83B2      	M_A_CPU0_SA_DQS_DP<2>
          	               	34        	83B2      	M_A_CPU0_SA_DQS_DN<2>
          	               	35        	83B1      	GND                 
          	               	36        	83B4      	M_A_CPU0_SA_DQ<20>  
          	               	37        	83B1      	GND                 
          	               	38        	83B4      	M_A_CPU0_SA_DQ<21>  
          	               	39        	83B1      	GND                 
          	               	40        	83B4      	M_A_CPU0_SA_DQ<24>  
          	               	41        	83B1      	GND                 
          	               	42        	83B4      	M_A_CPU0_SA_DQ<25>  
          	               	43        	83B1      	GND                 
          	               	44        	83B2      	M_A_CPU0_SA_DQS_DP<3>
          	               	45        	83B2      	M_A_CPU0_SA_DQS_DN<3>
          	               	46        	83B1      	GND                 
          	               	47        	83B4      	M_A_CPU0_SA_DQ<28>  
          	               	48        	83B1      	GND                 
          	               	49        	83B4      	M_A_CPU0_SA_DQ<29>  
          	               	50        	83B1      	GND                 
          	               	51        	83B4      	M_A_CPU0_SA_CB<0>   
          	               	52        	83B1      	GND                 
          	               	53        	83B4      	M_A_CPU0_SA_CB<1>   
          	               	54        	83B1      	GND                 
          	               	55        	83B2      	M_A_CPU0_SA_DQS_DP<4>
          	               	56        	83B2      	M_A_CPU0_SA_DQS_DN<4>
          	               	57        	83B1      	GND                 
          	               	58        	83B4      	M_A_CPU0_SA_CB<4>   
          	               	59        	83B1      	GND                 
          	               	60        	83B4      	M_A_CPU0_SA_CB<5>   
          	               	61        	83B1      	GND                 
          	               	62        	83B4      	M_A_CPU0_ALERT_N    
          	               	63        	83B1      	GND                 
          	               	64        	83B4      	M_A_CPU0_SA_CS_N<2> 
          	               	65        	83B1      	GND                 
          	               	66        	83B4      	M_A_CPU0_SA_CA<0>   
          	               	67        	83B1      	GND                 
          	               	68        	83B4      	M_A_CPU0_SA_CA<2>   
          	               	69        	83B1      	GND                 
          	               	70        	83B4      	M_A_CPU0_SA_CA<4>   
          	               	71        	83B1      	GND                 
          	               	72        	83B4      	M_A_CPU0_SA_CA<6>   
          	               	73        	83B1      	GND                 
          	               	74        	83B4      	M_A_CPU0_SA_PAR     
          	               	75        	83B1      	GND                 
          	               	76        	83B4      	M_A_CPU0_SB_CA<0>   
          	               	77        	83B1      	GND                 
          	               	78        	83B4      	M_A_CPU0_SB_CA<2>   
          	               	79        	83B1      	GND                 
          	               	80        	83B4      	M_A_CPU0_SB_CA<4>   
          	               	81        	83B1      	GND                 
          	               	82        	83B4      	M_A_CPU0_SB_CA<6>   
          	               	83        	83B1      	GND                 
          	               	84        	83B4      	M_A_CPU0_SB_CS_N<2> 
          	               	85        	83B1      	GND                 
          	               	86        	83A4      	M_A_CPU0_SA_RSP<1>  
          	               	87        	83A4      	M_A_CPU0_SB_RSP<1>  
          	               	88        	83B1      	GND                 
          	               	89        	83B4      	M_A_CPU0_SB_CB<4>   
          	               	90        	83B1      	GND                 
          	               	91        	83B4      	M_A_CPU0_SB_CB<5>   
          	               	92        	83B1      	GND                 
          	               	93        	83B2      	M_A_CPU0_SB_DQS_DP<9>
          	               	94        	83B2      	M_A_CPU0_SB_DQS_DN<9>
          	               	95        	83B1      	GND                 
          	               	96        	83B4      	M_A_CPU0_SB_CB<0>   
          	               	97        	83B1      	GND                 
          	               	98        	83B4      	M_A_CPU0_SB_CB<1>   
          	               	99        	83B1      	GND                 
          	               	100       	83B4      	M_A_CPU0_SB_DQ<0>   
          	               	101       	83B1      	GND                 
          	               	102       	83B4      	M_A_CPU0_SB_DQ<1>   
          	               	103       	83B1      	GND                 
          	               	104       	83B2      	M_A_CPU0_SB_DQS_DP<0>
          	               	105       	83B2      	M_A_CPU0_SB_DQS_DN<0>
          	               	106       	83B1      	GND                 
          	               	107       	83B4      	M_A_CPU0_SB_DQ<4>   
          	               	108       	83B1      	GND                 
          	               	109       	83B4      	M_A_CPU0_SB_DQ<5>   
          	               	110       	83B1      	GND                 
          	               	111       	83B4      	M_A_CPU0_SB_DQ<8>   
          	               	112       	83B1      	GND                 
          	               	113       	83B4      	M_A_CPU0_SB_DQ<9>   
          	               	114       	83B1      	GND                 
          	               	115       	83B2      	M_A_CPU0_SB_DQS_DP<1>
          	               	116       	83B2      	M_A_CPU0_SB_DQS_DN<1>
          	               	117       	83B1      	GND                 
          	               	118       	83B4      	M_A_CPU0_SB_DQ<12>  
          	               	119       	83B1      	GND                 
          	               	120       	83B4      	M_A_CPU0_SB_DQ<13>  
          	               	121       	83B1      	GND                 
          	               	122       	83B4      	M_A_CPU0_SB_DQ<16>  
          	               	123       	83B1      	GND                 
          	               	124       	83B4      	M_A_CPU0_SB_DQ<17>  
          	               	125       	83B1      	GND                 
          	               	126       	83B2      	M_A_CPU0_SB_DQS_DP<2>
          	               	127       	83B2      	M_A_CPU0_SB_DQS_DN<2>
          	               	128       	83B1      	GND                 
          	               	129       	83B4      	M_A_CPU0_SB_DQ<20>  
          	               	130       	83B1      	GND                 
          	               	131       	83B4      	M_A_CPU0_SB_DQ<21>  
          	               	132       	83B1      	GND                 
          	               	133       	83B4      	M_A_CPU0_SB_DQ<24>  
          	               	134       	83B1      	GND                 
          	               	135       	83B4      	M_A_CPU0_SB_DQ<25>  
          	               	136       	83B1      	GND                 
          	               	137       	83B2      	M_A_CPU0_SB_DQS_DP<3>
          	               	138       	83B2      	M_A_CPU0_SB_DQS_DN<3>
          	               	139       	83B1      	GND                 
          	               	140       	83B4      	M_A_CPU0_SB_DQ<28>  
          	               	141       	83B1      	GND                 
          	               	142       	83B4      	M_A_CPU0_SB_DQ<29>  
          	               	143       	83B1      	GND                 
          	               	144       	83B4      	TP_CHA_CPU0_DIMM2_FRU_1
          	               	145       	83B1      	P12V_S3_AUX_CPU0_NVDIMM
          	               	146       	83B1      	P12V_S3_AUX_CPU0_NVDIMM
          	               	147       	83B4      	PWRGD_CHA_CPU0_DIMM2
          	               	148       	83B4      	PD_CHA_CPU0_DIMM2_SAA
          	               	149       	83B4      	TP_CHA_CPU0_DIMM2_FRU_2
          	               	150       	83B4      	TP_CHA_CPU0_DIMM2_FRU_3
          	               	151       	83B1      	GND                 
          	               	152       	83B4      	M_A_CPU0_SA_DQ<2>   
          	               	153       	83B1      	GND                 
          	               	154       	83B4      	M_A_CPU0_SA_DQ<3>   
          	               	155       	83B1      	GND                 
          	               	156       	83B2      	M_A_CPU0_SA_DQS_DN<5>
          	               	157       	83B2      	M_A_CPU0_SA_DQS_DP<5>
          	               	158       	83B1      	GND                 
          	               	159       	83B4      	M_A_CPU0_SA_DQ<6>   
          	               	160       	83B1      	GND                 
          	               	161       	83B4      	M_A_CPU0_SA_DQ<7>   
          	               	162       	83B1      	GND                 
          	               	163       	83B4      	M_A_CPU0_SA_DQ<10>  
          	               	164       	83B1      	GND                 
          	               	165       	83B4      	M_A_CPU0_SA_DQ<11>  
          	               	166       	83B1      	GND                 
          	               	167       	83B2      	M_A_CPU0_SA_DQS_DN<6>
          	               	168       	83B2      	M_A_CPU0_SA_DQS_DP<6>
          	               	169       	83B1      	GND                 
          	               	170       	83B4      	M_A_CPU0_SA_DQ<14>  
          	               	171       	83B1      	GND                 
          	               	172       	83B4      	M_A_CPU0_SA_DQ<15>  
          	               	173       	83B1      	GND                 
          	               	174       	83B4      	M_A_CPU0_SA_DQ<18>  
          	               	175       	83B1      	GND                 
          	               	176       	83B4      	M_A_CPU0_SA_DQ<19>  
          	               	177       	83B1      	GND                 
          	               	178       	83B2      	M_A_CPU0_SA_DQS_DN<7>
          	               	179       	83B2      	M_A_CPU0_SA_DQS_DP<7>
          	               	180       	83B1      	GND                 
          	               	181       	83B4      	M_A_CPU0_SA_DQ<22>  
          	               	182       	83B1      	GND                 
          	               	183       	83B4      	M_A_CPU0_SA_DQ<23>  
          	               	184       	83B1      	GND                 
          	               	185       	83B4      	M_A_CPU0_SA_DQ<26>  
          	               	186       	83B1      	GND                 
          	               	187       	83B4      	M_A_CPU0_SA_DQ<27>  
          	               	188       	83B1      	GND                 
          	               	189       	83B2      	M_A_CPU0_SA_DQS_DN<8>
          	               	190       	83B2      	M_A_CPU0_SA_DQS_DP<8>
          	               	191       	83B1      	GND                 
          	               	192       	83B4      	M_A_CPU0_SA_DQ<30>  
          	               	193       	83B1      	GND                 
          	               	194       	83B4      	M_A_CPU0_SA_DQ<31>  
          	               	195       	83B1      	GND                 
          	               	196       	83B4      	M_A_CPU0_SA_CB<2>   
          	               	197       	83B1      	GND                 
          	               	198       	83B4      	M_A_CPU0_SA_CB<3>   
          	               	199       	83B1      	GND                 
          	               	200       	83B2      	M_A_CPU0_SA_DQS_DN<9>
          	               	201       	83B2      	M_A_CPU0_SA_DQS_DP<9>
          	               	202       	83B1      	GND                 
          	               	203       	83B4      	M_A_CPU0_SA_CB<6>   
          	               	204       	83B1      	GND                 
          	               	205       	83B4      	M_A_CPU0_SA_CB<7>   
          	               	206       	83B1      	GND                 
          	               	207       	83B4      	RST_M_AB_CPU0_FPGA_N
          	               	208       	83B1      	GND                 
          	               	209       	83B4      	M_A_CPU0_SA_CS_N<3> 
          	               	210       	83B1      	GND                 
          	               	211       	83B4      	M_A_CPU0_SA_CA<1>   
          	               	212       	83B1      	GND                 
          	               	213       	83B4      	M_A_CPU0_SA_CA<3>   
          	               	214       	83B1      	GND                 
          	               	215       	83B4      	M_A_CPU0_SA_CA<5>   
          	               	216       	83B1      	GND                 
          	               	217       	83B4      	M_A_CPU0_CLK_DP<1>  
          	               	218       	83B4      	M_A_CPU0_CLK_DN<1>  
          	               	219       	83B1      	GND                 
          	               	220       	83B4      	TP_CHA_CPU0_DIMM2_FRU_4
          	               	221       	83B4      	M_A_CPU0_SB_CA<1>   
          	               	222       	83B1      	GND                 
          	               	223       	83B4      	M_A_CPU0_SB_CA<3>   
          	               	224       	83B1      	GND                 
          	               	225       	83B4      	M_A_CPU0_SB_CA<5>   
          	               	226       	83B1      	GND                 
          	               	227       	83B4      	M_A_CPU0_SB_PAR     
          	               	228       	83B1      	GND                 
          	               	229       	83B4      	M_A_CPU0_SB_CS_N<3> 
          	               	230       	83B1      	GND                 
          	               	231       	83B4      	TP_CHA_CPU0_DIMM2_FRU_5
          	               	232       	83B4      	TP_CHA_CPU0_DIMM2_FRU_6
          	               	233       	83B1      	GND                 
          	               	234       	83B4      	M_A_CPU0_SB_CB<6>   
          	               	235       	83B1      	GND                 
          	               	236       	83B4      	M_A_CPU0_SB_CB<7>   
          	               	237       	83B1      	GND                 
          	               	238       	83B2      	M_A_CPU0_SB_DQS_DN<4>
          	               	239       	83B2      	M_A_CPU0_SB_DQS_DP<4>
          	               	240       	83B1      	GND                 
          	               	241       	83B4      	M_A_CPU0_SB_CB<2>   
          	               	242       	83B1      	GND                 
          	               	243       	83B4      	M_A_CPU0_SB_CB<3>   
          	               	244       	83B1      	GND                 
          	               	245       	83B4      	M_A_CPU0_SB_DQ<2>   
          	               	246       	83B1      	GND                 
          	               	247       	83B4      	M_A_CPU0_SB_DQ<3>   
          	               	248       	83B1      	GND                 
          	               	249       	83B2      	M_A_CPU0_SB_DQS_DN<5>
          	               	250       	83B2      	M_A_CPU0_SB_DQS_DP<5>
          	               	251       	83B1      	GND                 
          	               	252       	83B4      	M_A_CPU0_SB_DQ<6>   
          	               	253       	83B1      	GND                 
          	               	254       	83B4      	M_A_CPU0_SB_DQ<7>   
          	               	255       	83B1      	GND                 
          	               	256       	83B4      	M_A_CPU0_SB_DQ<10>  
          	               	257       	83B1      	GND                 
          	               	258       	83B4      	M_A_CPU0_SB_DQ<11>  
          	               	259       	83B1      	GND                 
          	               	260       	83B2      	M_A_CPU0_SB_DQS_DN<6>
          	               	261       	83B2      	M_A_CPU0_SB_DQS_DP<6>
          	               	262       	83B1      	GND                 
          	               	263       	83B4      	M_A_CPU0_SB_DQ<14>  
          	               	264       	83B1      	GND                 
          	               	265       	83B4      	M_A_CPU0_SB_DQ<15>  
          	               	266       	83B1      	GND                 
          	               	267       	83B4      	M_A_CPU0_SB_DQ<18>  
          	               	268       	83B1      	GND                 
          	               	269       	83B4      	M_A_CPU0_SB_DQ<19>  
          	               	270       	83B1      	GND                 
          	               	271       	83B2      	M_A_CPU0_SB_DQS_DN<7>
          	               	272       	83B2      	M_A_CPU0_SB_DQS_DP<7>
          	               	273       	83B1      	GND                 
          	               	274       	83B4      	M_A_CPU0_SB_DQ<22>  
          	               	275       	83B1      	GND                 
          	               	276       	83B4      	M_A_CPU0_SB_DQ<23>  
          	               	277       	83B1      	GND                 
          	               	278       	83B4      	M_A_CPU0_SB_DQ<26>  
          	               	279       	83B1      	GND                 
          	               	280       	83B4      	M_A_CPU0_SB_DQ<27>  
          	               	281       	83B1      	GND                 
          	               	282       	83B2      	M_A_CPU0_SB_DQS_DN<8>
          	               	283       	83B2      	M_A_CPU0_SB_DQS_DP<8>
          	               	284       	83B1      	GND                 
          	               	285       	83B4      	M_A_CPU0_SB_DQ<30>  
          	               	286       	83B1      	GND                 
          	               	287       	83B4      	M_A_CPU0_SB_DQ<31>  
          	               	288       	83B1      	GND                 
          	               	G1        	83B1      	GND                 
          	               	G2        	83A1      	GND                 
          	               	G3        	83A1      	GND                 

J3        	SCONN288_ADR50017P130CC	          	          	                    
          	               	1         	84B1      	P12V_S3_AUX_CPU0_NVDIMM
          	               	2         	84B4      	TP_CHB_CPU0_DIMM1_FRU_0
          	               	3         	84B4      	P3V3_AUX            
          	               	4         	84B4      	I3C_SPD_DDRABCD_CPU0_LVC1_SCL_2
          	               	5         	84B4      	I3C_SPD_DDRABCD_CPU0_LVC1_SDA
          	               	6         	84B1      	GND                 
          	               	7         	84B4      	M_B_CPU0_SA_DQ<0>   
          	               	8         	84B1      	GND                 
          	               	9         	84B4      	M_B_CPU0_SA_DQ<1>   
          	               	10        	84B1      	GND                 
          	               	11        	84B2      	M_B_CPU0_SA_DQS_DP<0>
          	               	12        	84B2      	M_B_CPU0_SA_DQS_DN<0>
          	               	13        	84B1      	GND                 
          	               	14        	84B4      	M_B_CPU0_SA_DQ<4>   
          	               	15        	84B1      	GND                 
          	               	16        	84B4      	M_B_CPU0_SA_DQ<5>   
          	               	17        	84B1      	GND                 
          	               	18        	84B4      	M_B_CPU0_SA_DQ<8>   
          	               	19        	84B1      	GND                 
          	               	20        	84B4      	M_B_CPU0_SA_DQ<9>   
          	               	21        	84B1      	GND                 
          	               	22        	84B2      	M_B_CPU0_SA_DQS_DP<1>
          	               	23        	84B2      	M_B_CPU0_SA_DQS_DN<1>
          	               	24        	84B1      	GND                 
          	               	25        	84B4      	M_B_CPU0_SA_DQ<12>  
          	               	26        	84B1      	GND                 
          	               	27        	84B4      	M_B_CPU0_SA_DQ<13>  
          	               	28        	84B1      	GND                 
          	               	29        	84B4      	M_B_CPU0_SA_DQ<16>  
          	               	30        	84B1      	GND                 
          	               	31        	84B4      	M_B_CPU0_SA_DQ<17>  
          	               	32        	84B1      	GND                 
          	               	33        	84B2      	M_B_CPU0_SA_DQS_DP<2>
          	               	34        	84B2      	M_B_CPU0_SA_DQS_DN<2>
          	               	35        	84B1      	GND                 
          	               	36        	84B4      	M_B_CPU0_SA_DQ<20>  
          	               	37        	84B1      	GND                 
          	               	38        	84B4      	M_B_CPU0_SA_DQ<21>  
          	               	39        	84B1      	GND                 
          	               	40        	84B4      	M_B_CPU0_SA_DQ<24>  
          	               	41        	84B1      	GND                 
          	               	42        	84B4      	M_B_CPU0_SA_DQ<25>  
          	               	43        	84B1      	GND                 
          	               	44        	84B2      	M_B_CPU0_SA_DQS_DP<3>
          	               	45        	84B2      	M_B_CPU0_SA_DQS_DN<3>
          	               	46        	84B1      	GND                 
          	               	47        	84B4      	M_B_CPU0_SA_DQ<28>  
          	               	48        	84B1      	GND                 
          	               	49        	84B4      	M_B_CPU0_SA_DQ<29>  
          	               	50        	84B1      	GND                 
          	               	51        	84B4      	M_B_CPU0_SA_CB<0>   
          	               	52        	84B1      	GND                 
          	               	53        	84B4      	M_B_CPU0_SA_CB<1>   
          	               	54        	84B1      	GND                 
          	               	55        	84B2      	M_B_CPU0_SA_DQS_DP<4>
          	               	56        	84B2      	M_B_CPU0_SA_DQS_DN<4>
          	               	57        	84B1      	GND                 
          	               	58        	84B4      	M_B_CPU0_SA_CB<4>   
          	               	59        	84B1      	GND                 
          	               	60        	84B4      	M_B_CPU0_SA_CB<5>   
          	               	61        	84B1      	GND                 
          	               	62        	84B4      	M_B_CPU0_ALERT_N    
          	               	63        	84B1      	GND                 
          	               	64        	84B4      	M_B_CPU0_SA_CS_N<0> 
          	               	65        	84B1      	GND                 
          	               	66        	84B4      	M_B_CPU0_SA_CA<0>   
          	               	67        	84B1      	GND                 
          	               	68        	84B4      	M_B_CPU0_SA_CA<2>   
          	               	69        	84B1      	GND                 
          	               	70        	84B4      	M_B_CPU0_SA_CA<4>   
          	               	71        	84B1      	GND                 
          	               	72        	84B4      	M_B_CPU0_SA_CA<6>   
          	               	73        	84B1      	GND                 
          	               	74        	84B4      	M_B_CPU0_SA_PAR     
          	               	75        	84B1      	GND                 
          	               	76        	84B4      	M_B_CPU0_SB_CA<0>   
          	               	77        	84B1      	GND                 
          	               	78        	84B4      	M_B_CPU0_SB_CA<2>   
          	               	79        	84B1      	GND                 
          	               	80        	84B4      	M_B_CPU0_SB_CA<4>   
          	               	81        	84B1      	GND                 
          	               	82        	84B4      	M_B_CPU0_SB_CA<6>   
          	               	83        	84B1      	GND                 
          	               	84        	84B4      	M_B_CPU0_SB_CS_N<0> 
          	               	85        	84B1      	GND                 
          	               	86        	84A4      	M_B_CPU0_SA_RSP<0>  
          	               	87        	84A4      	M_B_CPU0_SB_RSP<0>  
          	               	88        	84B1      	GND                 
          	               	89        	84B4      	M_B_CPU0_SB_CB<4>   
          	               	90        	84B1      	GND                 
          	               	91        	84B4      	M_B_CPU0_SB_CB<5>   
          	               	92        	84B1      	GND                 
          	               	93        	84B2      	M_B_CPU0_SB_DQS_DP<9>
          	               	94        	84B2      	M_B_CPU0_SB_DQS_DN<9>
          	               	95        	84B1      	GND                 
          	               	96        	84B4      	M_B_CPU0_SB_CB<0>   
          	               	97        	84B1      	GND                 
          	               	98        	84B4      	M_B_CPU0_SB_CB<1>   
          	               	99        	84B1      	GND                 
          	               	100       	84B4      	M_B_CPU0_SB_DQ<0>   
          	               	101       	84B1      	GND                 
          	               	102       	84B4      	M_B_CPU0_SB_DQ<1>   
          	               	103       	84B1      	GND                 
          	               	104       	84B2      	M_B_CPU0_SB_DQS_DP<0>
          	               	105       	84B2      	M_B_CPU0_SB_DQS_DN<0>
          	               	106       	84B1      	GND                 
          	               	107       	84B4      	M_B_CPU0_SB_DQ<4>   
          	               	108       	84B1      	GND                 
          	               	109       	84B4      	M_B_CPU0_SB_DQ<5>   
          	               	110       	84B1      	GND                 
          	               	111       	84B4      	M_B_CPU0_SB_DQ<8>   
          	               	112       	84B1      	GND                 
          	               	113       	84B4      	M_B_CPU0_SB_DQ<9>   
          	               	114       	84B1      	GND                 
          	               	115       	84B2      	M_B_CPU0_SB_DQS_DP<1>
          	               	116       	84B2      	M_B_CPU0_SB_DQS_DN<1>
          	               	117       	84B1      	GND                 
          	               	118       	84B4      	M_B_CPU0_SB_DQ<12>  
          	               	119       	84B1      	GND                 
          	               	120       	84B4      	M_B_CPU0_SB_DQ<13>  
          	               	121       	84B1      	GND                 
          	               	122       	84B4      	M_B_CPU0_SB_DQ<16>  
          	               	123       	84B1      	GND                 
          	               	124       	84B4      	M_B_CPU0_SB_DQ<17>  
          	               	125       	84B1      	GND                 
          	               	126       	84B2      	M_B_CPU0_SB_DQS_DP<2>
          	               	127       	84B2      	M_B_CPU0_SB_DQS_DN<2>
          	               	128       	84B1      	GND                 
          	               	129       	84B4      	M_B_CPU0_SB_DQ<20>  
          	               	130       	84B1      	GND                 
          	               	131       	84B4      	M_B_CPU0_SB_DQ<21>  
          	               	132       	84B1      	GND                 
          	               	133       	84B4      	M_B_CPU0_SB_DQ<24>  
          	               	134       	84B1      	GND                 
          	               	135       	84B4      	M_B_CPU0_SB_DQ<25>  
          	               	136       	84B1      	GND                 
          	               	137       	84B2      	M_B_CPU0_SB_DQS_DP<3>
          	               	138       	84B2      	M_B_CPU0_SB_DQS_DN<3>
          	               	139       	84B1      	GND                 
          	               	140       	84B4      	M_B_CPU0_SB_DQ<28>  
          	               	141       	84B1      	GND                 
          	               	142       	84B4      	M_B_CPU0_SB_DQ<29>  
          	               	143       	84B1      	GND                 
          	               	144       	84B4      	TP_CHB_CPU0_DIMM1_FRU_1
          	               	145       	84B1      	P12V_S3_AUX_CPU0_NVDIMM
          	               	146       	84B1      	P12V_S3_AUX_CPU0_NVDIMM
          	               	147       	84B4      	PWRGD_CHB_CPU0_DIMM1
          	               	148       	84B4      	PD_CHB_CPU0_DIMM1_SAA
          	               	149       	84B4      	TP_CHB_CPU0_DIMM1_FRU_2
          	               	150       	84B4      	TP_CHB_CPU0_DIMM1_FRU_3
          	               	151       	84B1      	GND                 
          	               	152       	84B4      	M_B_CPU0_SA_DQ<2>   
          	               	153       	84B1      	GND                 
          	               	154       	84B4      	M_B_CPU0_SA_DQ<3>   
          	               	155       	84B1      	GND                 
          	               	156       	84B2      	M_B_CPU0_SA_DQS_DN<5>
          	               	157       	84B2      	M_B_CPU0_SA_DQS_DP<5>
          	               	158       	84B1      	GND                 
          	               	159       	84B4      	M_B_CPU0_SA_DQ<6>   
          	               	160       	84B1      	GND                 
          	               	161       	84B4      	M_B_CPU0_SA_DQ<7>   
          	               	162       	84B1      	GND                 
          	               	163       	84B4      	M_B_CPU0_SA_DQ<10>  
          	               	164       	84B1      	GND                 
          	               	165       	84B4      	M_B_CPU0_SA_DQ<11>  
          	               	166       	84B1      	GND                 
          	               	167       	84B2      	M_B_CPU0_SA_DQS_DN<6>
          	               	168       	84B2      	M_B_CPU0_SA_DQS_DP<6>
          	               	169       	84B1      	GND                 
          	               	170       	84B4      	M_B_CPU0_SA_DQ<14>  
          	               	171       	84B1      	GND                 
          	               	172       	84B4      	M_B_CPU0_SA_DQ<15>  
          	               	173       	84B1      	GND                 
          	               	174       	84B4      	M_B_CPU0_SA_DQ<18>  
          	               	175       	84B1      	GND                 
          	               	176       	84B4      	M_B_CPU0_SA_DQ<19>  
          	               	177       	84B1      	GND                 
          	               	178       	84B2      	M_B_CPU0_SA_DQS_DN<7>
          	               	179       	84B2      	M_B_CPU0_SA_DQS_DP<7>
          	               	180       	84B1      	GND                 
          	               	181       	84B4      	M_B_CPU0_SA_DQ<22>  
          	               	182       	84B1      	GND                 
          	               	183       	84B4      	M_B_CPU0_SA_DQ<23>  
          	               	184       	84B1      	GND                 
          	               	185       	84B4      	M_B_CPU0_SA_DQ<26>  
          	               	186       	84B1      	GND                 
          	               	187       	84B4      	M_B_CPU0_SA_DQ<27>  
          	               	188       	84B1      	GND                 
          	               	189       	84B2      	M_B_CPU0_SA_DQS_DN<8>
          	               	190       	84B2      	M_B_CPU0_SA_DQS_DP<8>
          	               	191       	84B1      	GND                 
          	               	192       	84B4      	M_B_CPU0_SA_DQ<30>  
          	               	193       	84B1      	GND                 
          	               	194       	84B4      	M_B_CPU0_SA_DQ<31>  
          	               	195       	84B1      	GND                 
          	               	196       	84B4      	M_B_CPU0_SA_CB<2>   
          	               	197       	84B1      	GND                 
          	               	198       	84B4      	M_B_CPU0_SA_CB<3>   
          	               	199       	84B1      	GND                 
          	               	200       	84B2      	M_B_CPU0_SA_DQS_DN<9>
          	               	201       	84B2      	M_B_CPU0_SA_DQS_DP<9>
          	               	202       	84B1      	GND                 
          	               	203       	84B4      	M_B_CPU0_SA_CB<6>   
          	               	204       	84B1      	GND                 
          	               	205       	84B4      	M_B_CPU0_SA_CB<7>   
          	               	206       	84B1      	GND                 
          	               	207       	84B4      	RST_M_AB_CPU0_FPGA_N
          	               	208       	84B1      	GND                 
          	               	209       	84B4      	M_B_CPU0_SA_CS_N<1> 
          	               	210       	84B1      	GND                 
          	               	211       	84B4      	M_B_CPU0_SA_CA<1>   
          	               	212       	84B1      	GND                 
          	               	213       	84B4      	M_B_CPU0_SA_CA<3>   
          	               	214       	84B1      	GND                 
          	               	215       	84B4      	M_B_CPU0_SA_CA<5>   
          	               	216       	84B1      	GND                 
          	               	217       	84B4      	M_B_CPU0_CLK_DP<0>  
          	               	218       	84B4      	M_B_CPU0_CLK_DN<0>  
          	               	219       	84B1      	GND                 
          	               	220       	84B4      	TP_CHB_CPU0_DIMM1_FRU_4
          	               	221       	84B4      	M_B_CPU0_SB_CA<1>   
          	               	222       	84B1      	GND                 
          	               	223       	84B4      	M_B_CPU0_SB_CA<3>   
          	               	224       	84B1      	GND                 
          	               	225       	84B4      	M_B_CPU0_SB_CA<5>   
          	               	226       	84B1      	GND                 
          	               	227       	84B4      	M_B_CPU0_SB_PAR     
          	               	228       	84B1      	GND                 
          	               	229       	84B4      	M_B_CPU0_SB_CS_N<1> 
          	               	230       	84B1      	GND                 
          	               	231       	84B4      	TP_CHB_CPU0_DIMM1_FRU_5
          	               	232       	84B4      	TP_CHB_CPU0_DIMM1_FRU_6
          	               	233       	84B1      	GND                 
          	               	234       	84B4      	M_B_CPU0_SB_CB<6>   
          	               	235       	84B1      	GND                 
          	               	236       	84B4      	M_B_CPU0_SB_CB<7>   
          	               	237       	84B1      	GND                 
          	               	238       	84B2      	M_B_CPU0_SB_DQS_DN<4>
          	               	239       	84B2      	M_B_CPU0_SB_DQS_DP<4>
          	               	240       	84B1      	GND                 
          	               	241       	84B4      	M_B_CPU0_SB_CB<2>   
          	               	242       	84B1      	GND                 
          	               	243       	84B4      	M_B_CPU0_SB_CB<3>   
          	               	244       	84B1      	GND                 
          	               	245       	84B4      	M_B_CPU0_SB_DQ<2>   
          	               	246       	84B1      	GND                 
          	               	247       	84B4      	M_B_CPU0_SB_DQ<3>   
          	               	248       	84B1      	GND                 
          	               	249       	84B2      	M_B_CPU0_SB_DQS_DN<5>
          	               	250       	84B2      	M_B_CPU0_SB_DQS_DP<5>
          	               	251       	84B1      	GND                 
          	               	252       	84B4      	M_B_CPU0_SB_DQ<6>   
          	               	253       	84B1      	GND                 
          	               	254       	84B4      	M_B_CPU0_SB_DQ<7>   
          	               	255       	84B1      	GND                 
          	               	256       	84B4      	M_B_CPU0_SB_DQ<10>  
          	               	257       	84B1      	GND                 
          	               	258       	84B4      	M_B_CPU0_SB_DQ<11>  
          	               	259       	84B1      	GND                 
          	               	260       	84B2      	M_B_CPU0_SB_DQS_DN<6>
          	               	261       	84B2      	M_B_CPU0_SB_DQS_DP<6>
          	               	262       	84B1      	GND                 
          	               	263       	84B4      	M_B_CPU0_SB_DQ<14>  
          	               	264       	84B1      	GND                 
          	               	265       	84B4      	M_B_CPU0_SB_DQ<15>  
          	               	266       	84B1      	GND                 
          	               	267       	84B4      	M_B_CPU0_SB_DQ<18>  
          	               	268       	84B1      	GND                 
          	               	269       	84B4      	M_B_CPU0_SB_DQ<19>  
          	               	270       	84B1      	GND                 
          	               	271       	84B2      	M_B_CPU0_SB_DQS_DN<7>
          	               	272       	84B2      	M_B_CPU0_SB_DQS_DP<7>
          	               	273       	84B1      	GND                 
          	               	274       	84B4      	M_B_CPU0_SB_DQ<22>  
          	               	275       	84B1      	GND                 
          	               	276       	84B4      	M_B_CPU0_SB_DQ<23>  
          	               	277       	84B1      	GND                 
          	               	278       	84B4      	M_B_CPU0_SB_DQ<26>  
          	               	279       	84B1      	GND                 
          	               	280       	84B4      	M_B_CPU0_SB_DQ<27>  
          	               	281       	84B1      	GND                 
          	               	282       	84B2      	M_B_CPU0_SB_DQS_DN<8>
          	               	283       	84B2      	M_B_CPU0_SB_DQS_DP<8>
          	               	284       	84B1      	GND                 
          	               	285       	84B4      	M_B_CPU0_SB_DQ<30>  
          	               	286       	84B1      	GND                 
          	               	287       	84B4      	M_B_CPU0_SB_DQ<31>  
          	               	288       	84B1      	GND                 
          	               	G1        	84B1      	GND                 
          	               	G2        	84A1      	GND                 
          	               	G3        	84A1      	GND                 

J4        	SCONN288_ADR50017P087CC	          	          	                    
          	               	1         	85B1      	P12V_S3_AUX_CPU0_NVDIMM
          	               	2         	85A4      	TP_CHB_CPU0_DIMM2_FRU_0
          	               	3         	85B4      	P3V3_AUX            
          	               	4         	85B4      	I3C_SPD_DDRABCD_CPU0_LVC1_SCL_3
          	               	5         	85B4      	I3C_SPD_DDRABCD_CPU0_LVC1_SDA
          	               	6         	85B1      	GND                 
          	               	7         	85B4      	M_B_CPU0_SA_DQ<0>   
          	               	8         	85B1      	GND                 
          	               	9         	85B4      	M_B_CPU0_SA_DQ<1>   
          	               	10        	85B1      	GND                 
          	               	11        	85B2      	M_B_CPU0_SA_DQS_DP<0>
          	               	12        	85B2      	M_B_CPU0_SA_DQS_DN<0>
          	               	13        	85B1      	GND                 
          	               	14        	85B4      	M_B_CPU0_SA_DQ<4>   
          	               	15        	85B1      	GND                 
          	               	16        	85B4      	M_B_CPU0_SA_DQ<5>   
          	               	17        	85B1      	GND                 
          	               	18        	85B4      	M_B_CPU0_SA_DQ<8>   
          	               	19        	85B1      	GND                 
          	               	20        	85B4      	M_B_CPU0_SA_DQ<9>   
          	               	21        	85B1      	GND                 
          	               	22        	85B2      	M_B_CPU0_SA_DQS_DP<1>
          	               	23        	85B2      	M_B_CPU0_SA_DQS_DN<1>
          	               	24        	85B1      	GND                 
          	               	25        	85B4      	M_B_CPU0_SA_DQ<12>  
          	               	26        	85B1      	GND                 
          	               	27        	85B4      	M_B_CPU0_SA_DQ<13>  
          	               	28        	85B1      	GND                 
          	               	29        	85B4      	M_B_CPU0_SA_DQ<16>  
          	               	30        	85B1      	GND                 
          	               	31        	85B4      	M_B_CPU0_SA_DQ<17>  
          	               	32        	85B1      	GND                 
          	               	33        	85B2      	M_B_CPU0_SA_DQS_DP<2>
          	               	34        	85B2      	M_B_CPU0_SA_DQS_DN<2>
          	               	35        	85B1      	GND                 
          	               	36        	85B4      	M_B_CPU0_SA_DQ<20>  
          	               	37        	85B1      	GND                 
          	               	38        	85B4      	M_B_CPU0_SA_DQ<21>  
          	               	39        	85B1      	GND                 
          	               	40        	85B4      	M_B_CPU0_SA_DQ<24>  
          	               	41        	85B1      	GND                 
          	               	42        	85B4      	M_B_CPU0_SA_DQ<25>  
          	               	43        	85B1      	GND                 
          	               	44        	85B2      	M_B_CPU0_SA_DQS_DP<3>
          	               	45        	85B2      	M_B_CPU0_SA_DQS_DN<3>
          	               	46        	85B1      	GND                 
          	               	47        	85B4      	M_B_CPU0_SA_DQ<28>  
          	               	48        	85B1      	GND                 
          	               	49        	85B4      	M_B_CPU0_SA_DQ<29>  
          	               	50        	85B1      	GND                 
          	               	51        	85B4      	M_B_CPU0_SA_CB<0>   
          	               	52        	85B1      	GND                 
          	               	53        	85B4      	M_B_CPU0_SA_CB<1>   
          	               	54        	85B1      	GND                 
          	               	55        	85B2      	M_B_CPU0_SA_DQS_DP<4>
          	               	56        	85B2      	M_B_CPU0_SA_DQS_DN<4>
          	               	57        	85B1      	GND                 
          	               	58        	85B4      	M_B_CPU0_SA_CB<4>   
          	               	59        	85B1      	GND                 
          	               	60        	85B4      	M_B_CPU0_SA_CB<5>   
          	               	61        	85B1      	GND                 
          	               	62        	85B4      	M_B_CPU0_ALERT_N    
          	               	63        	85B1      	GND                 
          	               	64        	85B4      	M_B_CPU0_SA_CS_N<2> 
          	               	65        	85B1      	GND                 
          	               	66        	85B4      	M_B_CPU0_SA_CA<0>   
          	               	67        	85B1      	GND                 
          	               	68        	85B4      	M_B_CPU0_SA_CA<2>   
          	               	69        	85B1      	GND                 
          	               	70        	85B4      	M_B_CPU0_SA_CA<4>   
          	               	71        	85B1      	GND                 
          	               	72        	85B4      	M_B_CPU0_SA_CA<6>   
          	               	73        	85B1      	GND                 
          	               	74        	85B4      	M_B_CPU0_SA_PAR     
          	               	75        	85B1      	GND                 
          	               	76        	85B4      	M_B_CPU0_SB_CA<0>   
          	               	77        	85B1      	GND                 
          	               	78        	85B4      	M_B_CPU0_SB_CA<2>   
          	               	79        	85B1      	GND                 
          	               	80        	85B4      	M_B_CPU0_SB_CA<4>   
          	               	81        	85B1      	GND                 
          	               	82        	85B4      	M_B_CPU0_SB_CA<6>   
          	               	83        	85B1      	GND                 
          	               	84        	85B4      	M_B_CPU0_SB_CS_N<2> 
          	               	85        	85B1      	GND                 
          	               	86        	85A4      	M_B_CPU0_SA_RSP<1>  
          	               	87        	85A4      	M_B_CPU0_SB_RSP<1>  
          	               	88        	85B1      	GND                 
          	               	89        	85B4      	M_B_CPU0_SB_CB<4>   
          	               	90        	85B1      	GND                 
          	               	91        	85B4      	M_B_CPU0_SB_CB<5>   
          	               	92        	85B1      	GND                 
          	               	93        	85B2      	M_B_CPU0_SB_DQS_DP<9>
          	               	94        	85B2      	M_B_CPU0_SB_DQS_DN<9>
          	               	95        	85B1      	GND                 
          	               	96        	85B4      	M_B_CPU0_SB_CB<0>   
          	               	97        	85B1      	GND                 
          	               	98        	85B4      	M_B_CPU0_SB_CB<1>   
          	               	99        	85B1      	GND                 
          	               	100       	85B4      	M_B_CPU0_SB_DQ<0>   
          	               	101       	85B1      	GND                 
          	               	102       	85B4      	M_B_CPU0_SB_DQ<1>   
          	               	103       	85B1      	GND                 
          	               	104       	85B2      	M_B_CPU0_SB_DQS_DP<0>
          	               	105       	85B2      	M_B_CPU0_SB_DQS_DN<0>
          	               	106       	85B1      	GND                 
          	               	107       	85B4      	M_B_CPU0_SB_DQ<4>   
          	               	108       	85B1      	GND                 
          	               	109       	85B4      	M_B_CPU0_SB_DQ<5>   
          	               	110       	85B1      	GND                 
          	               	111       	85B4      	M_B_CPU0_SB_DQ<8>   
          	               	112       	85B1      	GND                 
          	               	113       	85B4      	M_B_CPU0_SB_DQ<9>   
          	               	114       	85B1      	GND                 
          	               	115       	85B2      	M_B_CPU0_SB_DQS_DP<1>
          	               	116       	85B2      	M_B_CPU0_SB_DQS_DN<1>
          	               	117       	85B1      	GND                 
          	               	118       	85B4      	M_B_CPU0_SB_DQ<12>  
          	               	119       	85B1      	GND                 
          	               	120       	85B4      	M_B_CPU0_SB_DQ<13>  
          	               	121       	85B1      	GND                 
          	               	122       	85B4      	M_B_CPU0_SB_DQ<16>  
          	               	123       	85B1      	GND                 
          	               	124       	85B4      	M_B_CPU0_SB_DQ<17>  
          	               	125       	85B1      	GND                 
          	               	126       	85B2      	M_B_CPU0_SB_DQS_DP<2>
          	               	127       	85B2      	M_B_CPU0_SB_DQS_DN<2>
          	               	128       	85B1      	GND                 
          	               	129       	85B4      	M_B_CPU0_SB_DQ<20>  
          	               	130       	85B1      	GND                 
          	               	131       	85B4      	M_B_CPU0_SB_DQ<21>  
          	               	132       	85B1      	GND                 
          	               	133       	85B4      	M_B_CPU0_SB_DQ<24>  
          	               	134       	85B1      	GND                 
          	               	135       	85B4      	M_B_CPU0_SB_DQ<25>  
          	               	136       	85B1      	GND                 
          	               	137       	85B2      	M_B_CPU0_SB_DQS_DP<3>
          	               	138       	85B2      	M_B_CPU0_SB_DQS_DN<3>
          	               	139       	85B1      	GND                 
          	               	140       	85B4      	M_B_CPU0_SB_DQ<28>  
          	               	141       	85B1      	GND                 
          	               	142       	85B4      	M_B_CPU0_SB_DQ<29>  
          	               	143       	85B1      	GND                 
          	               	144       	85B4      	TP_CHB_CPU0_DIMM2_FRU_1
          	               	145       	85B1      	P12V_S3_AUX_CPU0_NVDIMM
          	               	146       	85B1      	P12V_S3_AUX_CPU0_NVDIMM
          	               	147       	85B4      	PWRGD_CHB_CPU0_DIMM2
          	               	148       	85B4      	PD_CHB_CPU0_DIMM2_SAA
          	               	149       	85B4      	TP_CHB_CPU0_DIMM2_FRU_2
          	               	150       	85B4      	TP_CHB_CPU0_DIMM2_FRU_3
          	               	151       	85A1      	GND                 
          	               	152       	85B4      	M_B_CPU0_SA_DQ<2>   
          	               	153       	85B1      	GND                 
          	               	154       	85B4      	M_B_CPU0_SA_DQ<3>   
          	               	155       	85B1      	GND                 
          	               	156       	85B2      	M_B_CPU0_SA_DQS_DN<5>
          	               	157       	85B2      	M_B_CPU0_SA_DQS_DP<5>
          	               	158       	85B1      	GND                 
          	               	159       	85B4      	M_B_CPU0_SA_DQ<6>   
          	               	160       	85B1      	GND                 
          	               	161       	85B4      	M_B_CPU0_SA_DQ<7>   
          	               	162       	85B1      	GND                 
          	               	163       	85B4      	M_B_CPU0_SA_DQ<10>  
          	               	164       	85B1      	GND                 
          	               	165       	85B4      	M_B_CPU0_SA_DQ<11>  
          	               	166       	85B1      	GND                 
          	               	167       	85B2      	M_B_CPU0_SA_DQS_DN<6>
          	               	168       	85B2      	M_B_CPU0_SA_DQS_DP<6>
          	               	169       	85B1      	GND                 
          	               	170       	85B4      	M_B_CPU0_SA_DQ<14>  
          	               	171       	85B1      	GND                 
          	               	172       	85B4      	M_B_CPU0_SA_DQ<15>  
          	               	173       	85B1      	GND                 
          	               	174       	85B4      	M_B_CPU0_SA_DQ<18>  
          	               	175       	85B1      	GND                 
          	               	176       	85B4      	M_B_CPU0_SA_DQ<19>  
          	               	177       	85B1      	GND                 
          	               	178       	85B2      	M_B_CPU0_SA_DQS_DN<7>
          	               	179       	85B2      	M_B_CPU0_SA_DQS_DP<7>
          	               	180       	85B1      	GND                 
          	               	181       	85B4      	M_B_CPU0_SA_DQ<22>  
          	               	182       	85B1      	GND                 
          	               	183       	85B4      	M_B_CPU0_SA_DQ<23>  
          	               	184       	85B1      	GND                 
          	               	185       	85B4      	M_B_CPU0_SA_DQ<26>  
          	               	186       	85B1      	GND                 
          	               	187       	85B4      	M_B_CPU0_SA_DQ<27>  
          	               	188       	85B1      	GND                 
          	               	189       	85B2      	M_B_CPU0_SA_DQS_DN<8>
          	               	190       	85B2      	M_B_CPU0_SA_DQS_DP<8>
          	               	191       	85B1      	GND                 
          	               	192       	85B4      	M_B_CPU0_SA_DQ<30>  
          	               	193       	85B1      	GND                 
          	               	194       	85B4      	M_B_CPU0_SA_DQ<31>  
          	               	195       	85B1      	GND                 
          	               	196       	85B4      	M_B_CPU0_SA_CB<2>   
          	               	197       	85B1      	GND                 
          	               	198       	85B4      	M_B_CPU0_SA_CB<3>   
          	               	199       	85B1      	GND                 
          	               	200       	85B2      	M_B_CPU0_SA_DQS_DN<9>
          	               	201       	85B2      	M_B_CPU0_SA_DQS_DP<9>
          	               	202       	85B1      	GND                 
          	               	203       	85B4      	M_B_CPU0_SA_CB<6>   
          	               	204       	85B1      	GND                 
          	               	205       	85B4      	M_B_CPU0_SA_CB<7>   
          	               	206       	85B1      	GND                 
          	               	207       	85B4      	RST_M_AB_CPU0_FPGA_N
          	               	208       	85B1      	GND                 
          	               	209       	85B4      	M_B_CPU0_SA_CS_N<3> 
          	               	210       	85B1      	GND                 
          	               	211       	85B4      	M_B_CPU0_SA_CA<1>   
          	               	212       	85B1      	GND                 
          	               	213       	85B4      	M_B_CPU0_SA_CA<3>   
          	               	214       	85B1      	GND                 
          	               	215       	85B4      	M_B_CPU0_SA_CA<5>   
          	               	216       	85B1      	GND                 
          	               	217       	85B4      	M_B_CPU0_CLK_DP<1>  
          	               	218       	85B4      	M_B_CPU0_CLK_DN<1>  
          	               	219       	85B1      	GND                 
          	               	220       	85B4      	TP_CHB_CPU0_DIMM2_FRU_4
          	               	221       	85B4      	M_B_CPU0_SB_CA<1>   
          	               	222       	85B1      	GND                 
          	               	223       	85B4      	M_B_CPU0_SB_CA<3>   
          	               	224       	85B1      	GND                 
          	               	225       	85B4      	M_B_CPU0_SB_CA<5>   
          	               	226       	85B1      	GND                 
          	               	227       	85B4      	M_B_CPU0_SB_PAR     
          	               	228       	85B1      	GND                 
          	               	229       	85B4      	M_B_CPU0_SB_CS_N<3> 
          	               	230       	85B1      	GND                 
          	               	231       	85B4      	TP_CHB_CPU0_DIMM2_FRU_5
          	               	232       	85B4      	TP_CHB_CPU0_DIMM2_FRU_6
          	               	233       	85B1      	GND                 
          	               	234       	85B4      	M_B_CPU0_SB_CB<6>   
          	               	235       	85B1      	GND                 
          	               	236       	85B4      	M_B_CPU0_SB_CB<7>   
          	               	237       	85B1      	GND                 
          	               	238       	85B2      	M_B_CPU0_SB_DQS_DN<4>
          	               	239       	85B2      	M_B_CPU0_SB_DQS_DP<4>
          	               	240       	85B1      	GND                 
          	               	241       	85B4      	M_B_CPU0_SB_CB<2>   
          	               	242       	85B1      	GND                 
          	               	243       	85B4      	M_B_CPU0_SB_CB<3>   
          	               	244       	85B1      	GND                 
          	               	245       	85B4      	M_B_CPU0_SB_DQ<2>   
          	               	246       	85B1      	GND                 
          	               	247       	85B4      	M_B_CPU0_SB_DQ<3>   
          	               	248       	85B1      	GND                 
          	               	249       	85B2      	M_B_CPU0_SB_DQS_DN<5>
          	               	250       	85B2      	M_B_CPU0_SB_DQS_DP<5>
          	               	251       	85B1      	GND                 
          	               	252       	85B4      	M_B_CPU0_SB_DQ<6>   
          	               	253       	85B1      	GND                 
          	               	254       	85B4      	M_B_CPU0_SB_DQ<7>   
          	               	255       	85B1      	GND                 
          	               	256       	85B4      	M_B_CPU0_SB_DQ<10>  
          	               	257       	85B1      	GND                 
          	               	258       	85B4      	M_B_CPU0_SB_DQ<11>  
          	               	259       	85B1      	GND                 
          	               	260       	85B2      	M_B_CPU0_SB_DQS_DN<6>
          	               	261       	85B2      	M_B_CPU0_SB_DQS_DP<6>
          	               	262       	85B1      	GND                 
          	               	263       	85B4      	M_B_CPU0_SB_DQ<14>  
          	               	264       	85B1      	GND                 
          	               	265       	85B4      	M_B_CPU0_SB_DQ<15>  
          	               	266       	85B1      	GND                 
          	               	267       	85B4      	M_B_CPU0_SB_DQ<18>  
          	               	268       	85B1      	GND                 
          	               	269       	85B4      	M_B_CPU0_SB_DQ<19>  
          	               	270       	85B1      	GND                 
          	               	271       	85B2      	M_B_CPU0_SB_DQS_DN<7>
          	               	272       	85B2      	M_B_CPU0_SB_DQS_DP<7>
          	               	273       	85B1      	GND                 
          	               	274       	85B4      	M_B_CPU0_SB_DQ<22>  
          	               	275       	85B1      	GND                 
          	               	276       	85B4      	M_B_CPU0_SB_DQ<23>  
          	               	277       	85B1      	GND                 
          	               	278       	85B4      	M_B_CPU0_SB_DQ<26>  
          	               	279       	85B1      	GND                 
          	               	280       	85B4      	M_B_CPU0_SB_DQ<27>  
          	               	281       	85B1      	GND                 
          	               	282       	85B2      	M_B_CPU0_SB_DQS_DN<8>
          	               	283       	85B2      	M_B_CPU0_SB_DQS_DP<8>
          	               	284       	85B1      	GND                 
          	               	285       	85B4      	M_B_CPU0_SB_DQ<30>  
          	               	286       	85B1      	GND                 
          	               	287       	85B4      	M_B_CPU0_SB_DQ<31>  
          	               	288       	85B1      	GND                 
          	               	G1        	85A1      	GND                 
          	               	G2        	85A1      	GND                 
          	               	G3        	85A1      	GND                 

J5        	SCONN288_ADR50017P130CC	          	          	                    
          	               	1         	86B1      	P12V_S3_AUX_CPU0_NVDIMM
          	               	2         	86B4      	TP_CHC_CPU0_DIMM1_FRU_0
          	               	3         	86B4      	P3V3_AUX            
          	               	4         	86B4      	I3C_SPD_DDRABCD_CPU0_LVC1_SCL_4
          	               	5         	86B4      	I3C_SPD_DDRABCD_CPU0_LVC1_SDA
          	               	6         	86B1      	GND                 
          	               	7         	86B4      	M_C_CPU0_SA_DQ<0>   
          	               	8         	86B1      	GND                 
          	               	9         	86B4      	M_C_CPU0_SA_DQ<1>   
          	               	10        	86B1      	GND                 
          	               	11        	86B2      	M_C_CPU0_SA_DQS_DP<0>
          	               	12        	86B2      	M_C_CPU0_SA_DQS_DN<0>
          	               	13        	86B1      	GND                 
          	               	14        	86B4      	M_C_CPU0_SA_DQ<4>   
          	               	15        	86B1      	GND                 
          	               	16        	86B4      	M_C_CPU0_SA_DQ<5>   
          	               	17        	86B1      	GND                 
          	               	18        	86B4      	M_C_CPU0_SA_DQ<8>   
          	               	19        	86B1      	GND                 
          	               	20        	86B4      	M_C_CPU0_SA_DQ<9>   
          	               	21        	86B1      	GND                 
          	               	22        	86B2      	M_C_CPU0_SA_DQS_DP<1>
          	               	23        	86B2      	M_C_CPU0_SA_DQS_DN<1>
          	               	24        	86B1      	GND                 
          	               	25        	86B4      	M_C_CPU0_SA_DQ<12>  
          	               	26        	86B1      	GND                 
          	               	27        	86B4      	M_C_CPU0_SA_DQ<13>  
          	               	28        	86B1      	GND                 
          	               	29        	86B4      	M_C_CPU0_SA_DQ<16>  
          	               	30        	86B1      	GND                 
          	               	31        	86B4      	M_C_CPU0_SA_DQ<17>  
          	               	32        	86B1      	GND                 
          	               	33        	86B2      	M_C_CPU0_SA_DQS_DP<2>
          	               	34        	86B2      	M_C_CPU0_SA_DQS_DN<2>
          	               	35        	86B1      	GND                 
          	               	36        	86B4      	M_C_CPU0_SA_DQ<20>  
          	               	37        	86B1      	GND                 
          	               	38        	86B4      	M_C_CPU0_SA_DQ<21>  
          	               	39        	86B1      	GND                 
          	               	40        	86B4      	M_C_CPU0_SA_DQ<24>  
          	               	41        	86B1      	GND                 
          	               	42        	86B4      	M_C_CPU0_SA_DQ<25>  
          	               	43        	86B1      	GND                 
          	               	44        	86B2      	M_C_CPU0_SA_DQS_DP<3>
          	               	45        	86B2      	M_C_CPU0_SA_DQS_DN<3>
          	               	46        	86B1      	GND                 
          	               	47        	86B4      	M_C_CPU0_SA_DQ<28>  
          	               	48        	86B1      	GND                 
          	               	49        	86B4      	M_C_CPU0_SA_DQ<29>  
          	               	50        	86B1      	GND                 
          	               	51        	86B4      	M_C_CPU0_SA_CB<0>   
          	               	52        	86B1      	GND                 
          	               	53        	86B4      	M_C_CPU0_SA_CB<1>   
          	               	54        	86B1      	GND                 
          	               	55        	86B2      	M_C_CPU0_SA_DQS_DP<4>
          	               	56        	86B2      	M_C_CPU0_SA_DQS_DN<4>
          	               	57        	86B1      	GND                 
          	               	58        	86B4      	M_C_CPU0_SA_CB<4>   
          	               	59        	86B1      	GND                 
          	               	60        	86B4      	M_C_CPU0_SA_CB<5>   
          	               	61        	86B1      	GND                 
          	               	62        	86B4      	M_C_CPU0_ALERT_N    
          	               	63        	86B1      	GND                 
          	               	64        	86B4      	M_C_CPU0_SA_CS_N<0> 
          	               	65        	86B1      	GND                 
          	               	66        	86B4      	M_C_CPU0_SA_CA<0>   
          	               	67        	86B1      	GND                 
          	               	68        	86B4      	M_C_CPU0_SA_CA<2>   
          	               	69        	86B1      	GND                 
          	               	70        	86B4      	M_C_CPU0_SA_CA<4>   
          	               	71        	86B1      	GND                 
          	               	72        	86B4      	M_C_CPU0_SA_CA<6>   
          	               	73        	86B1      	GND                 
          	               	74        	86B4      	M_C_CPU0_SA_PAR     
          	               	75        	86B1      	GND                 
          	               	76        	86B4      	M_C_CPU0_SB_CA<0>   
          	               	77        	86B1      	GND                 
          	               	78        	86B4      	M_C_CPU0_SB_CA<2>   
          	               	79        	86B1      	GND                 
          	               	80        	86B4      	M_C_CPU0_SB_CA<4>   
          	               	81        	86B1      	GND                 
          	               	82        	86B4      	M_C_CPU0_SB_CA<6>   
          	               	83        	86B1      	GND                 
          	               	84        	86B4      	M_C_CPU0_SB_CS_N<0> 
          	               	85        	86B1      	GND                 
          	               	86        	86A4      	M_C_CPU0_SA_RSP<0>  
          	               	87        	86A4      	M_C_CPU0_SB_RSP<0>  
          	               	88        	86B1      	GND                 
          	               	89        	86B4      	M_C_CPU0_SB_CB<4>   
          	               	90        	86B1      	GND                 
          	               	91        	86B4      	M_C_CPU0_SB_CB<5>   
          	               	92        	86B1      	GND                 
          	               	93        	86B2      	M_C_CPU0_SB_DQS_DP<9>
          	               	94        	86B2      	M_C_CPU0_SB_DQS_DN<9>
          	               	95        	86B1      	GND                 
          	               	96        	86B4      	M_C_CPU0_SB_CB<0>   
          	               	97        	86B1      	GND                 
          	               	98        	86B4      	M_C_CPU0_SB_CB<1>   
          	               	99        	86B1      	GND                 
          	               	100       	86B4      	M_C_CPU0_SB_DQ<0>   
          	               	101       	86B1      	GND                 
          	               	102       	86B4      	M_C_CPU0_SB_DQ<1>   
          	               	103       	86B1      	GND                 
          	               	104       	86B2      	M_C_CPU0_SB_DQS_DP<0>
          	               	105       	86B2      	M_C_CPU0_SB_DQS_DN<0>
          	               	106       	86B1      	GND                 
          	               	107       	86B4      	M_C_CPU0_SB_DQ<4>   
          	               	108       	86B1      	GND                 
          	               	109       	86B4      	M_C_CPU0_SB_DQ<5>   
          	               	110       	86B1      	GND                 
          	               	111       	86B4      	M_C_CPU0_SB_DQ<8>   
          	               	112       	86B1      	GND                 
          	               	113       	86B4      	M_C_CPU0_SB_DQ<9>   
          	               	114       	86B1      	GND                 
          	               	115       	86B2      	M_C_CPU0_SB_DQS_DP<1>
          	               	116       	86B2      	M_C_CPU0_SB_DQS_DN<1>
          	               	117       	86B1      	GND                 
          	               	118       	86B4      	M_C_CPU0_SB_DQ<12>  
          	               	119       	86B1      	GND                 
          	               	120       	86B4      	M_C_CPU0_SB_DQ<13>  
          	               	121       	86B1      	GND                 
          	               	122       	86B4      	M_C_CPU0_SB_DQ<16>  
          	               	123       	86B1      	GND                 
          	               	124       	86B4      	M_C_CPU0_SB_DQ<17>  
          	               	125       	86B1      	GND                 
          	               	126       	86B2      	M_C_CPU0_SB_DQS_DP<2>
          	               	127       	86B2      	M_C_CPU0_SB_DQS_DN<2>
          	               	128       	86B1      	GND                 
          	               	129       	86B4      	M_C_CPU0_SB_DQ<20>  
          	               	130       	86B1      	GND                 
          	               	131       	86B4      	M_C_CPU0_SB_DQ<21>  
          	               	132       	86B1      	GND                 
          	               	133       	86B4      	M_C_CPU0_SB_DQ<24>  
          	               	134       	86B1      	GND                 
          	               	135       	86B4      	M_C_CPU0_SB_DQ<25>  
          	               	136       	86B1      	GND                 
          	               	137       	86B2      	M_C_CPU0_SB_DQS_DP<3>
          	               	138       	86B2      	M_C_CPU0_SB_DQS_DN<3>
          	               	139       	86B1      	GND                 
          	               	140       	86B4      	M_C_CPU0_SB_DQ<28>  
          	               	141       	86B1      	GND                 
          	               	142       	86B4      	M_C_CPU0_SB_DQ<29>  
          	               	143       	86B1      	GND                 
          	               	144       	86B4      	TP_CHC_CPU0_DIMM1_FRU_1
          	               	145       	86B1      	P12V_S3_AUX_CPU0_NVDIMM
          	               	146       	86B1      	P12V_S3_AUX_CPU0_NVDIMM
          	               	147       	86B4      	PWRGD_CHC_CPU0_DIMM1
          	               	148       	86B4      	PD_CHC_CPU0_DIMM1_SAA
          	               	149       	86B4      	TP_CHC_CPU0_DIMM1_FRU_2
          	               	150       	86B4      	TP_CHC_CPU0_DIMM1_FRU_3
          	               	151       	86B1      	GND                 
          	               	152       	86B4      	M_C_CPU0_SA_DQ<2>   
          	               	153       	86B1      	GND                 
          	               	154       	86B4      	M_C_CPU0_SA_DQ<3>   
          	               	155       	86B1      	GND                 
          	               	156       	86B2      	M_C_CPU0_SA_DQS_DN<5>
          	               	157       	86B2      	M_C_CPU0_SA_DQS_DP<5>
          	               	158       	86B1      	GND                 
          	               	159       	86B4      	M_C_CPU0_SA_DQ<6>   
          	               	160       	86B1      	GND                 
          	               	161       	86B4      	M_C_CPU0_SA_DQ<7>   
          	               	162       	86B1      	GND                 
          	               	163       	86B4      	M_C_CPU0_SA_DQ<10>  
          	               	164       	86B1      	GND                 
          	               	165       	86B4      	M_C_CPU0_SA_DQ<11>  
          	               	166       	86B1      	GND                 
          	               	167       	86B2      	M_C_CPU0_SA_DQS_DN<6>
          	               	168       	86B2      	M_C_CPU0_SA_DQS_DP<6>
          	               	169       	86B1      	GND                 
          	               	170       	86B4      	M_C_CPU0_SA_DQ<14>  
          	               	171       	86B1      	GND                 
          	               	172       	86B4      	M_C_CPU0_SA_DQ<15>  
          	               	173       	86B1      	GND                 
          	               	174       	86B4      	M_C_CPU0_SA_DQ<18>  
          	               	175       	86B1      	GND                 
          	               	176       	86B4      	M_C_CPU0_SA_DQ<19>  
          	               	177       	86B1      	GND                 
          	               	178       	86B2      	M_C_CPU0_SA_DQS_DN<7>
          	               	179       	86B2      	M_C_CPU0_SA_DQS_DP<7>
          	               	180       	86B1      	GND                 
          	               	181       	86B4      	M_C_CPU0_SA_DQ<22>  
          	               	182       	86B1      	GND                 
          	               	183       	86B4      	M_C_CPU0_SA_DQ<23>  
          	               	184       	86B1      	GND                 
          	               	185       	86B4      	M_C_CPU0_SA_DQ<26>  
          	               	186       	86B1      	GND                 
          	               	187       	86B4      	M_C_CPU0_SA_DQ<27>  
          	               	188       	86B1      	GND                 
          	               	189       	86B2      	M_C_CPU0_SA_DQS_DN<8>
          	               	190       	86B2      	M_C_CPU0_SA_DQS_DP<8>
          	               	191       	86B1      	GND                 
          	               	192       	86B4      	M_C_CPU0_SA_DQ<30>  
          	               	193       	86B1      	GND                 
          	               	194       	86B4      	M_C_CPU0_SA_DQ<31>  
          	               	195       	86B1      	GND                 
          	               	196       	86B4      	M_C_CPU0_SA_CB<2>   
          	               	197       	86B1      	GND                 
          	               	198       	86B4      	M_C_CPU0_SA_CB<3>   
          	               	199       	86B1      	GND                 
          	               	200       	86B2      	M_C_CPU0_SA_DQS_DN<9>
          	               	201       	86B2      	M_C_CPU0_SA_DQS_DP<9>
          	               	202       	86B1      	GND                 
          	               	203       	86B4      	M_C_CPU0_SA_CB<6>   
          	               	204       	86B1      	GND                 
          	               	205       	86B4      	M_C_CPU0_SA_CB<7>   
          	               	206       	86B1      	GND                 
          	               	207       	86B4      	RST_M_CD_CPU0_FPGA_N
          	               	208       	86B1      	GND                 
          	               	209       	86B4      	M_C_CPU0_SA_CS_N<1> 
          	               	210       	86B1      	GND                 
          	               	211       	86B4      	M_C_CPU0_SA_CA<1>   
          	               	212       	86B1      	GND                 
          	               	213       	86B4      	M_C_CPU0_SA_CA<3>   
          	               	214       	86B1      	GND                 
          	               	215       	86B4      	M_C_CPU0_SA_CA<5>   
          	               	216       	86B1      	GND                 
          	               	217       	86B4      	M_C_CPU0_CLK_DP<0>  
          	               	218       	86B4      	M_C_CPU0_CLK_DN<0>  
          	               	219       	86B1      	GND                 
          	               	220       	86B4      	TP_CHC_CPU0_DIMM1_FRU_4
          	               	221       	86B4      	M_C_CPU0_SB_CA<1>   
          	               	222       	86B1      	GND                 
          	               	223       	86B4      	M_C_CPU0_SB_CA<3>   
          	               	224       	86B1      	GND                 
          	               	225       	86B4      	M_C_CPU0_SB_CA<5>   
          	               	226       	86B1      	GND                 
          	               	227       	86B4      	M_C_CPU0_SB_PAR     
          	               	228       	86B1      	GND                 
          	               	229       	86B4      	M_C_CPU0_SB_CS_N<1> 
          	               	230       	86B1      	GND                 
          	               	231       	86B4      	TP_CHC_CPU0_DIMM1_FRU_5
          	               	232       	86B4      	TP_CHC_CPU0_DIMM1_FRU_6
          	               	233       	86B1      	GND                 
          	               	234       	86B4      	M_C_CPU0_SB_CB<6>   
          	               	235       	86B1      	GND                 
          	               	236       	86B4      	M_C_CPU0_SB_CB<7>   
          	               	237       	86B1      	GND                 
          	               	238       	86B2      	M_C_CPU0_SB_DQS_DN<4>
          	               	239       	86B2      	M_C_CPU0_SB_DQS_DP<4>
          	               	240       	86B1      	GND                 
          	               	241       	86B4      	M_C_CPU0_SB_CB<2>   
          	               	242       	86B1      	GND                 
          	               	243       	86B4      	M_C_CPU0_SB_CB<3>   
          	               	244       	86B1      	GND                 
          	               	245       	86B4      	M_C_CPU0_SB_DQ<2>   
          	               	246       	86B1      	GND                 
          	               	247       	86B4      	M_C_CPU0_SB_DQ<3>   
          	               	248       	86B1      	GND                 
          	               	249       	86B2      	M_C_CPU0_SB_DQS_DN<5>
          	               	250       	86B2      	M_C_CPU0_SB_DQS_DP<5>
          	               	251       	86B1      	GND                 
          	               	252       	86B4      	M_C_CPU0_SB_DQ<6>   
          	               	253       	86B1      	GND                 
          	               	254       	86B4      	M_C_CPU0_SB_DQ<7>   
          	               	255       	86B1      	GND                 
          	               	256       	86B4      	M_C_CPU0_SB_DQ<10>  
          	               	257       	86B1      	GND                 
          	               	258       	86B4      	M_C_CPU0_SB_DQ<11>  
          	               	259       	86B1      	GND                 
          	               	260       	86B2      	M_C_CPU0_SB_DQS_DN<6>
          	               	261       	86B2      	M_C_CPU0_SB_DQS_DP<6>
          	               	262       	86B1      	GND                 
          	               	263       	86B4      	M_C_CPU0_SB_DQ<14>  
          	               	264       	86B1      	GND                 
          	               	265       	86B4      	M_C_CPU0_SB_DQ<15>  
          	               	266       	86B1      	GND                 
          	               	267       	86B4      	M_C_CPU0_SB_DQ<18>  
          	               	268       	86B1      	GND                 
          	               	269       	86B4      	M_C_CPU0_SB_DQ<19>  
          	               	270       	86B1      	GND                 
          	               	271       	86B2      	M_C_CPU0_SB_DQS_DN<7>
          	               	272       	86B2      	M_C_CPU0_SB_DQS_DP<7>
          	               	273       	86B1      	GND                 
          	               	274       	86B4      	M_C_CPU0_SB_DQ<22>  
          	               	275       	86B1      	GND                 
          	               	276       	86B4      	M_C_CPU0_SB_DQ<23>  
          	               	277       	86B1      	GND                 
          	               	278       	86B4      	M_C_CPU0_SB_DQ<26>  
          	               	279       	86B1      	GND                 
          	               	280       	86B4      	M_C_CPU0_SB_DQ<27>  
          	               	281       	86B1      	GND                 
          	               	282       	86B2      	M_C_CPU0_SB_DQS_DN<8>
          	               	283       	86B2      	M_C_CPU0_SB_DQS_DP<8>
          	               	284       	86B1      	GND                 
          	               	285       	86B4      	M_C_CPU0_SB_DQ<30>  
          	               	286       	86B1      	GND                 
          	               	287       	86B4      	M_C_CPU0_SB_DQ<31>  
          	               	288       	86B1      	GND                 
          	               	G1        	86B1      	GND                 
          	               	G2        	86A1      	GND                 
          	               	G3        	86A1      	GND                 

J6        	SCONN288_ADR50017P087CC	          	          	                    
          	               	1         	87B1      	P12V_S3_AUX_CPU0_NVDIMM
          	               	2         	87B4      	TP_CHC_CPU0_DIMM2_FRU_0
          	               	3         	87B4      	P3V3_AUX            
          	               	4         	87B4      	I3C_SPD_DDRABCD_CPU0_LVC1_SCL_5
          	               	5         	87B4      	I3C_SPD_DDRABCD_CPU0_LVC1_SDA
          	               	6         	87B1      	GND                 
          	               	7         	87B4      	M_C_CPU0_SA_DQ<0>   
          	               	8         	87B1      	GND                 
          	               	9         	87B4      	M_C_CPU0_SA_DQ<1>   
          	               	10        	87B1      	GND                 
          	               	11        	87B2      	M_C_CPU0_SA_DQS_DP<0>
          	               	12        	87B2      	M_C_CPU0_SA_DQS_DN<0>
          	               	13        	87B1      	GND                 
          	               	14        	87B4      	M_C_CPU0_SA_DQ<4>   
          	               	15        	87B1      	GND                 
          	               	16        	87B4      	M_C_CPU0_SA_DQ<5>   
          	               	17        	87B1      	GND                 
          	               	18        	87B4      	M_C_CPU0_SA_DQ<8>   
          	               	19        	87B1      	GND                 
          	               	20        	87B4      	M_C_CPU0_SA_DQ<9>   
          	               	21        	87B1      	GND                 
          	               	22        	87B2      	M_C_CPU0_SA_DQS_DP<1>
          	               	23        	87B2      	M_C_CPU0_SA_DQS_DN<1>
          	               	24        	87B1      	GND                 
          	               	25        	87B4      	M_C_CPU0_SA_DQ<12>  
          	               	26        	87B1      	GND                 
          	               	27        	87B4      	M_C_CPU0_SA_DQ<13>  
          	               	28        	87B1      	GND                 
          	               	29        	87B4      	M_C_CPU0_SA_DQ<16>  
          	               	30        	87B1      	GND                 
          	               	31        	87B4      	M_C_CPU0_SA_DQ<17>  
          	               	32        	87B1      	GND                 
          	               	33        	87B2      	M_C_CPU0_SA_DQS_DP<2>
          	               	34        	87B2      	M_C_CPU0_SA_DQS_DN<2>
          	               	35        	87B1      	GND                 
          	               	36        	87B4      	M_C_CPU0_SA_DQ<20>  
          	               	37        	87B1      	GND                 
          	               	38        	87B4      	M_C_CPU0_SA_DQ<21>  
          	               	39        	87B1      	GND                 
          	               	40        	87B4      	M_C_CPU0_SA_DQ<24>  
          	               	41        	87B1      	GND                 
          	               	42        	87B4      	M_C_CPU0_SA_DQ<25>  
          	               	43        	87B1      	GND                 
          	               	44        	87B2      	M_C_CPU0_SA_DQS_DP<3>
          	               	45        	87B2      	M_C_CPU0_SA_DQS_DN<3>
          	               	46        	87B1      	GND                 
          	               	47        	87B4      	M_C_CPU0_SA_DQ<28>  
          	               	48        	87B1      	GND                 
          	               	49        	87B4      	M_C_CPU0_SA_DQ<29>  
          	               	50        	87B1      	GND                 
          	               	51        	87B4      	M_C_CPU0_SA_CB<0>   
          	               	52        	87B1      	GND                 
          	               	53        	87B4      	M_C_CPU0_SA_CB<1>   
          	               	54        	87B1      	GND                 
          	               	55        	87B2      	M_C_CPU0_SA_DQS_DP<4>
          	               	56        	87B2      	M_C_CPU0_SA_DQS_DN<4>
          	               	57        	87B1      	GND                 
          	               	58        	87B4      	M_C_CPU0_SA_CB<4>   
          	               	59        	87B1      	GND                 
          	               	60        	87B4      	M_C_CPU0_SA_CB<5>   
          	               	61        	87B1      	GND                 
          	               	62        	87B4      	M_C_CPU0_ALERT_N    
          	               	63        	87B1      	GND                 
          	               	64        	87B4      	M_C_CPU0_SA_CS_N<2> 
          	               	65        	87B1      	GND                 
          	               	66        	87B4      	M_C_CPU0_SA_CA<0>   
          	               	67        	87B1      	GND                 
          	               	68        	87B4      	M_C_CPU0_SA_CA<2>   
          	               	69        	87B1      	GND                 
          	               	70        	87B4      	M_C_CPU0_SA_CA<4>   
          	               	71        	87B1      	GND                 
          	               	72        	87B4      	M_C_CPU0_SA_CA<6>   
          	               	73        	87B1      	GND                 
          	               	74        	87B4      	M_C_CPU0_SA_PAR     
          	               	75        	87B1      	GND                 
          	               	76        	87B4      	M_C_CPU0_SB_CA<0>   
          	               	77        	87B1      	GND                 
          	               	78        	87B4      	M_C_CPU0_SB_CA<2>   
          	               	79        	87B1      	GND                 
          	               	80        	87B4      	M_C_CPU0_SB_CA<4>   
          	               	81        	87B1      	GND                 
          	               	82        	87B4      	M_C_CPU0_SB_CA<6>   
          	               	83        	87B1      	GND                 
          	               	84        	87B4      	M_C_CPU0_SB_CS_N<2> 
          	               	85        	87B1      	GND                 
          	               	86        	87A4      	M_C_CPU0_SA_RSP<1>  
          	               	87        	87A4      	M_C_CPU0_SB_RSP<1>  
          	               	88        	87B1      	GND                 
          	               	89        	87B4      	M_C_CPU0_SB_CB<4>   
          	               	90        	87B1      	GND                 
          	               	91        	87B4      	M_C_CPU0_SB_CB<5>   
          	               	92        	87B1      	GND                 
          	               	93        	87B2      	M_C_CPU0_SB_DQS_DP<9>
          	               	94        	87B2      	M_C_CPU0_SB_DQS_DN<9>
          	               	95        	87B1      	GND                 
          	               	96        	87B4      	M_C_CPU0_SB_CB<0>   
          	               	97        	87B1      	GND                 
          	               	98        	87B4      	M_C_CPU0_SB_CB<1>   
          	               	99        	87B1      	GND                 
          	               	100       	87B4      	M_C_CPU0_SB_DQ<0>   
          	               	101       	87B1      	GND                 
          	               	102       	87B4      	M_C_CPU0_SB_DQ<1>   
          	               	103       	87B1      	GND                 
          	               	104       	87B2      	M_C_CPU0_SB_DQS_DP<0>
          	               	105       	87B2      	M_C_CPU0_SB_DQS_DN<0>
          	               	106       	87B1      	GND                 
          	               	107       	87B4      	M_C_CPU0_SB_DQ<4>   
          	               	108       	87B1      	GND                 
          	               	109       	87B4      	M_C_CPU0_SB_DQ<5>   
          	               	110       	87B1      	GND                 
          	               	111       	87B4      	M_C_CPU0_SB_DQ<8>   
          	               	112       	87B1      	GND                 
          	               	113       	87B4      	M_C_CPU0_SB_DQ<9>   
          	               	114       	87B1      	GND                 
          	               	115       	87B2      	M_C_CPU0_SB_DQS_DP<1>
          	               	116       	87B2      	M_C_CPU0_SB_DQS_DN<1>
          	               	117       	87B1      	GND                 
          	               	118       	87B4      	M_C_CPU0_SB_DQ<12>  
          	               	119       	87B1      	GND                 
          	               	120       	87B4      	M_C_CPU0_SB_DQ<13>  
          	               	121       	87B1      	GND                 
          	               	122       	87B4      	M_C_CPU0_SB_DQ<16>  
          	               	123       	87B1      	GND                 
          	               	124       	87B4      	M_C_CPU0_SB_DQ<17>  
          	               	125       	87B1      	GND                 
          	               	126       	87B2      	M_C_CPU0_SB_DQS_DP<2>
          	               	127       	87B2      	M_C_CPU0_SB_DQS_DN<2>
          	               	128       	87B1      	GND                 
          	               	129       	87B4      	M_C_CPU0_SB_DQ<20>  
          	               	130       	87B1      	GND                 
          	               	131       	87B4      	M_C_CPU0_SB_DQ<21>  
          	               	132       	87B1      	GND                 
          	               	133       	87B4      	M_C_CPU0_SB_DQ<24>  
          	               	134       	87B1      	GND                 
          	               	135       	87B4      	M_C_CPU0_SB_DQ<25>  
          	               	136       	87B1      	GND                 
          	               	137       	87B2      	M_C_CPU0_SB_DQS_DP<3>
          	               	138       	87B2      	M_C_CPU0_SB_DQS_DN<3>
          	               	139       	87B1      	GND                 
          	               	140       	87B4      	M_C_CPU0_SB_DQ<28>  
          	               	141       	87B1      	GND                 
          	               	142       	87B4      	M_C_CPU0_SB_DQ<29>  
          	               	143       	87B1      	GND                 
          	               	144       	87B4      	TP_CHC_CPU0_DIMM2_FRU_1
          	               	145       	87B1      	P12V_S3_AUX_CPU0_NVDIMM
          	               	146       	87B1      	P12V_S3_AUX_CPU0_NVDIMM
          	               	147       	87B4      	PWRGD_CHC_CPU0_DIMM2
          	               	148       	87B4      	PD_CHC_CPU0_DIMM2_SAA
          	               	149       	87B4      	TP_CHC_CPU0_DIMM2_FRU_2
          	               	150       	87B4      	TP_CHC_CPU0_DIMM2_FRU_3
          	               	151       	87B1      	GND                 
          	               	152       	87B4      	M_C_CPU0_SA_DQ<2>   
          	               	153       	87B1      	GND                 
          	               	154       	87B4      	M_C_CPU0_SA_DQ<3>   
          	               	155       	87B1      	GND                 
          	               	156       	87B2      	M_C_CPU0_SA_DQS_DN<5>
          	               	157       	87B2      	M_C_CPU0_SA_DQS_DP<5>
          	               	158       	87B1      	GND                 
          	               	159       	87B4      	M_C_CPU0_SA_DQ<6>   
          	               	160       	87B1      	GND                 
          	               	161       	87B4      	M_C_CPU0_SA_DQ<7>   
          	               	162       	87B1      	GND                 
          	               	163       	87B4      	M_C_CPU0_SA_DQ<10>  
          	               	164       	87B1      	GND                 
          	               	165       	87B4      	M_C_CPU0_SA_DQ<11>  
          	               	166       	87B1      	GND                 
          	               	167       	87B2      	M_C_CPU0_SA_DQS_DN<6>
          	               	168       	87B2      	M_C_CPU0_SA_DQS_DP<6>
          	               	169       	87B1      	GND                 
          	               	170       	87B4      	M_C_CPU0_SA_DQ<14>  
          	               	171       	87B1      	GND                 
          	               	172       	87B4      	M_C_CPU0_SA_DQ<15>  
          	               	173       	87B1      	GND                 
          	               	174       	87B4      	M_C_CPU0_SA_DQ<18>  
          	               	175       	87B1      	GND                 
          	               	176       	87B4      	M_C_CPU0_SA_DQ<19>  
          	               	177       	87B1      	GND                 
          	               	178       	87B2      	M_C_CPU0_SA_DQS_DN<7>
          	               	179       	87B2      	M_C_CPU0_SA_DQS_DP<7>
          	               	180       	87B1      	GND                 
          	               	181       	87B4      	M_C_CPU0_SA_DQ<22>  
          	               	182       	87B1      	GND                 
          	               	183       	87B4      	M_C_CPU0_SA_DQ<23>  
          	               	184       	87B1      	GND                 
          	               	185       	87B4      	M_C_CPU0_SA_DQ<26>  
          	               	186       	87B1      	GND                 
          	               	187       	87B4      	M_C_CPU0_SA_DQ<27>  
          	               	188       	87B1      	GND                 
          	               	189       	87B2      	M_C_CPU0_SA_DQS_DN<8>
          	               	190       	87B2      	M_C_CPU0_SA_DQS_DP<8>
          	               	191       	87B1      	GND                 
          	               	192       	87B4      	M_C_CPU0_SA_DQ<30>  
          	               	193       	87B1      	GND                 
          	               	194       	87B4      	M_C_CPU0_SA_DQ<31>  
          	               	195       	87B1      	GND                 
          	               	196       	87B4      	M_C_CPU0_SA_CB<2>   
          	               	197       	87B1      	GND                 
          	               	198       	87B4      	M_C_CPU0_SA_CB<3>   
          	               	199       	87B1      	GND                 
          	               	200       	87B2      	M_C_CPU0_SA_DQS_DN<9>
          	               	201       	87B2      	M_C_CPU0_SA_DQS_DP<9>
          	               	202       	87B1      	GND                 
          	               	203       	87B4      	M_C_CPU0_SA_CB<6>   
          	               	204       	87B1      	GND                 
          	               	205       	87B4      	M_C_CPU0_SA_CB<7>   
          	               	206       	87B1      	GND                 
          	               	207       	87B4      	RST_M_CD_CPU0_FPGA_N
          	               	208       	87B1      	GND                 
          	               	209       	87B4      	M_C_CPU0_SA_CS_N<3> 
          	               	210       	87B1      	GND                 
          	               	211       	87B4      	M_C_CPU0_SA_CA<1>   
          	               	212       	87B1      	GND                 
          	               	213       	87B4      	M_C_CPU0_SA_CA<3>   
          	               	214       	87B1      	GND                 
          	               	215       	87B4      	M_C_CPU0_SA_CA<5>   
          	               	216       	87B1      	GND                 
          	               	217       	87B4      	M_C_CPU0_CLK_DP<1>  
          	               	218       	87B4      	M_C_CPU0_CLK_DN<1>  
          	               	219       	87B1      	GND                 
          	               	220       	87B4      	TP_CHC_CPU0_DIMM2_FRU_4
          	               	221       	87B4      	M_C_CPU0_SB_CA<1>   
          	               	222       	87B1      	GND                 
          	               	223       	87B4      	M_C_CPU0_SB_CA<3>   
          	               	224       	87B1      	GND                 
          	               	225       	87B4      	M_C_CPU0_SB_CA<5>   
          	               	226       	87B1      	GND                 
          	               	227       	87B4      	M_C_CPU0_SB_PAR     
          	               	228       	87B1      	GND                 
          	               	229       	87B4      	M_C_CPU0_SB_CS_N<3> 
          	               	230       	87B1      	GND                 
          	               	231       	87B4      	TP_CHC_CPU0_DIMM2_FRU_5
          	               	232       	87B4      	TP_CHC_CPU0_DIMM2_FRU_6
          	               	233       	87B1      	GND                 
          	               	234       	87B4      	M_C_CPU0_SB_CB<6>   
          	               	235       	87B1      	GND                 
          	               	236       	87B4      	M_C_CPU0_SB_CB<7>   
          	               	237       	87B1      	GND                 
          	               	238       	87B2      	M_C_CPU0_SB_DQS_DN<4>
          	               	239       	87B2      	M_C_CPU0_SB_DQS_DP<4>
          	               	240       	87B1      	GND                 
          	               	241       	87B4      	M_C_CPU0_SB_CB<2>   
          	               	242       	87B1      	GND                 
          	               	243       	87B4      	M_C_CPU0_SB_CB<3>   
          	               	244       	87B1      	GND                 
          	               	245       	87B4      	M_C_CPU0_SB_DQ<2>   
          	               	246       	87B1      	GND                 
          	               	247       	87B4      	M_C_CPU0_SB_DQ<3>   
          	               	248       	87B1      	GND                 
          	               	249       	87B2      	M_C_CPU0_SB_DQS_DN<5>
          	               	250       	87B2      	M_C_CPU0_SB_DQS_DP<5>
          	               	251       	87B1      	GND                 
          	               	252       	87B4      	M_C_CPU0_SB_DQ<6>   
          	               	253       	87B1      	GND                 
          	               	254       	87B4      	M_C_CPU0_SB_DQ<7>   
          	               	255       	87B1      	GND                 
          	               	256       	87B4      	M_C_CPU0_SB_DQ<10>  
          	               	257       	87B1      	GND                 
          	               	258       	87B4      	M_C_CPU0_SB_DQ<11>  
          	               	259       	87B1      	GND                 
          	               	260       	87B2      	M_C_CPU0_SB_DQS_DN<6>
          	               	261       	87B2      	M_C_CPU0_SB_DQS_DP<6>
          	               	262       	87B1      	GND                 
          	               	263       	87B4      	M_C_CPU0_SB_DQ<14>  
          	               	264       	87B1      	GND                 
          	               	265       	87B4      	M_C_CPU0_SB_DQ<15>  
          	               	266       	87B1      	GND                 
          	               	267       	87B4      	M_C_CPU0_SB_DQ<18>  
          	               	268       	87B1      	GND                 
          	               	269       	87B4      	M_C_CPU0_SB_DQ<19>  
          	               	270       	87B1      	GND                 
          	               	271       	87B2      	M_C_CPU0_SB_DQS_DN<7>
          	               	272       	87B2      	M_C_CPU0_SB_DQS_DP<7>
          	               	273       	87B1      	GND                 
          	               	274       	87B4      	M_C_CPU0_SB_DQ<22>  
          	               	275       	87B1      	GND                 
          	               	276       	87B4      	M_C_CPU0_SB_DQ<23>  
          	               	277       	87B1      	GND                 
          	               	278       	87B4      	M_C_CPU0_SB_DQ<26>  
          	               	279       	87B1      	GND                 
          	               	280       	87B4      	M_C_CPU0_SB_DQ<27>  
          	               	281       	87B1      	GND                 
          	               	282       	87B2      	M_C_CPU0_SB_DQS_DN<8>
          	               	283       	87B2      	M_C_CPU0_SB_DQS_DP<8>
          	               	284       	87B1      	GND                 
          	               	285       	87B4      	M_C_CPU0_SB_DQ<30>  
          	               	286       	87B1      	GND                 
          	               	287       	87B4      	M_C_CPU0_SB_DQ<31>  
          	               	288       	87B1      	GND                 
          	               	G1        	87B1      	GND                 
          	               	G2        	87A1      	GND                 
          	               	G3        	87A1      	GND                 

J7        	SCONN288_ADR50017P130CC	          	          	                    
          	               	1         	88B1      	P12V_S3_AUX_CPU0_NVDIMM
          	               	2         	88B4      	TP_CHD_CPU0_DIMM1_FRU_0
          	               	3         	88B4      	P3V3_AUX            
          	               	4         	88B4      	I3C_SPD_DDRABCD_CPU0_LVC1_SCL_6
          	               	5         	88B4      	I3C_SPD_DDRABCD_CPU0_LVC1_SDA
          	               	6         	88B1      	GND                 
          	               	7         	88B4      	M_D_CPU0_SA_DQ<0>   
          	               	8         	88B1      	GND                 
          	               	9         	88B4      	M_D_CPU0_SA_DQ<1>   
          	               	10        	88B1      	GND                 
          	               	11        	88B2      	M_D_CPU0_SA_DQS_DP<0>
          	               	12        	88B2      	M_D_CPU0_SA_DQS_DN<0>
          	               	13        	88B1      	GND                 
          	               	14        	88B4      	M_D_CPU0_SA_DQ<4>   
          	               	15        	88B1      	GND                 
          	               	16        	88B4      	M_D_CPU0_SA_DQ<5>   
          	               	17        	88B1      	GND                 
          	               	18        	88B4      	M_D_CPU0_SA_DQ<8>   
          	               	19        	88B1      	GND                 
          	               	20        	88B4      	M_D_CPU0_SA_DQ<9>   
          	               	21        	88B1      	GND                 
          	               	22        	88B2      	M_D_CPU0_SA_DQS_DP<1>
          	               	23        	88B2      	M_D_CPU0_SA_DQS_DN<1>
          	               	24        	88B1      	GND                 
          	               	25        	88B4      	M_D_CPU0_SA_DQ<12>  
          	               	26        	88B1      	GND                 
          	               	27        	88B4      	M_D_CPU0_SA_DQ<13>  
          	               	28        	88B1      	GND                 
          	               	29        	88B4      	M_D_CPU0_SA_DQ<16>  
          	               	30        	88B1      	GND                 
          	               	31        	88B4      	M_D_CPU0_SA_DQ<17>  
          	               	32        	88B1      	GND                 
          	               	33        	88B2      	M_D_CPU0_SA_DQS_DP<2>
          	               	34        	88B2      	M_D_CPU0_SA_DQS_DN<2>
          	               	35        	88B1      	GND                 
          	               	36        	88B4      	M_D_CPU0_SA_DQ<20>  
          	               	37        	88B1      	GND                 
          	               	38        	88B4      	M_D_CPU0_SA_DQ<21>  
          	               	39        	88B1      	GND                 
          	               	40        	88B4      	M_D_CPU0_SA_DQ<24>  
          	               	41        	88B1      	GND                 
          	               	42        	88B4      	M_D_CPU0_SA_DQ<25>  
          	               	43        	88B1      	GND                 
          	               	44        	88B2      	M_D_CPU0_SA_DQS_DP<3>
          	               	45        	88B2      	M_D_CPU0_SA_DQS_DN<3>
          	               	46        	88B1      	GND                 
          	               	47        	88B4      	M_D_CPU0_SA_DQ<28>  
          	               	48        	88B1      	GND                 
          	               	49        	88B4      	M_D_CPU0_SA_DQ<29>  
          	               	50        	88B1      	GND                 
          	               	51        	88B4      	M_D_CPU0_SA_CB<0>   
          	               	52        	88B1      	GND                 
          	               	53        	88B4      	M_D_CPU0_SA_CB<1>   
          	               	54        	88B1      	GND                 
          	               	55        	88B2      	M_D_CPU0_SA_DQS_DP<4>
          	               	56        	88B2      	M_D_CPU0_SA_DQS_DN<4>
          	               	57        	88B1      	GND                 
          	               	58        	88B4      	M_D_CPU0_SA_CB<4>   
          	               	59        	88B1      	GND                 
          	               	60        	88B4      	M_D_CPU0_SA_CB<5>   
          	               	61        	88B1      	GND                 
          	               	62        	88B4      	M_D_CPU0_ALERT_N    
          	               	63        	88B1      	GND                 
          	               	64        	88B4      	M_D_CPU0_SA_CS_N<0> 
          	               	65        	88B1      	GND                 
          	               	66        	88B4      	M_D_CPU0_SA_CA<0>   
          	               	67        	88B1      	GND                 
          	               	68        	88B4      	M_D_CPU0_SA_CA<2>   
          	               	69        	88B1      	GND                 
          	               	70        	88B4      	M_D_CPU0_SA_CA<4>   
          	               	71        	88B1      	GND                 
          	               	72        	88B4      	M_D_CPU0_SA_CA<6>   
          	               	73        	88B1      	GND                 
          	               	74        	88B4      	M_D_CPU0_SA_PAR     
          	               	75        	88B1      	GND                 
          	               	76        	88B4      	M_D_CPU0_SB_CA<0>   
          	               	77        	88B1      	GND                 
          	               	78        	88B4      	M_D_CPU0_SB_CA<2>   
          	               	79        	88B1      	GND                 
          	               	80        	88B4      	M_D_CPU0_SB_CA<4>   
          	               	81        	88B1      	GND                 
          	               	82        	88B4      	M_D_CPU0_SB_CA<6>   
          	               	83        	88B1      	GND                 
          	               	84        	88B4      	M_D_CPU0_SB_CS_N<0> 
          	               	85        	88B1      	GND                 
          	               	86        	88A4      	M_D_CPU0_SA_RSP<0>  
          	               	87        	88A4      	M_D_CPU0_SB_RSP<0>  
          	               	88        	88B1      	GND                 
          	               	89        	88B4      	M_D_CPU0_SB_CB<4>   
          	               	90        	88B1      	GND                 
          	               	91        	88B4      	M_D_CPU0_SB_CB<5>   
          	               	92        	88B1      	GND                 
          	               	93        	88B2      	M_D_CPU0_SB_DQS_DP<9>
          	               	94        	88B2      	M_D_CPU0_SB_DQS_DN<9>
          	               	95        	88B1      	GND                 
          	               	96        	88B4      	M_D_CPU0_SB_CB<0>   
          	               	97        	88B1      	GND                 
          	               	98        	88B4      	M_D_CPU0_SB_CB<1>   
          	               	99        	88B1      	GND                 
          	               	100       	88B4      	M_D_CPU0_SB_DQ<0>   
          	               	101       	88B1      	GND                 
          	               	102       	88B4      	M_D_CPU0_SB_DQ<1>   
          	               	103       	88B1      	GND                 
          	               	104       	88B2      	M_D_CPU0_SB_DQS_DP<0>
          	               	105       	88B2      	M_D_CPU0_SB_DQS_DN<0>
          	               	106       	88B1      	GND                 
          	               	107       	88B4      	M_D_CPU0_SB_DQ<4>   
          	               	108       	88B1      	GND                 
          	               	109       	88B4      	M_D_CPU0_SB_DQ<5>   
          	               	110       	88B1      	GND                 
          	               	111       	88B4      	M_D_CPU0_SB_DQ<8>   
          	               	112       	88B1      	GND                 
          	               	113       	88B4      	M_D_CPU0_SB_DQ<9>   
          	               	114       	88B1      	GND                 
          	               	115       	88B2      	M_D_CPU0_SB_DQS_DP<1>
          	               	116       	88B2      	M_D_CPU0_SB_DQS_DN<1>
          	               	117       	88B1      	GND                 
          	               	118       	88B4      	M_D_CPU0_SB_DQ<12>  
          	               	119       	88B1      	GND                 
          	               	120       	88B4      	M_D_CPU0_SB_DQ<13>  
          	               	121       	88B1      	GND                 
          	               	122       	88B4      	M_D_CPU0_SB_DQ<16>  
          	               	123       	88B1      	GND                 
          	               	124       	88B4      	M_D_CPU0_SB_DQ<17>  
          	               	125       	88B1      	GND                 
          	               	126       	88B2      	M_D_CPU0_SB_DQS_DP<2>
          	               	127       	88B2      	M_D_CPU0_SB_DQS_DN<2>
          	               	128       	88B1      	GND                 
          	               	129       	88B4      	M_D_CPU0_SB_DQ<20>  
          	               	130       	88B1      	GND                 
          	               	131       	88B4      	M_D_CPU0_SB_DQ<21>  
          	               	132       	88B1      	GND                 
          	               	133       	88B4      	M_D_CPU0_SB_DQ<24>  
          	               	134       	88B1      	GND                 
          	               	135       	88B4      	M_D_CPU0_SB_DQ<25>  
          	               	136       	88B1      	GND                 
          	               	137       	88B2      	M_D_CPU0_SB_DQS_DP<3>
          	               	138       	88B2      	M_D_CPU0_SB_DQS_DN<3>
          	               	139       	88B1      	GND                 
          	               	140       	88B4      	M_D_CPU0_SB_DQ<28>  
          	               	141       	88B1      	GND                 
          	               	142       	88B4      	M_D_CPU0_SB_DQ<29>  
          	               	143       	88B1      	GND                 
          	               	144       	88B4      	TP_CHD_CPU0_DIMM1_FRU_1
          	               	145       	88B1      	P12V_S3_AUX_CPU0_NVDIMM
          	               	146       	88B1      	P12V_S3_AUX_CPU0_NVDIMM
          	               	147       	88B4      	PWRGD_CHD_CPU0_DIMM1
          	               	148       	88B4      	PD_CHD_CPU0_DIMM1_SAA
          	               	149       	88B4      	TP_CHD_CPU0_DIMM1_FRU_2
          	               	150       	88B4      	TP_CHD_CPU0_DIMM1_FRU_3
          	               	151       	88B1      	GND                 
          	               	152       	88B4      	M_D_CPU0_SA_DQ<2>   
          	               	153       	88B1      	GND                 
          	               	154       	88B4      	M_D_CPU0_SA_DQ<3>   
          	               	155       	88B1      	GND                 
          	               	156       	88B2      	M_D_CPU0_SA_DQS_DN<5>
          	               	157       	88B2      	M_D_CPU0_SA_DQS_DP<5>
          	               	158       	88B1      	GND                 
          	               	159       	88B4      	M_D_CPU0_SA_DQ<6>   
          	               	160       	88B1      	GND                 
          	               	161       	88B4      	M_D_CPU0_SA_DQ<7>   
          	               	162       	88B1      	GND                 
          	               	163       	88B4      	M_D_CPU0_SA_DQ<10>  
          	               	164       	88B1      	GND                 
          	               	165       	88B4      	M_D_CPU0_SA_DQ<11>  
          	               	166       	88B1      	GND                 
          	               	167       	88B2      	M_D_CPU0_SA_DQS_DN<6>
          	               	168       	88B2      	M_D_CPU0_SA_DQS_DP<6>
          	               	169       	88B1      	GND                 
          	               	170       	88B4      	M_D_CPU0_SA_DQ<14>  
          	               	171       	88B1      	GND                 
          	               	172       	88B4      	M_D_CPU0_SA_DQ<15>  
          	               	173       	88B1      	GND                 
          	               	174       	88B4      	M_D_CPU0_SA_DQ<18>  
          	               	175       	88B1      	GND                 
          	               	176       	88B4      	M_D_CPU0_SA_DQ<19>  
          	               	177       	88B1      	GND                 
          	               	178       	88B2      	M_D_CPU0_SA_DQS_DN<7>
          	               	179       	88B2      	M_D_CPU0_SA_DQS_DP<7>
          	               	180       	88B1      	GND                 
          	               	181       	88B4      	M_D_CPU0_SA_DQ<22>  
          	               	182       	88B1      	GND                 
          	               	183       	88B4      	M_D_CPU0_SA_DQ<23>  
          	               	184       	88B1      	GND                 
          	               	185       	88B4      	M_D_CPU0_SA_DQ<26>  
          	               	186       	88B1      	GND                 
          	               	187       	88B4      	M_D_CPU0_SA_DQ<27>  
          	               	188       	88B1      	GND                 
          	               	189       	88B2      	M_D_CPU0_SA_DQS_DN<8>
          	               	190       	88B2      	M_D_CPU0_SA_DQS_DP<8>
          	               	191       	88B1      	GND                 
          	               	192       	88B4      	M_D_CPU0_SA_DQ<30>  
          	               	193       	88B1      	GND                 
          	               	194       	88B4      	M_D_CPU0_SA_DQ<31>  
          	               	195       	88B1      	GND                 
          	               	196       	88B4      	M_D_CPU0_SA_CB<2>   
          	               	197       	88B1      	GND                 
          	               	198       	88B4      	M_D_CPU0_SA_CB<3>   
          	               	199       	88B1      	GND                 
          	               	200       	88B2      	M_D_CPU0_SA_DQS_DN<9>
          	               	201       	88B2      	M_D_CPU0_SA_DQS_DP<9>
          	               	202       	88B1      	GND                 
          	               	203       	88B4      	M_D_CPU0_SA_CB<6>   
          	               	204       	88B1      	GND                 
          	               	205       	88B4      	M_D_CPU0_SA_CB<7>   
          	               	206       	88B1      	GND                 
          	               	207       	88B4      	RST_M_CD_CPU0_FPGA_N
          	               	208       	88B1      	GND                 
          	               	209       	88B4      	M_D_CPU0_SA_CS_N<1> 
          	               	210       	88B1      	GND                 
          	               	211       	88B4      	M_D_CPU0_SA_CA<1>   
          	               	212       	88B1      	GND                 
          	               	213       	88B4      	M_D_CPU0_SA_CA<3>   
          	               	214       	88B1      	GND                 
          	               	215       	88B4      	M_D_CPU0_SA_CA<5>   
          	               	216       	88B1      	GND                 
          	               	217       	88B4      	M_D_CPU0_CLK_DP<0>  
          	               	218       	88B4      	M_D_CPU0_CLK_DN<0>  
          	               	219       	88B1      	GND                 
          	               	220       	88B4      	TP_CHD_CPU0_DIMM1_FRU_4
          	               	221       	88B4      	M_D_CPU0_SB_CA<1>   
          	               	222       	88B1      	GND                 
          	               	223       	88B4      	M_D_CPU0_SB_CA<3>   
          	               	224       	88B1      	GND                 
          	               	225       	88B4      	M_D_CPU0_SB_CA<5>   
          	               	226       	88B1      	GND                 
          	               	227       	88B4      	M_D_CPU0_SB_PAR     
          	               	228       	88B1      	GND                 
          	               	229       	88B4      	M_D_CPU0_SB_CS_N<1> 
          	               	230       	88B1      	GND                 
          	               	231       	88B4      	TP_CHD_CPU0_DIMM1_FRU_5
          	               	232       	88B4      	TP_CHD_CPU0_DIMM1_FRU_6
          	               	233       	88B1      	GND                 
          	               	234       	88B4      	M_D_CPU0_SB_CB<6>   
          	               	235       	88B1      	GND                 
          	               	236       	88B4      	M_D_CPU0_SB_CB<7>   
          	               	237       	88B1      	GND                 
          	               	238       	88B2      	M_D_CPU0_SB_DQS_DN<4>
          	               	239       	88B2      	M_D_CPU0_SB_DQS_DP<4>
          	               	240       	88B1      	GND                 
          	               	241       	88B4      	M_D_CPU0_SB_CB<2>   
          	               	242       	88B1      	GND                 
          	               	243       	88B4      	M_D_CPU0_SB_CB<3>   
          	               	244       	88B1      	GND                 
          	               	245       	88B4      	M_D_CPU0_SB_DQ<2>   
          	               	246       	88B1      	GND                 
          	               	247       	88B4      	M_D_CPU0_SB_DQ<3>   
          	               	248       	88B1      	GND                 
          	               	249       	88B2      	M_D_CPU0_SB_DQS_DN<5>
          	               	250       	88B2      	M_D_CPU0_SB_DQS_DP<5>
          	               	251       	88B1      	GND                 
          	               	252       	88B4      	M_D_CPU0_SB_DQ<6>   
          	               	253       	88B1      	GND                 
          	               	254       	88B4      	M_D_CPU0_SB_DQ<7>   
          	               	255       	88B1      	GND                 
          	               	256       	88B4      	M_D_CPU0_SB_DQ<10>  
          	               	257       	88B1      	GND                 
          	               	258       	88B4      	M_D_CPU0_SB_DQ<11>  
          	               	259       	88B1      	GND                 
          	               	260       	88B2      	M_D_CPU0_SB_DQS_DN<6>
          	               	261       	88B2      	M_D_CPU0_SB_DQS_DP<6>
          	               	262       	88B1      	GND                 
          	               	263       	88B4      	M_D_CPU0_SB_DQ<14>  
          	               	264       	88B1      	GND                 
          	               	265       	88B4      	M_D_CPU0_SB_DQ<15>  
          	               	266       	88B1      	GND                 
          	               	267       	88B4      	M_D_CPU0_SB_DQ<18>  
          	               	268       	88B1      	GND                 
          	               	269       	88B4      	M_D_CPU0_SB_DQ<19>  
          	               	270       	88B1      	GND                 
          	               	271       	88B2      	M_D_CPU0_SB_DQS_DN<7>
          	               	272       	88B2      	M_D_CPU0_SB_DQS_DP<7>
          	               	273       	88B1      	GND                 
          	               	274       	88B4      	M_D_CPU0_SB_DQ<22>  
          	               	275       	88B1      	GND                 
          	               	276       	88B4      	M_D_CPU0_SB_DQ<23>  
          	               	277       	88B1      	GND                 
          	               	278       	88B4      	M_D_CPU0_SB_DQ<26>  
          	               	279       	88B1      	GND                 
          	               	280       	88B4      	M_D_CPU0_SB_DQ<27>  
          	               	281       	88B1      	GND                 
          	               	282       	88B2      	M_D_CPU0_SB_DQS_DN<8>
          	               	283       	88B2      	M_D_CPU0_SB_DQS_DP<8>
          	               	284       	88B1      	GND                 
          	               	285       	88B4      	M_D_CPU0_SB_DQ<30>  
          	               	286       	88B1      	GND                 
          	               	287       	88B4      	M_D_CPU0_SB_DQ<31>  
          	               	288       	88B1      	GND                 
          	               	G1        	88B1      	GND                 
          	               	G2        	88A1      	GND                 
          	               	G3        	88A1      	GND                 

J8        	SCONN288_ADR50017P087CC	          	          	                    
          	               	1         	89B1      	P12V_S3_AUX_CPU0_NVDIMM
          	               	2         	89B4      	TP_CHD_CPU0_DIMM2_FRU_0
          	               	3         	89B4      	P3V3_AUX            
          	               	4         	89B4      	I3C_SPD_DDRABCD_CPU0_LVC1_SCL_7
          	               	5         	89B4      	I3C_SPD_DDRABCD_CPU0_LVC1_SDA
          	               	6         	89B1      	GND                 
          	               	7         	89B4      	M_D_CPU0_SA_DQ<0>   
          	               	8         	89B1      	GND                 
          	               	9         	89B4      	M_D_CPU0_SA_DQ<1>   
          	               	10        	89B1      	GND                 
          	               	11        	89B2      	M_D_CPU0_SA_DQS_DP<0>
          	               	12        	89B2      	M_D_CPU0_SA_DQS_DN<0>
          	               	13        	89B1      	GND                 
          	               	14        	89B4      	M_D_CPU0_SA_DQ<4>   
          	               	15        	89B1      	GND                 
          	               	16        	89B4      	M_D_CPU0_SA_DQ<5>   
          	               	17        	89B1      	GND                 
          	               	18        	89B4      	M_D_CPU0_SA_DQ<8>   
          	               	19        	89B1      	GND                 
          	               	20        	89B4      	M_D_CPU0_SA_DQ<9>   
          	               	21        	89B1      	GND                 
          	               	22        	89B2      	M_D_CPU0_SA_DQS_DP<1>
          	               	23        	89B2      	M_D_CPU0_SA_DQS_DN<1>
          	               	24        	89B1      	GND                 
          	               	25        	89B4      	M_D_CPU0_SA_DQ<12>  
          	               	26        	89B1      	GND                 
          	               	27        	89B4      	M_D_CPU0_SA_DQ<13>  
          	               	28        	89B1      	GND                 
          	               	29        	89B4      	M_D_CPU0_SA_DQ<16>  
          	               	30        	89B1      	GND                 
          	               	31        	89B4      	M_D_CPU0_SA_DQ<17>  
          	               	32        	89B1      	GND                 
          	               	33        	89B2      	M_D_CPU0_SA_DQS_DP<2>
          	               	34        	89B2      	M_D_CPU0_SA_DQS_DN<2>
          	               	35        	89B1      	GND                 
          	               	36        	89B4      	M_D_CPU0_SA_DQ<20>  
          	               	37        	89B1      	GND                 
          	               	38        	89B4      	M_D_CPU0_SA_DQ<21>  
          	               	39        	89B1      	GND                 
          	               	40        	89B4      	M_D_CPU0_SA_DQ<24>  
          	               	41        	89B1      	GND                 
          	               	42        	89B4      	M_D_CPU0_SA_DQ<25>  
          	               	43        	89B1      	GND                 
          	               	44        	89B2      	M_D_CPU0_SA_DQS_DP<3>
          	               	45        	89B2      	M_D_CPU0_SA_DQS_DN<3>
          	               	46        	89B1      	GND                 
          	               	47        	89B4      	M_D_CPU0_SA_DQ<28>  
          	               	48        	89B1      	GND                 
          	               	49        	89B4      	M_D_CPU0_SA_DQ<29>  
          	               	50        	89B1      	GND                 
          	               	51        	89B4      	M_D_CPU0_SA_CB<0>   
          	               	52        	89B1      	GND                 
          	               	53        	89B4      	M_D_CPU0_SA_CB<1>   
          	               	54        	89B1      	GND                 
          	               	55        	89B2      	M_D_CPU0_SA_DQS_DP<4>
          	               	56        	89B2      	M_D_CPU0_SA_DQS_DN<4>
          	               	57        	89B1      	GND                 
          	               	58        	89B4      	M_D_CPU0_SA_CB<4>   
          	               	59        	89B1      	GND                 
          	               	60        	89B4      	M_D_CPU0_SA_CB<5>   
          	               	61        	89B1      	GND                 
          	               	62        	89B4      	M_D_CPU0_ALERT_N    
          	               	63        	89B1      	GND                 
          	               	64        	89B4      	M_D_CPU0_SA_CS_N<2> 
          	               	65        	89B1      	GND                 
          	               	66        	89B4      	M_D_CPU0_SA_CA<0>   
          	               	67        	89B1      	GND                 
          	               	68        	89B4      	M_D_CPU0_SA_CA<2>   
          	               	69        	89B1      	GND                 
          	               	70        	89B4      	M_D_CPU0_SA_CA<4>   
          	               	71        	89B1      	GND                 
          	               	72        	89B4      	M_D_CPU0_SA_CA<6>   
          	               	73        	89B1      	GND                 
          	               	74        	89B4      	M_D_CPU0_SA_PAR     
          	               	75        	89B1      	GND                 
          	               	76        	89B4      	M_D_CPU0_SB_CA<0>   
          	               	77        	89B1      	GND                 
          	               	78        	89B4      	M_D_CPU0_SB_CA<2>   
          	               	79        	89B1      	GND                 
          	               	80        	89B4      	M_D_CPU0_SB_CA<4>   
          	               	81        	89B1      	GND                 
          	               	82        	89B4      	M_D_CPU0_SB_CA<6>   
          	               	83        	89B1      	GND                 
          	               	84        	89B4      	M_D_CPU0_SB_CS_N<2> 
          	               	85        	89B1      	GND                 
          	               	86        	89A4      	M_D_CPU0_SA_RSP<1>  
          	               	87        	89A4      	M_D_CPU0_SB_RSP<1>  
          	               	88        	89B1      	GND                 
          	               	89        	89B4      	M_D_CPU0_SB_CB<4>   
          	               	90        	89B1      	GND                 
          	               	91        	89B4      	M_D_CPU0_SB_CB<5>   
          	               	92        	89B1      	GND                 
          	               	93        	89B2      	M_D_CPU0_SB_DQS_DP<9>
          	               	94        	89B2      	M_D_CPU0_SB_DQS_DN<9>
          	               	95        	89B1      	GND                 
          	               	96        	89B4      	M_D_CPU0_SB_CB<0>   
          	               	97        	89B1      	GND                 
          	               	98        	89B4      	M_D_CPU0_SB_CB<1>   
          	               	99        	89B1      	GND                 
          	               	100       	89B4      	M_D_CPU0_SB_DQ<0>   
          	               	101       	89B1      	GND                 
          	               	102       	89B4      	M_D_CPU0_SB_DQ<1>   
          	               	103       	89B1      	GND                 
          	               	104       	89B2      	M_D_CPU0_SB_DQS_DP<0>
          	               	105       	89B2      	M_D_CPU0_SB_DQS_DN<0>
          	               	106       	89B1      	GND                 
          	               	107       	89B4      	M_D_CPU0_SB_DQ<4>   
          	               	108       	89B1      	GND                 
          	               	109       	89B4      	M_D_CPU0_SB_DQ<5>   
          	               	110       	89B1      	GND                 
          	               	111       	89B4      	M_D_CPU0_SB_DQ<8>   
          	               	112       	89B1      	GND                 
          	               	113       	89B4      	M_D_CPU0_SB_DQ<9>   
          	               	114       	89B1      	GND                 
          	               	115       	89B2      	M_D_CPU0_SB_DQS_DP<1>
          	               	116       	89B2      	M_D_CPU0_SB_DQS_DN<1>
          	               	117       	89B1      	GND                 
          	               	118       	89B4      	M_D_CPU0_SB_DQ<12>  
          	               	119       	89B1      	GND                 
          	               	120       	89B4      	M_D_CPU0_SB_DQ<13>  
          	               	121       	89B1      	GND                 
          	               	122       	89B4      	M_D_CPU0_SB_DQ<16>  
          	               	123       	89B1      	GND                 
          	               	124       	89B4      	M_D_CPU0_SB_DQ<17>  
          	               	125       	89B1      	GND                 
          	               	126       	89B2      	M_D_CPU0_SB_DQS_DP<2>
          	               	127       	89B2      	M_D_CPU0_SB_DQS_DN<2>
          	               	128       	89B1      	GND                 
          	               	129       	89B4      	M_D_CPU0_SB_DQ<20>  
          	               	130       	89B1      	GND                 
          	               	131       	89B4      	M_D_CPU0_SB_DQ<21>  
          	               	132       	89B1      	GND                 
          	               	133       	89B4      	M_D_CPU0_SB_DQ<24>  
          	               	134       	89B1      	GND                 
          	               	135       	89B4      	M_D_CPU0_SB_DQ<25>  
          	               	136       	89B1      	GND                 
          	               	137       	89B2      	M_D_CPU0_SB_DQS_DP<3>
          	               	138       	89B2      	M_D_CPU0_SB_DQS_DN<3>
          	               	139       	89B1      	GND                 
          	               	140       	89B4      	M_D_CPU0_SB_DQ<28>  
          	               	141       	89B1      	GND                 
          	               	142       	89B4      	M_D_CPU0_SB_DQ<29>  
          	               	143       	89B1      	GND                 
          	               	144       	89B4      	TP_CHD_CPU0_DIMM2_FRU_1
          	               	145       	89B1      	P12V_S3_AUX_CPU0_NVDIMM
          	               	146       	89B1      	P12V_S3_AUX_CPU0_NVDIMM
          	               	147       	89B4      	PWRGD_CHD_CPU0_DIMM2
          	               	148       	89B4      	PD_CHD_CPU0_DIMM2_SAA
          	               	149       	89B4      	TP_CHD_CPU0_DIMM2_FRU_2
          	               	150       	89B4      	TP_CHD_CPU0_DIMM2_FRU_3
          	               	151       	89B1      	GND                 
          	               	152       	89B4      	M_D_CPU0_SA_DQ<2>   
          	               	153       	89B1      	GND                 
          	               	154       	89B4      	M_D_CPU0_SA_DQ<3>   
          	               	155       	89B1      	GND                 
          	               	156       	89B2      	M_D_CPU0_SA_DQS_DN<5>
          	               	157       	89B2      	M_D_CPU0_SA_DQS_DP<5>
          	               	158       	89B1      	GND                 
          	               	159       	89B4      	M_D_CPU0_SA_DQ<6>   
          	               	160       	89B1      	GND                 
          	               	161       	89B4      	M_D_CPU0_SA_DQ<7>   
          	               	162       	89B1      	GND                 
          	               	163       	89B4      	M_D_CPU0_SA_DQ<10>  
          	               	164       	89B1      	GND                 
          	               	165       	89B4      	M_D_CPU0_SA_DQ<11>  
          	               	166       	89B1      	GND                 
          	               	167       	89B2      	M_D_CPU0_SA_DQS_DN<6>
          	               	168       	89B2      	M_D_CPU0_SA_DQS_DP<6>
          	               	169       	89B1      	GND                 
          	               	170       	89B4      	M_D_CPU0_SA_DQ<14>  
          	               	171       	89B1      	GND                 
          	               	172       	89B4      	M_D_CPU0_SA_DQ<15>  
          	               	173       	89B1      	GND                 
          	               	174       	89B4      	M_D_CPU0_SA_DQ<18>  
          	               	175       	89B1      	GND                 
          	               	176       	89B4      	M_D_CPU0_SA_DQ<19>  
          	               	177       	89B1      	GND                 
          	               	178       	89B2      	M_D_CPU0_SA_DQS_DN<7>
          	               	179       	89B2      	M_D_CPU0_SA_DQS_DP<7>
          	               	180       	89B1      	GND                 
          	               	181       	89B4      	M_D_CPU0_SA_DQ<22>  
          	               	182       	89B1      	GND                 
          	               	183       	89B4      	M_D_CPU0_SA_DQ<23>  
          	               	184       	89B1      	GND                 
          	               	185       	89B4      	M_D_CPU0_SA_DQ<26>  
          	               	186       	89B1      	GND                 
          	               	187       	89B4      	M_D_CPU0_SA_DQ<27>  
          	               	188       	89B1      	GND                 
          	               	189       	89B2      	M_D_CPU0_SA_DQS_DN<8>
          	               	190       	89B2      	M_D_CPU0_SA_DQS_DP<8>
          	               	191       	89B1      	GND                 
          	               	192       	89B4      	M_D_CPU0_SA_DQ<30>  
          	               	193       	89B1      	GND                 
          	               	194       	89B4      	M_D_CPU0_SA_DQ<31>  
          	               	195       	89B1      	GND                 
          	               	196       	89B4      	M_D_CPU0_SA_CB<2>   
          	               	197       	89B1      	GND                 
          	               	198       	89B4      	M_D_CPU0_SA_CB<3>   
          	               	199       	89B1      	GND                 
          	               	200       	89B2      	M_D_CPU0_SA_DQS_DN<9>
          	               	201       	89B2      	M_D_CPU0_SA_DQS_DP<9>
          	               	202       	89B1      	GND                 
          	               	203       	89B4      	M_D_CPU0_SA_CB<6>   
          	               	204       	89B1      	GND                 
          	               	205       	89B4      	M_D_CPU0_SA_CB<7>   
          	               	206       	89B1      	GND                 
          	               	207       	89B4      	RST_M_CD_CPU0_FPGA_N
          	               	208       	89B1      	GND                 
          	               	209       	89B4      	M_D_CPU0_SA_CS_N<3> 
          	               	210       	89B1      	GND                 
          	               	211       	89B4      	M_D_CPU0_SA_CA<1>   
          	               	212       	89B1      	GND                 
          	               	213       	89B4      	M_D_CPU0_SA_CA<3>   
          	               	214       	89B1      	GND                 
          	               	215       	89B4      	M_D_CPU0_SA_CA<5>   
          	               	216       	89B1      	GND                 
          	               	217       	89B4      	M_D_CPU0_CLK_DP<1>  
          	               	218       	89B4      	M_D_CPU0_CLK_DN<1>  
          	               	219       	89B1      	GND                 
          	               	220       	89B4      	TP_CHD_CPU0_DIMM2_FRU_4
          	               	221       	89B4      	M_D_CPU0_SB_CA<1>   
          	               	222       	89B1      	GND                 
          	               	223       	89B4      	M_D_CPU0_SB_CA<3>   
          	               	224       	89B1      	GND                 
          	               	225       	89B4      	M_D_CPU0_SB_CA<5>   
          	               	226       	89B1      	GND                 
          	               	227       	89B4      	M_D_CPU0_SB_PAR     
          	               	228       	89B1      	GND                 
          	               	229       	89B4      	M_D_CPU0_SB_CS_N<3> 
          	               	230       	89B1      	GND                 
          	               	231       	89B4      	TP_CHD_CPU0_DIMM2_FRU_5
          	               	232       	89B4      	TP_CHD_CPU0_DIMM2_FRU_6
          	               	233       	89B1      	GND                 
          	               	234       	89B4      	M_D_CPU0_SB_CB<6>   
          	               	235       	89B1      	GND                 
          	               	236       	89B4      	M_D_CPU0_SB_CB<7>   
          	               	237       	89B1      	GND                 
          	               	238       	89B2      	M_D_CPU0_SB_DQS_DN<4>
          	               	239       	89B2      	M_D_CPU0_SB_DQS_DP<4>
          	               	240       	89B1      	GND                 
          	               	241       	89B4      	M_D_CPU0_SB_CB<2>   
          	               	242       	89B1      	GND                 
          	               	243       	89B4      	M_D_CPU0_SB_CB<3>   
          	               	244       	89B1      	GND                 
          	               	245       	89B4      	M_D_CPU0_SB_DQ<2>   
          	               	246       	89B1      	GND                 
          	               	247       	89B4      	M_D_CPU0_SB_DQ<3>   
          	               	248       	89B1      	GND                 
          	               	249       	89B2      	M_D_CPU0_SB_DQS_DN<5>
          	               	250       	89B2      	M_D_CPU0_SB_DQS_DP<5>
          	               	251       	89B1      	GND                 
          	               	252       	89B4      	M_D_CPU0_SB_DQ<6>   
          	               	253       	89B1      	GND                 
          	               	254       	89B4      	M_D_CPU0_SB_DQ<7>   
          	               	255       	89B1      	GND                 
          	               	256       	89B4      	M_D_CPU0_SB_DQ<10>  
          	               	257       	89B1      	GND                 
          	               	258       	89B4      	M_D_CPU0_SB_DQ<11>  
          	               	259       	89B1      	GND                 
          	               	260       	89B2      	M_D_CPU0_SB_DQS_DN<6>
          	               	261       	89B2      	M_D_CPU0_SB_DQS_DP<6>
          	               	262       	89B1      	GND                 
          	               	263       	89B4      	M_D_CPU0_SB_DQ<14>  
          	               	264       	89B1      	GND                 
          	               	265       	89B4      	M_D_CPU0_SB_DQ<15>  
          	               	266       	89B1      	GND                 
          	               	267       	89B4      	M_D_CPU0_SB_DQ<18>  
          	               	268       	89B1      	GND                 
          	               	269       	89B4      	M_D_CPU0_SB_DQ<19>  
          	               	270       	89B1      	GND                 
          	               	271       	89B2      	M_D_CPU0_SB_DQS_DN<7>
          	               	272       	89B2      	M_D_CPU0_SB_DQS_DP<7>
          	               	273       	89B1      	GND                 
          	               	274       	89B4      	M_D_CPU0_SB_DQ<22>  
          	               	275       	89B1      	GND                 
          	               	276       	89B4      	M_D_CPU0_SB_DQ<23>  
          	               	277       	89B1      	GND                 
          	               	278       	89B4      	M_D_CPU0_SB_DQ<26>  
          	               	279       	89B1      	GND                 
          	               	280       	89B4      	M_D_CPU0_SB_DQ<27>  
          	               	281       	89B1      	GND                 
          	               	282       	89B2      	M_D_CPU0_SB_DQS_DN<8>
          	               	283       	89B2      	M_D_CPU0_SB_DQS_DP<8>
          	               	284       	89B1      	GND                 
          	               	285       	89B4      	M_D_CPU0_SB_DQ<30>  
          	               	286       	89B1      	GND                 
          	               	287       	89B4      	M_D_CPU0_SB_DQ<31>  
          	               	288       	89B1      	GND                 
          	               	G1        	89B1      	GND                 
          	               	G2        	89A1      	GND                 
          	               	G3        	89A1      	GND                 

J9        	SCONN288_ADR50017P130CC	          	          	                    
          	               	1         	90B1      	P12V_S3_AUX_CPU0_NVDIMM
          	               	2         	90B4      	TP_CHE_CPU0_DIMM1_FRU_0
          	               	3         	90B4      	P3V3_AUX            
          	               	4         	90B4      	I3C_SPD_DDREFGH_CPU0_LVC1_SCL_R
          	               	5         	90B4      	I3C_SPD_DDREFGH_CPU0_LVC1_SDA
          	               	6         	90B1      	GND                 
          	               	7         	90B4      	M_E_CPU0_SA_DQ<0>   
          	               	8         	90B1      	GND                 
          	               	9         	90B4      	M_E_CPU0_SA_DQ<1>   
          	               	10        	90B1      	GND                 
          	               	11        	90B2      	M_E_CPU0_SA_DQS_DP<0>
          	               	12        	90B2      	M_E_CPU0_SA_DQS_DN<0>
          	               	13        	90B1      	GND                 
          	               	14        	90B4      	M_E_CPU0_SA_DQ<4>   
          	               	15        	90B1      	GND                 
          	               	16        	90B4      	M_E_CPU0_SA_DQ<5>   
          	               	17        	90B1      	GND                 
          	               	18        	90B4      	M_E_CPU0_SA_DQ<8>   
          	               	19        	90B1      	GND                 
          	               	20        	90B4      	M_E_CPU0_SA_DQ<9>   
          	               	21        	90B1      	GND                 
          	               	22        	90B2      	M_E_CPU0_SA_DQS_DP<1>
          	               	23        	90B2      	M_E_CPU0_SA_DQS_DN<1>
          	               	24        	90B1      	GND                 
          	               	25        	90B4      	M_E_CPU0_SA_DQ<12>  
          	               	26        	90B1      	GND                 
          	               	27        	90B4      	M_E_CPU0_SA_DQ<13>  
          	               	28        	90B1      	GND                 
          	               	29        	90B4      	M_E_CPU0_SA_DQ<16>  
          	               	30        	90B1      	GND                 
          	               	31        	90B4      	M_E_CPU0_SA_DQ<17>  
          	               	32        	90B1      	GND                 
          	               	33        	90B2      	M_E_CPU0_SA_DQS_DP<2>
          	               	34        	90B2      	M_E_CPU0_SA_DQS_DN<2>
          	               	35        	90B1      	GND                 
          	               	36        	90B4      	M_E_CPU0_SA_DQ<20>  
          	               	37        	90B1      	GND                 
          	               	38        	90B4      	M_E_CPU0_SA_DQ<21>  
          	               	39        	90B1      	GND                 
          	               	40        	90B4      	M_E_CPU0_SA_DQ<24>  
          	               	41        	90B1      	GND                 
          	               	42        	90B4      	M_E_CPU0_SA_DQ<25>  
          	               	43        	90B1      	GND                 
          	               	44        	90B2      	M_E_CPU0_SA_DQS_DP<3>
          	               	45        	90B2      	M_E_CPU0_SA_DQS_DN<3>
          	               	46        	90B1      	GND                 
          	               	47        	90B4      	M_E_CPU0_SA_DQ<28>  
          	               	48        	90B1      	GND                 
          	               	49        	90B4      	M_E_CPU0_SA_DQ<29>  
          	               	50        	90B1      	GND                 
          	               	51        	90B4      	M_E_CPU0_SA_CB<0>   
          	               	52        	90B1      	GND                 
          	               	53        	90B4      	M_E_CPU0_SA_CB<1>   
          	               	54        	90B1      	GND                 
          	               	55        	90B2      	M_E_CPU0_SA_DQS_DP<4>
          	               	56        	90B2      	M_E_CPU0_SA_DQS_DN<4>
          	               	57        	90B1      	GND                 
          	               	58        	90B4      	M_E_CPU0_SA_CB<4>   
          	               	59        	90B1      	GND                 
          	               	60        	90B4      	M_E_CPU0_SA_CB<5>   
          	               	61        	90B1      	GND                 
          	               	62        	90B4      	M_E_CPU0_ALERT_N    
          	               	63        	90B1      	GND                 
          	               	64        	90B4      	M_E_CPU0_SA_CS_N<0> 
          	               	65        	90B1      	GND                 
          	               	66        	90B4      	M_E_CPU0_SA_CA<0>   
          	               	67        	90B1      	GND                 
          	               	68        	90B4      	M_E_CPU0_SA_CA<2>   
          	               	69        	90B1      	GND                 
          	               	70        	90B4      	M_E_CPU0_SA_CA<4>   
          	               	71        	90B1      	GND                 
          	               	72        	90B4      	M_E_CPU0_SA_CA<6>   
          	               	73        	90B1      	GND                 
          	               	74        	90B4      	M_E_CPU0_SA_PAR     
          	               	75        	90B1      	GND                 
          	               	76        	90B4      	M_E_CPU0_SB_CA<0>   
          	               	77        	90B1      	GND                 
          	               	78        	90B4      	M_E_CPU0_SB_CA<2>   
          	               	79        	90B1      	GND                 
          	               	80        	90B4      	M_E_CPU0_SB_CA<4>   
          	               	81        	90B1      	GND                 
          	               	82        	90B4      	M_E_CPU0_SB_CA<6>   
          	               	83        	90B1      	GND                 
          	               	84        	90B4      	M_E_CPU0_SB_CS_N<0> 
          	               	85        	90B1      	GND                 
          	               	86        	90A4      	M_E_CPU0_SA_RSP<0>  
          	               	87        	90A4      	M_E_CPU0_SB_RSP<0>  
          	               	88        	90B1      	GND                 
          	               	89        	90B4      	M_E_CPU0_SB_CB<4>   
          	               	90        	90B1      	GND                 
          	               	91        	90B4      	M_E_CPU0_SB_CB<5>   
          	               	92        	90B1      	GND                 
          	               	93        	90B2      	M_E_CPU0_SB_DQS_DP<9>
          	               	94        	90B2      	M_E_CPU0_SB_DQS_DN<9>
          	               	95        	90B1      	GND                 
          	               	96        	90B4      	M_E_CPU0_SB_CB<0>   
          	               	97        	90B1      	GND                 
          	               	98        	90B4      	M_E_CPU0_SB_CB<1>   
          	               	99        	90B1      	GND                 
          	               	100       	90B4      	M_E_CPU0_SB_DQ<0>   
          	               	101       	90B1      	GND                 
          	               	102       	90B4      	M_E_CPU0_SB_DQ<1>   
          	               	103       	90B1      	GND                 
          	               	104       	90B2      	M_E_CPU0_SB_DQS_DP<0>
          	               	105       	90B2      	M_E_CPU0_SB_DQS_DN<0>
          	               	106       	90B1      	GND                 
          	               	107       	90B4      	M_E_CPU0_SB_DQ<4>   
          	               	108       	90B1      	GND                 
          	               	109       	90B4      	M_E_CPU0_SB_DQ<5>   
          	               	110       	90B1      	GND                 
          	               	111       	90B4      	M_E_CPU0_SB_DQ<8>   
          	               	112       	90B1      	GND                 
          	               	113       	90B4      	M_E_CPU0_SB_DQ<9>   
          	               	114       	90B1      	GND                 
          	               	115       	90B2      	M_E_CPU0_SB_DQS_DP<1>
          	               	116       	90B2      	M_E_CPU0_SB_DQS_DN<1>
          	               	117       	90B1      	GND                 
          	               	118       	90B4      	M_E_CPU0_SB_DQ<12>  
          	               	119       	90B1      	GND                 
          	               	120       	90B4      	M_E_CPU0_SB_DQ<13>  
          	               	121       	90B1      	GND                 
          	               	122       	90B4      	M_E_CPU0_SB_DQ<16>  
          	               	123       	90B1      	GND                 
          	               	124       	90B4      	M_E_CPU0_SB_DQ<17>  
          	               	125       	90B1      	GND                 
          	               	126       	90B2      	M_E_CPU0_SB_DQS_DP<2>
          	               	127       	90B2      	M_E_CPU0_SB_DQS_DN<2>
          	               	128       	90B1      	GND                 
          	               	129       	90B4      	M_E_CPU0_SB_DQ<20>  
          	               	130       	90B1      	GND                 
          	               	131       	90B4      	M_E_CPU0_SB_DQ<21>  
          	               	132       	90B1      	GND                 
          	               	133       	90B4      	M_E_CPU0_SB_DQ<24>  
          	               	134       	90B1      	GND                 
          	               	135       	90B4      	M_E_CPU0_SB_DQ<25>  
          	               	136       	90B1      	GND                 
          	               	137       	90B2      	M_E_CPU0_SB_DQS_DP<3>
          	               	138       	90B2      	M_E_CPU0_SB_DQS_DN<3>
          	               	139       	90B1      	GND                 
          	               	140       	90B4      	M_E_CPU0_SB_DQ<28>  
          	               	141       	90B1      	GND                 
          	               	142       	90B4      	M_E_CPU0_SB_DQ<29>  
          	               	143       	90B1      	GND                 
          	               	144       	90B4      	TP_CHE_CPU0_DIMM1_FRU_1
          	               	145       	90B1      	P12V_S3_AUX_CPU0_NVDIMM
          	               	146       	90B1      	P12V_S3_AUX_CPU0_NVDIMM
          	               	147       	90B4      	PWRGD_CHE_CPU0_DIMM1
          	               	148       	90B4      	PD_CHE_CPU0_DIMM1_SAA
          	               	149       	90B4      	TP_CHE_CPU0_DIMM1_FRU_2
          	               	150       	90B4      	TP_CHE_CPU0_DIMM1_FRU_3
          	               	151       	90B1      	GND                 
          	               	152       	90B4      	M_E_CPU0_SA_DQ<2>   
          	               	153       	90B1      	GND                 
          	               	154       	90B4      	M_E_CPU0_SA_DQ<3>   
          	               	155       	90B1      	GND                 
          	               	156       	90B2      	M_E_CPU0_SA_DQS_DN<5>
          	               	157       	90B2      	M_E_CPU0_SA_DQS_DP<5>
          	               	158       	90B1      	GND                 
          	               	159       	90B4      	M_E_CPU0_SA_DQ<6>   
          	               	160       	90B1      	GND                 
          	               	161       	90B4      	M_E_CPU0_SA_DQ<7>   
          	               	162       	90B1      	GND                 
          	               	163       	90B4      	M_E_CPU0_SA_DQ<10>  
          	               	164       	90B1      	GND                 
          	               	165       	90B4      	M_E_CPU0_SA_DQ<11>  
          	               	166       	90B1      	GND                 
          	               	167       	90B2      	M_E_CPU0_SA_DQS_DN<6>
          	               	168       	90B2      	M_E_CPU0_SA_DQS_DP<6>
          	               	169       	90B1      	GND                 
          	               	170       	90B4      	M_E_CPU0_SA_DQ<14>  
          	               	171       	90B1      	GND                 
          	               	172       	90B4      	M_E_CPU0_SA_DQ<15>  
          	               	173       	90B1      	GND                 
          	               	174       	90B4      	M_E_CPU0_SA_DQ<18>  
          	               	175       	90B1      	GND                 
          	               	176       	90B4      	M_E_CPU0_SA_DQ<19>  
          	               	177       	90B1      	GND                 
          	               	178       	90B2      	M_E_CPU0_SA_DQS_DN<7>
          	               	179       	90B2      	M_E_CPU0_SA_DQS_DP<7>
          	               	180       	90B1      	GND                 
          	               	181       	90B4      	M_E_CPU0_SA_DQ<22>  
          	               	182       	90B1      	GND                 
          	               	183       	90B4      	M_E_CPU0_SA_DQ<23>  
          	               	184       	90B1      	GND                 
          	               	185       	90B4      	M_E_CPU0_SA_DQ<26>  
          	               	186       	90B1      	GND                 
          	               	187       	90B4      	M_E_CPU0_SA_DQ<27>  
          	               	188       	90B1      	GND                 
          	               	189       	90B2      	M_E_CPU0_SA_DQS_DN<8>
          	               	190       	90B2      	M_E_CPU0_SA_DQS_DP<8>
          	               	191       	90B1      	GND                 
          	               	192       	90B4      	M_E_CPU0_SA_DQ<30>  
          	               	193       	90B1      	GND                 
          	               	194       	90B4      	M_E_CPU0_SA_DQ<31>  
          	               	195       	90B1      	GND                 
          	               	196       	90B4      	M_E_CPU0_SA_CB<2>   
          	               	197       	90B1      	GND                 
          	               	198       	90B4      	M_E_CPU0_SA_CB<3>   
          	               	199       	90B1      	GND                 
          	               	200       	90B2      	M_E_CPU0_SA_DQS_DN<9>
          	               	201       	90B2      	M_E_CPU0_SA_DQS_DP<9>
          	               	202       	90B1      	GND                 
          	               	203       	90B4      	M_E_CPU0_SA_CB<6>   
          	               	204       	90B1      	GND                 
          	               	205       	90B4      	M_E_CPU0_SA_CB<7>   
          	               	206       	90B1      	GND                 
          	               	207       	90B4      	RST_M_EF_CPU0_FPGA_N
          	               	208       	90B1      	GND                 
          	               	209       	90B4      	M_E_CPU0_SA_CS_N<1> 
          	               	210       	90B1      	GND                 
          	               	211       	90B4      	M_E_CPU0_SA_CA<1>   
          	               	212       	90B1      	GND                 
          	               	213       	90B4      	M_E_CPU0_SA_CA<3>   
          	               	214       	90B1      	GND                 
          	               	215       	90B4      	M_E_CPU0_SA_CA<5>   
          	               	216       	90B1      	GND                 
          	               	217       	90B4      	M_E_CPU0_CLK_DP<0>  
          	               	218       	90B4      	M_E_CPU0_CLK_DN<0>  
          	               	219       	90B1      	GND                 
          	               	220       	90B4      	TP_CHE_CPU0_DIMM1_FRU_4
          	               	221       	90B4      	M_E_CPU0_SB_CA<1>   
          	               	222       	90B1      	GND                 
          	               	223       	90B4      	M_E_CPU0_SB_CA<3>   
          	               	224       	90B1      	GND                 
          	               	225       	90B4      	M_E_CPU0_SB_CA<5>   
          	               	226       	90B1      	GND                 
          	               	227       	90B4      	M_E_CPU0_SB_PAR     
          	               	228       	90B1      	GND                 
          	               	229       	90B4      	M_E_CPU0_SB_CS_N<1> 
          	               	230       	90B1      	GND                 
          	               	231       	90B4      	TP_CHE_CPU0_DIMM1_FRU_5
          	               	232       	90B4      	TP_CHE_CPU0_DIMM1_FRU_6
          	               	233       	90B1      	GND                 
          	               	234       	90B4      	M_E_CPU0_SB_CB<6>   
          	               	235       	90B1      	GND                 
          	               	236       	90B4      	M_E_CPU0_SB_CB<7>   
          	               	237       	90B1      	GND                 
          	               	238       	90B2      	M_E_CPU0_SB_DQS_DN<4>
          	               	239       	90B2      	M_E_CPU0_SB_DQS_DP<4>
          	               	240       	90B1      	GND                 
          	               	241       	90B4      	M_E_CPU0_SB_CB<2>   
          	               	242       	90B1      	GND                 
          	               	243       	90B4      	M_E_CPU0_SB_CB<3>   
          	               	244       	90B1      	GND                 
          	               	245       	90B4      	M_E_CPU0_SB_DQ<2>   
          	               	246       	90B1      	GND                 
          	               	247       	90B4      	M_E_CPU0_SB_DQ<3>   
          	               	248       	90B1      	GND                 
          	               	249       	90B2      	M_E_CPU0_SB_DQS_DN<5>
          	               	250       	90B2      	M_E_CPU0_SB_DQS_DP<5>
          	               	251       	90B1      	GND                 
          	               	252       	90B4      	M_E_CPU0_SB_DQ<6>   
          	               	253       	90B1      	GND                 
          	               	254       	90B4      	M_E_CPU0_SB_DQ<7>   
          	               	255       	90B1      	GND                 
          	               	256       	90B4      	M_E_CPU0_SB_DQ<10>  
          	               	257       	90B1      	GND                 
          	               	258       	90B4      	M_E_CPU0_SB_DQ<11>  
          	               	259       	90B1      	GND                 
          	               	260       	90B2      	M_E_CPU0_SB_DQS_DN<6>
          	               	261       	90B2      	M_E_CPU0_SB_DQS_DP<6>
          	               	262       	90B1      	GND                 
          	               	263       	90B4      	M_E_CPU0_SB_DQ<14>  
          	               	264       	90B1      	GND                 
          	               	265       	90B4      	M_E_CPU0_SB_DQ<15>  
          	               	266       	90B1      	GND                 
          	               	267       	90B4      	M_E_CPU0_SB_DQ<18>  
          	               	268       	90B1      	GND                 
          	               	269       	90B4      	M_E_CPU0_SB_DQ<19>  
          	               	270       	90B1      	GND                 
          	               	271       	90B2      	M_E_CPU0_SB_DQS_DN<7>
          	               	272       	90B2      	M_E_CPU0_SB_DQS_DP<7>
          	               	273       	90B1      	GND                 
          	               	274       	90B4      	M_E_CPU0_SB_DQ<22>  
          	               	275       	90B1      	GND                 
          	               	276       	90B4      	M_E_CPU0_SB_DQ<23>  
          	               	277       	90B1      	GND                 
          	               	278       	90B4      	M_E_CPU0_SB_DQ<26>  
          	               	279       	90B1      	GND                 
          	               	280       	90B4      	M_E_CPU0_SB_DQ<27>  
          	               	281       	90B1      	GND                 
          	               	282       	90B2      	M_E_CPU0_SB_DQS_DN<8>
          	               	283       	90B2      	M_E_CPU0_SB_DQS_DP<8>
          	               	284       	90B1      	GND                 
          	               	285       	90B4      	M_E_CPU0_SB_DQ<30>  
          	               	286       	90B1      	GND                 
          	               	287       	90B4      	M_E_CPU0_SB_DQ<31>  
          	               	288       	90B1      	GND                 
          	               	G1        	90B1      	GND                 
          	               	G2        	90A1      	GND                 
          	               	G3        	90A1      	GND                 

J10       	SCONN288_ADR50017P087CC	          	          	                    
          	               	1         	91B1      	P12V_S3_AUX_CPU0_NVDIMM
          	               	2         	91B4      	TP_CHE_CPU0_DIMM2_FRU_0
          	               	3         	91B4      	P3V3_AUX            
          	               	4         	91B4      	I3C_SPD_DDREFGH_CPU0_LVC1_SCL_1
          	               	5         	91B4      	I3C_SPD_DDREFGH_CPU0_LVC1_SDA
          	               	6         	91B1      	GND                 
          	               	7         	91B4      	M_E_CPU0_SA_DQ<0>   
          	               	8         	91B1      	GND                 
          	               	9         	91B4      	M_E_CPU0_SA_DQ<1>   
          	               	10        	91B1      	GND                 
          	               	11        	91B2      	M_E_CPU0_SA_DQS_DP<0>
          	               	12        	91B2      	M_E_CPU0_SA_DQS_DN<0>
          	               	13        	91B1      	GND                 
          	               	14        	91B4      	M_E_CPU0_SA_DQ<4>   
          	               	15        	91B1      	GND                 
          	               	16        	91B4      	M_E_CPU0_SA_DQ<5>   
          	               	17        	91B1      	GND                 
          	               	18        	91B4      	M_E_CPU0_SA_DQ<8>   
          	               	19        	91B1      	GND                 
          	               	20        	91B4      	M_E_CPU0_SA_DQ<9>   
          	               	21        	91B1      	GND                 
          	               	22        	91B2      	M_E_CPU0_SA_DQS_DP<1>
          	               	23        	91B2      	M_E_CPU0_SA_DQS_DN<1>
          	               	24        	91B1      	GND                 
          	               	25        	91B4      	M_E_CPU0_SA_DQ<12>  
          	               	26        	91B1      	GND                 
          	               	27        	91B4      	M_E_CPU0_SA_DQ<13>  
          	               	28        	91B1      	GND                 
          	               	29        	91B4      	M_E_CPU0_SA_DQ<16>  
          	               	30        	91B1      	GND                 
          	               	31        	91B4      	M_E_CPU0_SA_DQ<17>  
          	               	32        	91B1      	GND                 
          	               	33        	91B2      	M_E_CPU0_SA_DQS_DP<2>
          	               	34        	91B2      	M_E_CPU0_SA_DQS_DN<2>
          	               	35        	91B1      	GND                 
          	               	36        	91B4      	M_E_CPU0_SA_DQ<20>  
          	               	37        	91B1      	GND                 
          	               	38        	91B4      	M_E_CPU0_SA_DQ<21>  
          	               	39        	91B1      	GND                 
          	               	40        	91B4      	M_E_CPU0_SA_DQ<24>  
          	               	41        	91B1      	GND                 
          	               	42        	91B4      	M_E_CPU0_SA_DQ<25>  
          	               	43        	91B1      	GND                 
          	               	44        	91B2      	M_E_CPU0_SA_DQS_DP<3>
          	               	45        	91B2      	M_E_CPU0_SA_DQS_DN<3>
          	               	46        	91B1      	GND                 
          	               	47        	91B4      	M_E_CPU0_SA_DQ<28>  
          	               	48        	91B1      	GND                 
          	               	49        	91B4      	M_E_CPU0_SA_DQ<29>  
          	               	50        	91B1      	GND                 
          	               	51        	91B4      	M_E_CPU0_SA_CB<0>   
          	               	52        	91B1      	GND                 
          	               	53        	91B4      	M_E_CPU0_SA_CB<1>   
          	               	54        	91B1      	GND                 
          	               	55        	91B2      	M_E_CPU0_SA_DQS_DP<4>
          	               	56        	91B2      	M_E_CPU0_SA_DQS_DN<4>
          	               	57        	91B1      	GND                 
          	               	58        	91B4      	M_E_CPU0_SA_CB<4>   
          	               	59        	91B1      	GND                 
          	               	60        	91B4      	M_E_CPU0_SA_CB<5>   
          	               	61        	91B1      	GND                 
          	               	62        	91B4      	M_E_CPU0_ALERT_N    
          	               	63        	91B1      	GND                 
          	               	64        	91B4      	M_E_CPU0_SA_CS_N<2> 
          	               	65        	91B1      	GND                 
          	               	66        	91B4      	M_E_CPU0_SA_CA<0>   
          	               	67        	91B1      	GND                 
          	               	68        	91B4      	M_E_CPU0_SA_CA<2>   
          	               	69        	91B1      	GND                 
          	               	70        	91B4      	M_E_CPU0_SA_CA<4>   
          	               	71        	91B1      	GND                 
          	               	72        	91B4      	M_E_CPU0_SA_CA<6>   
          	               	73        	91B1      	GND                 
          	               	74        	91B4      	M_E_CPU0_SA_PAR     
          	               	75        	91B1      	GND                 
          	               	76        	91B4      	M_E_CPU0_SB_CA<0>   
          	               	77        	91B1      	GND                 
          	               	78        	91B4      	M_E_CPU0_SB_CA<2>   
          	               	79        	91B1      	GND                 
          	               	80        	91B4      	M_E_CPU0_SB_CA<4>   
          	               	81        	91B1      	GND                 
          	               	82        	91B4      	M_E_CPU0_SB_CA<6>   
          	               	83        	91B1      	GND                 
          	               	84        	91B4      	M_E_CPU0_SB_CS_N<2> 
          	               	85        	91B1      	GND                 
          	               	86        	91A4      	M_E_CPU0_SA_RSP<1>  
          	               	87        	91A4      	M_E_CPU0_SB_RSP<1>  
          	               	88        	91B1      	GND                 
          	               	89        	91B4      	M_E_CPU0_SB_CB<4>   
          	               	90        	91B1      	GND                 
          	               	91        	91B4      	M_E_CPU0_SB_CB<5>   
          	               	92        	91B1      	GND                 
          	               	93        	91B2      	M_E_CPU0_SB_DQS_DP<9>
          	               	94        	91B2      	M_E_CPU0_SB_DQS_DN<9>
          	               	95        	91B1      	GND                 
          	               	96        	91B4      	M_E_CPU0_SB_CB<0>   
          	               	97        	91B1      	GND                 
          	               	98        	91B4      	M_E_CPU0_SB_CB<1>   
          	               	99        	91B1      	GND                 
          	               	100       	91B4      	M_E_CPU0_SB_DQ<0>   
          	               	101       	91B1      	GND                 
          	               	102       	91B4      	M_E_CPU0_SB_DQ<1>   
          	               	103       	91B1      	GND                 
          	               	104       	91B2      	M_E_CPU0_SB_DQS_DP<0>
          	               	105       	91B2      	M_E_CPU0_SB_DQS_DN<0>
          	               	106       	91B1      	GND                 
          	               	107       	91B4      	M_E_CPU0_SB_DQ<4>   
          	               	108       	91B1      	GND                 
          	               	109       	91B4      	M_E_CPU0_SB_DQ<5>   
          	               	110       	91B1      	GND                 
          	               	111       	91B4      	M_E_CPU0_SB_DQ<8>   
          	               	112       	91B1      	GND                 
          	               	113       	91B4      	M_E_CPU0_SB_DQ<9>   
          	               	114       	91B1      	GND                 
          	               	115       	91B2      	M_E_CPU0_SB_DQS_DP<1>
          	               	116       	91B2      	M_E_CPU0_SB_DQS_DN<1>
          	               	117       	91B1      	GND                 
          	               	118       	91B4      	M_E_CPU0_SB_DQ<12>  
          	               	119       	91B1      	GND                 
          	               	120       	91B4      	M_E_CPU0_SB_DQ<13>  
          	               	121       	91B1      	GND                 
          	               	122       	91B4      	M_E_CPU0_SB_DQ<16>  
          	               	123       	91B1      	GND                 
          	               	124       	91B4      	M_E_CPU0_SB_DQ<17>  
          	               	125       	91B1      	GND                 
          	               	126       	91B2      	M_E_CPU0_SB_DQS_DP<2>
          	               	127       	91B2      	M_E_CPU0_SB_DQS_DN<2>
          	               	128       	91B1      	GND                 
          	               	129       	91B4      	M_E_CPU0_SB_DQ<20>  
          	               	130       	91B1      	GND                 
          	               	131       	91B4      	M_E_CPU0_SB_DQ<21>  
          	               	132       	91B1      	GND                 
          	               	133       	91B4      	M_E_CPU0_SB_DQ<24>  
          	               	134       	91B1      	GND                 
          	               	135       	91B4      	M_E_CPU0_SB_DQ<25>  
          	               	136       	91B1      	GND                 
          	               	137       	91B2      	M_E_CPU0_SB_DQS_DP<3>
          	               	138       	91B2      	M_E_CPU0_SB_DQS_DN<3>
          	               	139       	91B1      	GND                 
          	               	140       	91B4      	M_E_CPU0_SB_DQ<28>  
          	               	141       	91B1      	GND                 
          	               	142       	91B4      	M_E_CPU0_SB_DQ<29>  
          	               	143       	91B1      	GND                 
          	               	144       	91B4      	TP_CHE_CPU0_DIMM2_FRU_1
          	               	145       	91B1      	P12V_S3_AUX_CPU0_NVDIMM
          	               	146       	91B1      	P12V_S3_AUX_CPU0_NVDIMM
          	               	147       	91B4      	PWRGD_CHE_CPU0_DIMM2
          	               	148       	91B4      	PD_CHE_CPU0_DIMM2_SAA
          	               	149       	91B4      	TP_CHE_CPU0_DIMM2_FRU_2
          	               	150       	91B4      	TP_CHE_CPU0_DIMM2_FRU_3
          	               	151       	91B1      	GND                 
          	               	152       	91B4      	M_E_CPU0_SA_DQ<2>   
          	               	153       	91B1      	GND                 
          	               	154       	91B4      	M_E_CPU0_SA_DQ<3>   
          	               	155       	91B1      	GND                 
          	               	156       	91B2      	M_E_CPU0_SA_DQS_DN<5>
          	               	157       	91B2      	M_E_CPU0_SA_DQS_DP<5>
          	               	158       	91B1      	GND                 
          	               	159       	91B4      	M_E_CPU0_SA_DQ<6>   
          	               	160       	91B1      	GND                 
          	               	161       	91B4      	M_E_CPU0_SA_DQ<7>   
          	               	162       	91B1      	GND                 
          	               	163       	91B4      	M_E_CPU0_SA_DQ<10>  
          	               	164       	91B1      	GND                 
          	               	165       	91B4      	M_E_CPU0_SA_DQ<11>  
          	               	166       	91B1      	GND                 
          	               	167       	91B2      	M_E_CPU0_SA_DQS_DN<6>
          	               	168       	91B2      	M_E_CPU0_SA_DQS_DP<6>
          	               	169       	91B1      	GND                 
          	               	170       	91B4      	M_E_CPU0_SA_DQ<14>  
          	               	171       	91B1      	GND                 
          	               	172       	91B4      	M_E_CPU0_SA_DQ<15>  
          	               	173       	91B1      	GND                 
          	               	174       	91B4      	M_E_CPU0_SA_DQ<18>  
          	               	175       	91B1      	GND                 
          	               	176       	91B4      	M_E_CPU0_SA_DQ<19>  
          	               	177       	91B1      	GND                 
          	               	178       	91B2      	M_E_CPU0_SA_DQS_DN<7>
          	               	179       	91B2      	M_E_CPU0_SA_DQS_DP<7>
          	               	180       	91B1      	GND                 
          	               	181       	91B4      	M_E_CPU0_SA_DQ<22>  
          	               	182       	91B1      	GND                 
          	               	183       	91B4      	M_E_CPU0_SA_DQ<23>  
          	               	184       	91B1      	GND                 
          	               	185       	91B4      	M_E_CPU0_SA_DQ<26>  
          	               	186       	91B1      	GND                 
          	               	187       	91B4      	M_E_CPU0_SA_DQ<27>  
          	               	188       	91B1      	GND                 
          	               	189       	91B2      	M_E_CPU0_SA_DQS_DN<8>
          	               	190       	91B2      	M_E_CPU0_SA_DQS_DP<8>
          	               	191       	91B1      	GND                 
          	               	192       	91B4      	M_E_CPU0_SA_DQ<30>  
          	               	193       	91B1      	GND                 
          	               	194       	91B4      	M_E_CPU0_SA_DQ<31>  
          	               	195       	91B1      	GND                 
          	               	196       	91B4      	M_E_CPU0_SA_CB<2>   
          	               	197       	91B1      	GND                 
          	               	198       	91B4      	M_E_CPU0_SA_CB<3>   
          	               	199       	91B1      	GND                 
          	               	200       	91B2      	M_E_CPU0_SA_DQS_DN<9>
          	               	201       	91B2      	M_E_CPU0_SA_DQS_DP<9>
          	               	202       	91B1      	GND                 
          	               	203       	91B4      	M_E_CPU0_SA_CB<6>   
          	               	204       	91B1      	GND                 
          	               	205       	91B4      	M_E_CPU0_SA_CB<7>   
          	               	206       	91B1      	GND                 
          	               	207       	91B4      	RST_M_EF_CPU0_FPGA_N
          	               	208       	91B1      	GND                 
          	               	209       	91B4      	M_E_CPU0_SA_CS_N<3> 
          	               	210       	91B1      	GND                 
          	               	211       	91B4      	M_E_CPU0_SA_CA<1>   
          	               	212       	91B1      	GND                 
          	               	213       	91B4      	M_E_CPU0_SA_CA<3>   
          	               	214       	91B1      	GND                 
          	               	215       	91B4      	M_E_CPU0_SA_CA<5>   
          	               	216       	91B1      	GND                 
          	               	217       	91B4      	M_E_CPU0_CLK_DP<1>  
          	               	218       	91B4      	M_E_CPU0_CLK_DN<1>  
          	               	219       	91B1      	GND                 
          	               	220       	91B4      	TP_CHE_CPU0_DIMM2_FRU_4
          	               	221       	91B4      	M_E_CPU0_SB_CA<1>   
          	               	222       	91B1      	GND                 
          	               	223       	91B4      	M_E_CPU0_SB_CA<3>   
          	               	224       	91B1      	GND                 
          	               	225       	91B4      	M_E_CPU0_SB_CA<5>   
          	               	226       	91B1      	GND                 
          	               	227       	91B4      	M_E_CPU0_SB_PAR     
          	               	228       	91B1      	GND                 
          	               	229       	91B4      	M_E_CPU0_SB_CS_N<3> 
          	               	230       	91B1      	GND                 
          	               	231       	91B4      	TP_CHE_CPU0_DIMM2_FRU_5
          	               	232       	91B4      	TP_CHE_CPU0_DIMM2_FRU_6
          	               	233       	91B1      	GND                 
          	               	234       	91B4      	M_E_CPU0_SB_CB<6>   
          	               	235       	91B1      	GND                 
          	               	236       	91B4      	M_E_CPU0_SB_CB<7>   
          	               	237       	91B1      	GND                 
          	               	238       	91B2      	M_E_CPU0_SB_DQS_DN<4>
          	               	239       	91B2      	M_E_CPU0_SB_DQS_DP<4>
          	               	240       	91B1      	GND                 
          	               	241       	91B4      	M_E_CPU0_SB_CB<2>   
          	               	242       	91B1      	GND                 
          	               	243       	91B4      	M_E_CPU0_SB_CB<3>   
          	               	244       	91B1      	GND                 
          	               	245       	91B4      	M_E_CPU0_SB_DQ<2>   
          	               	246       	91B1      	GND                 
          	               	247       	91B4      	M_E_CPU0_SB_DQ<3>   
          	               	248       	91B1      	GND                 
          	               	249       	91B2      	M_E_CPU0_SB_DQS_DN<5>
          	               	250       	91B2      	M_E_CPU0_SB_DQS_DP<5>
          	               	251       	91B1      	GND                 
          	               	252       	91B4      	M_E_CPU0_SB_DQ<6>   
          	               	253       	91B1      	GND                 
          	               	254       	91B4      	M_E_CPU0_SB_DQ<7>   
          	               	255       	91B1      	GND                 
          	               	256       	91B4      	M_E_CPU0_SB_DQ<10>  
          	               	257       	91B1      	GND                 
          	               	258       	91B4      	M_E_CPU0_SB_DQ<11>  
          	               	259       	91B1      	GND                 
          	               	260       	91B2      	M_E_CPU0_SB_DQS_DN<6>
          	               	261       	91B2      	M_E_CPU0_SB_DQS_DP<6>
          	               	262       	91B1      	GND                 
          	               	263       	91B4      	M_E_CPU0_SB_DQ<14>  
          	               	264       	91B1      	GND                 
          	               	265       	91B4      	M_E_CPU0_SB_DQ<15>  
          	               	266       	91B1      	GND                 
          	               	267       	91B4      	M_E_CPU0_SB_DQ<18>  
          	               	268       	91B1      	GND                 
          	               	269       	91B4      	M_E_CPU0_SB_DQ<19>  
          	               	270       	91B1      	GND                 
          	               	271       	91B2      	M_E_CPU0_SB_DQS_DN<7>
          	               	272       	91B2      	M_E_CPU0_SB_DQS_DP<7>
          	               	273       	91B1      	GND                 
          	               	274       	91B4      	M_E_CPU0_SB_DQ<22>  
          	               	275       	91B1      	GND                 
          	               	276       	91B4      	M_E_CPU0_SB_DQ<23>  
          	               	277       	91B1      	GND                 
          	               	278       	91B4      	M_E_CPU0_SB_DQ<26>  
          	               	279       	91B1      	GND                 
          	               	280       	91B4      	M_E_CPU0_SB_DQ<27>  
          	               	281       	91B1      	GND                 
          	               	282       	91B2      	M_E_CPU0_SB_DQS_DN<8>
          	               	283       	91B2      	M_E_CPU0_SB_DQS_DP<8>
          	               	284       	91B1      	GND                 
          	               	285       	91B4      	M_E_CPU0_SB_DQ<30>  
          	               	286       	91B1      	GND                 
          	               	287       	91B4      	M_E_CPU0_SB_DQ<31>  
          	               	288       	91B1      	GND                 
          	               	G1        	91B1      	GND                 
          	               	G2        	91A1      	GND                 
          	               	G3        	91A1      	GND                 

J11       	SCONN288_ADR50017P130CC	          	          	                    
          	               	1         	92B1      	P12V_S3_AUX_CPU0_NVDIMM
          	               	2         	92B4      	TP_CHF_CPU0_DIMM1_FRU_0
          	               	3         	92B4      	P3V3_AUX            
          	               	4         	92B4      	I3C_SPD_DDREFGH_CPU0_LVC1_SCL_2
          	               	5         	92B4      	I3C_SPD_DDREFGH_CPU0_LVC1_SDA
          	               	6         	92B1      	GND                 
          	               	7         	92B4      	M_F_CPU0_SA_DQ<0>   
          	               	8         	92B1      	GND                 
          	               	9         	92B4      	M_F_CPU0_SA_DQ<1>   
          	               	10        	92B1      	GND                 
          	               	11        	92B2      	M_F_CPU0_SA_DQS_DP<0>
          	               	12        	92B2      	M_F_CPU0_SA_DQS_DN<0>
          	               	13        	92B1      	GND                 
          	               	14        	92B4      	M_F_CPU0_SA_DQ<4>   
          	               	15        	92B1      	GND                 
          	               	16        	92B4      	M_F_CPU0_SA_DQ<5>   
          	               	17        	92B1      	GND                 
          	               	18        	92B4      	M_F_CPU0_SA_DQ<8>   
          	               	19        	92B1      	GND                 
          	               	20        	92B4      	M_F_CPU0_SA_DQ<9>   
          	               	21        	92B1      	GND                 
          	               	22        	92B2      	M_F_CPU0_SA_DQS_DP<1>
          	               	23        	92B2      	M_F_CPU0_SA_DQS_DN<1>
          	               	24        	92B1      	GND                 
          	               	25        	92B4      	M_F_CPU0_SA_DQ<12>  
          	               	26        	92B1      	GND                 
          	               	27        	92B4      	M_F_CPU0_SA_DQ<13>  
          	               	28        	92B1      	GND                 
          	               	29        	92B4      	M_F_CPU0_SA_DQ<16>  
          	               	30        	92B1      	GND                 
          	               	31        	92B4      	M_F_CPU0_SA_DQ<17>  
          	               	32        	92B1      	GND                 
          	               	33        	92B2      	M_F_CPU0_SA_DQS_DP<2>
          	               	34        	92B2      	M_F_CPU0_SA_DQS_DN<2>
          	               	35        	92B1      	GND                 
          	               	36        	92B4      	M_F_CPU0_SA_DQ<20>  
          	               	37        	92B1      	GND                 
          	               	38        	92B4      	M_F_CPU0_SA_DQ<21>  
          	               	39        	92B1      	GND                 
          	               	40        	92B4      	M_F_CPU0_SA_DQ<24>  
          	               	41        	92B1      	GND                 
          	               	42        	92B4      	M_F_CPU0_SA_DQ<25>  
          	               	43        	92B1      	GND                 
          	               	44        	92B2      	M_F_CPU0_SA_DQS_DP<3>
          	               	45        	92B2      	M_F_CPU0_SA_DQS_DN<3>
          	               	46        	92B1      	GND                 
          	               	47        	92B4      	M_F_CPU0_SA_DQ<28>  
          	               	48        	92B1      	GND                 
          	               	49        	92B4      	M_F_CPU0_SA_DQ<29>  
          	               	50        	92B1      	GND                 
          	               	51        	92B4      	M_F_CPU0_SA_CB<0>   
          	               	52        	92B1      	GND                 
          	               	53        	92B4      	M_F_CPU0_SA_CB<1>   
          	               	54        	92B1      	GND                 
          	               	55        	92B2      	M_F_CPU0_SA_DQS_DP<4>
          	               	56        	92B2      	M_F_CPU0_SA_DQS_DN<4>
          	               	57        	92B1      	GND                 
          	               	58        	92B4      	M_F_CPU0_SA_CB<4>   
          	               	59        	92B1      	GND                 
          	               	60        	92B4      	M_F_CPU0_SA_CB<5>   
          	               	61        	92B1      	GND                 
          	               	62        	92B4      	M_F_CPU0_ALERT_N    
          	               	63        	92B1      	GND                 
          	               	64        	92B4      	M_F_CPU0_SA_CS_N<0> 
          	               	65        	92B1      	GND                 
          	               	66        	92B4      	M_F_CPU0_SA_CA<0>   
          	               	67        	92B1      	GND                 
          	               	68        	92B4      	M_F_CPU0_SA_CA<2>   
          	               	69        	92B1      	GND                 
          	               	70        	92B4      	M_F_CPU0_SA_CA<4>   
          	               	71        	92B1      	GND                 
          	               	72        	92B4      	M_F_CPU0_SA_CA<6>   
          	               	73        	92B1      	GND                 
          	               	74        	92B4      	M_F_CPU0_SA_PAR     
          	               	75        	92B1      	GND                 
          	               	76        	92B4      	M_F_CPU0_SB_CA<0>   
          	               	77        	92B1      	GND                 
          	               	78        	92B4      	M_F_CPU0_SB_CA<2>   
          	               	79        	92B1      	GND                 
          	               	80        	92B4      	M_F_CPU0_SB_CA<4>   
          	               	81        	92B1      	GND                 
          	               	82        	92B4      	M_F_CPU0_SB_CA<6>   
          	               	83        	92B1      	GND                 
          	               	84        	92B4      	M_F_CPU0_SB_CS_N<0> 
          	               	85        	92B1      	GND                 
          	               	86        	92A4      	M_F_CPU0_SA_RSP<0>  
          	               	87        	92A4      	M_F_CPU0_SB_RSP<0>  
          	               	88        	92B1      	GND                 
          	               	89        	92B4      	M_F_CPU0_SB_CB<4>   
          	               	90        	92B1      	GND                 
          	               	91        	92B4      	M_F_CPU0_SB_CB<5>   
          	               	92        	92B1      	GND                 
          	               	93        	92B2      	M_F_CPU0_SB_DQS_DP<9>
          	               	94        	92B2      	M_F_CPU0_SB_DQS_DN<9>
          	               	95        	92B1      	GND                 
          	               	96        	92B4      	M_F_CPU0_SB_CB<0>   
          	               	97        	92B1      	GND                 
          	               	98        	92B4      	M_F_CPU0_SB_CB<1>   
          	               	99        	92B1      	GND                 
          	               	100       	92B4      	M_F_CPU0_SB_DQ<0>   
          	               	101       	92B1      	GND                 
          	               	102       	92B4      	M_F_CPU0_SB_DQ<1>   
          	               	103       	92B1      	GND                 
          	               	104       	92B2      	M_F_CPU0_SB_DQS_DP<0>
          	               	105       	92B2      	M_F_CPU0_SB_DQS_DN<0>
          	               	106       	92B1      	GND                 
          	               	107       	92B4      	M_F_CPU0_SB_DQ<4>   
          	               	108       	92B1      	GND                 
          	               	109       	92B4      	M_F_CPU0_SB_DQ<5>   
          	               	110       	92B1      	GND                 
          	               	111       	92B4      	M_F_CPU0_SB_DQ<8>   
          	               	112       	92B1      	GND                 
          	               	113       	92B4      	M_F_CPU0_SB_DQ<9>   
          	               	114       	92B1      	GND                 
          	               	115       	92B2      	M_F_CPU0_SB_DQS_DP<1>
          	               	116       	92B2      	M_F_CPU0_SB_DQS_DN<1>
          	               	117       	92B1      	GND                 
          	               	118       	92B4      	M_F_CPU0_SB_DQ<12>  
          	               	119       	92B1      	GND                 
          	               	120       	92B4      	M_F_CPU0_SB_DQ<13>  
          	               	121       	92B1      	GND                 
          	               	122       	92B4      	M_F_CPU0_SB_DQ<16>  
          	               	123       	92B1      	GND                 
          	               	124       	92B4      	M_F_CPU0_SB_DQ<17>  
          	               	125       	92B1      	GND                 
          	               	126       	92B2      	M_F_CPU0_SB_DQS_DP<2>
          	               	127       	92B2      	M_F_CPU0_SB_DQS_DN<2>
          	               	128       	92B1      	GND                 
          	               	129       	92B4      	M_F_CPU0_SB_DQ<20>  
          	               	130       	92B1      	GND                 
          	               	131       	92B4      	M_F_CPU0_SB_DQ<21>  
          	               	132       	92B1      	GND                 
          	               	133       	92B4      	M_F_CPU0_SB_DQ<24>  
          	               	134       	92B1      	GND                 
          	               	135       	92B4      	M_F_CPU0_SB_DQ<25>  
          	               	136       	92B1      	GND                 
          	               	137       	92B2      	M_F_CPU0_SB_DQS_DP<3>
          	               	138       	92B2      	M_F_CPU0_SB_DQS_DN<3>
          	               	139       	92B1      	GND                 
          	               	140       	92B4      	M_F_CPU0_SB_DQ<28>  
          	               	141       	92B1      	GND                 
          	               	142       	92B4      	M_F_CPU0_SB_DQ<29>  
          	               	143       	92B1      	GND                 
          	               	144       	92B4      	TP_CHF_CPU0_DIMM1_FRU_1
          	               	145       	92B1      	P12V_S3_AUX_CPU0_NVDIMM
          	               	146       	92B1      	P12V_S3_AUX_CPU0_NVDIMM
          	               	147       	92B4      	PWRGD_CHF_CPU0_DIMM1
          	               	148       	92B4      	PD_CHF_CPU0_DIMM1_SAA
          	               	149       	92B4      	TP_CHF_CPU0_DIMM1_FRU_2
          	               	150       	92B4      	TP_CHF_CPU0_DIMM1_FRU_3
          	               	151       	92B1      	GND                 
          	               	152       	92B4      	M_F_CPU0_SA_DQ<2>   
          	               	153       	92B1      	GND                 
          	               	154       	92B4      	M_F_CPU0_SA_DQ<3>   
          	               	155       	92B1      	GND                 
          	               	156       	92B2      	M_F_CPU0_SA_DQS_DN<5>
          	               	157       	92B2      	M_F_CPU0_SA_DQS_DP<5>
          	               	158       	92B1      	GND                 
          	               	159       	92B4      	M_F_CPU0_SA_DQ<6>   
          	               	160       	92B1      	GND                 
          	               	161       	92B4      	M_F_CPU0_SA_DQ<7>   
          	               	162       	92B1      	GND                 
          	               	163       	92B4      	M_F_CPU0_SA_DQ<10>  
          	               	164       	92B1      	GND                 
          	               	165       	92B4      	M_F_CPU0_SA_DQ<11>  
          	               	166       	92B1      	GND                 
          	               	167       	92B2      	M_F_CPU0_SA_DQS_DN<6>
          	               	168       	92B2      	M_F_CPU0_SA_DQS_DP<6>
          	               	169       	92B1      	GND                 
          	               	170       	92B4      	M_F_CPU0_SA_DQ<14>  
          	               	171       	92B1      	GND                 
          	               	172       	92B4      	M_F_CPU0_SA_DQ<15>  
          	               	173       	92B1      	GND                 
          	               	174       	92B4      	M_F_CPU0_SA_DQ<18>  
          	               	175       	92B1      	GND                 
          	               	176       	92B4      	M_F_CPU0_SA_DQ<19>  
          	               	177       	92B1      	GND                 
          	               	178       	92B2      	M_F_CPU0_SA_DQS_DN<7>
          	               	179       	92B2      	M_F_CPU0_SA_DQS_DP<7>
          	               	180       	92B1      	GND                 
          	               	181       	92B4      	M_F_CPU0_SA_DQ<22>  
          	               	182       	92B1      	GND                 
          	               	183       	92B4      	M_F_CPU0_SA_DQ<23>  
          	               	184       	92B1      	GND                 
          	               	185       	92B4      	M_F_CPU0_SA_DQ<26>  
          	               	186       	92B1      	GND                 
          	               	187       	92B4      	M_F_CPU0_SA_DQ<27>  
          	               	188       	92B1      	GND                 
          	               	189       	92B2      	M_F_CPU0_SA_DQS_DN<8>
          	               	190       	92B2      	M_F_CPU0_SA_DQS_DP<8>
          	               	191       	92B1      	GND                 
          	               	192       	92B4      	M_F_CPU0_SA_DQ<30>  
          	               	193       	92B1      	GND                 
          	               	194       	92B4      	M_F_CPU0_SA_DQ<31>  
          	               	195       	92B1      	GND                 
          	               	196       	92B4      	M_F_CPU0_SA_CB<2>   
          	               	197       	92B1      	GND                 
          	               	198       	92B4      	M_F_CPU0_SA_CB<3>   
          	               	199       	92B1      	GND                 
          	               	200       	92B2      	M_F_CPU0_SA_DQS_DN<9>
          	               	201       	92B2      	M_F_CPU0_SA_DQS_DP<9>
          	               	202       	92B1      	GND                 
          	               	203       	92B4      	M_F_CPU0_SA_CB<6>   
          	               	204       	92B1      	GND                 
          	               	205       	92B4      	M_F_CPU0_SA_CB<7>   
          	               	206       	92B1      	GND                 
          	               	207       	92B4      	RST_M_EF_CPU0_FPGA_N
          	               	208       	92B1      	GND                 
          	               	209       	92B4      	M_F_CPU0_SA_CS_N<1> 
          	               	210       	92B1      	GND                 
          	               	211       	92B4      	M_F_CPU0_SA_CA<1>   
          	               	212       	92B1      	GND                 
          	               	213       	92B4      	M_F_CPU0_SA_CA<3>   
          	               	214       	92B1      	GND                 
          	               	215       	92B4      	M_F_CPU0_SA_CA<5>   
          	               	216       	92B1      	GND                 
          	               	217       	92B4      	M_F_CPU0_CLK_DP<0>  
          	               	218       	92B4      	M_F_CPU0_CLK_DN<0>  
          	               	219       	92B1      	GND                 
          	               	220       	92B4      	TP_CHF_CPU0_DIMM1_FRU_4
          	               	221       	92B4      	M_F_CPU0_SB_CA<1>   
          	               	222       	92B1      	GND                 
          	               	223       	92B4      	M_F_CPU0_SB_CA<3>   
          	               	224       	92B1      	GND                 
          	               	225       	92B4      	M_F_CPU0_SB_CA<5>   
          	               	226       	92B1      	GND                 
          	               	227       	92B4      	M_F_CPU0_SB_PAR     
          	               	228       	92B1      	GND                 
          	               	229       	92B4      	M_F_CPU0_SB_CS_N<1> 
          	               	230       	92B1      	GND                 
          	               	231       	92B4      	TP_CHF_CPU0_DIMM1_FRU_5
          	               	232       	92B4      	TP_CHF_CPU0_DIMM1_FRU_6
          	               	233       	92B1      	GND                 
          	               	234       	92B4      	M_F_CPU0_SB_CB<6>   
          	               	235       	92B1      	GND                 
          	               	236       	92B4      	M_F_CPU0_SB_CB<7>   
          	               	237       	92B1      	GND                 
          	               	238       	92B2      	M_F_CPU0_SB_DQS_DN<4>
          	               	239       	92B2      	M_F_CPU0_SB_DQS_DP<4>
          	               	240       	92B1      	GND                 
          	               	241       	92B4      	M_F_CPU0_SB_CB<2>   
          	               	242       	92B1      	GND                 
          	               	243       	92B4      	M_F_CPU0_SB_CB<3>   
          	               	244       	92B1      	GND                 
          	               	245       	92B4      	M_F_CPU0_SB_DQ<2>   
          	               	246       	92B1      	GND                 
          	               	247       	92B4      	M_F_CPU0_SB_DQ<3>   
          	               	248       	92B1      	GND                 
          	               	249       	92B2      	M_F_CPU0_SB_DQS_DN<5>
          	               	250       	92B2      	M_F_CPU0_SB_DQS_DP<5>
          	               	251       	92B1      	GND                 
          	               	252       	92B4      	M_F_CPU0_SB_DQ<6>   
          	               	253       	92B1      	GND                 
          	               	254       	92B4      	M_F_CPU0_SB_DQ<7>   
          	               	255       	92B1      	GND                 
          	               	256       	92B4      	M_F_CPU0_SB_DQ<10>  
          	               	257       	92B1      	GND                 
          	               	258       	92B4      	M_F_CPU0_SB_DQ<11>  
          	               	259       	92B1      	GND                 
          	               	260       	92B2      	M_F_CPU0_SB_DQS_DN<6>
          	               	261       	92B2      	M_F_CPU0_SB_DQS_DP<6>
          	               	262       	92B1      	GND                 
          	               	263       	92B4      	M_F_CPU0_SB_DQ<14>  
          	               	264       	92B1      	GND                 
          	               	265       	92B4      	M_F_CPU0_SB_DQ<15>  
          	               	266       	92B1      	GND                 
          	               	267       	92B4      	M_F_CPU0_SB_DQ<18>  
          	               	268       	92B1      	GND                 
          	               	269       	92B4      	M_F_CPU0_SB_DQ<19>  
          	               	270       	92B1      	GND                 
          	               	271       	92B2      	M_F_CPU0_SB_DQS_DN<7>
          	               	272       	92B2      	M_F_CPU0_SB_DQS_DP<7>
          	               	273       	92B1      	GND                 
          	               	274       	92B4      	M_F_CPU0_SB_DQ<22>  
          	               	275       	92B1      	GND                 
          	               	276       	92B4      	M_F_CPU0_SB_DQ<23>  
          	               	277       	92B1      	GND                 
          	               	278       	92B4      	M_F_CPU0_SB_DQ<26>  
          	               	279       	92B1      	GND                 
          	               	280       	92B4      	M_F_CPU0_SB_DQ<27>  
          	               	281       	92B1      	GND                 
          	               	282       	92B2      	M_F_CPU0_SB_DQS_DN<8>
          	               	283       	92B2      	M_F_CPU0_SB_DQS_DP<8>
          	               	284       	92B1      	GND                 
          	               	285       	92B4      	M_F_CPU0_SB_DQ<30>  
          	               	286       	92B1      	GND                 
          	               	287       	92B4      	M_F_CPU0_SB_DQ<31>  
          	               	288       	92B1      	GND                 
          	               	G1        	92B1      	GND                 
          	               	G2        	92A1      	GND                 
          	               	G3        	92A1      	GND                 

J12       	SCONN288_ADR50017P087CC	          	          	                    
          	               	1         	93B1      	P12V_S3_AUX_CPU0_NVDIMM
          	               	2         	93B4      	TP_CHF_CPU0_DIMM2_FRU_0
          	               	3         	93B4      	P3V3_AUX            
          	               	4         	93B4      	I3C_SPD_DDREFGH_CPU0_LVC1_SCL_3
          	               	5         	93B4      	I3C_SPD_DDREFGH_CPU0_LVC1_SDA
          	               	6         	93B1      	GND                 
          	               	7         	93B4      	M_F_CPU0_SA_DQ<0>   
          	               	8         	93B1      	GND                 
          	               	9         	93B4      	M_F_CPU0_SA_DQ<1>   
          	               	10        	93B1      	GND                 
          	               	11        	93B2      	M_F_CPU0_SA_DQS_DP<0>
          	               	12        	93B2      	M_F_CPU0_SA_DQS_DN<0>
          	               	13        	93B1      	GND                 
          	               	14        	93B4      	M_F_CPU0_SA_DQ<4>   
          	               	15        	93B1      	GND                 
          	               	16        	93B4      	M_F_CPU0_SA_DQ<5>   
          	               	17        	93B1      	GND                 
          	               	18        	93B4      	M_F_CPU0_SA_DQ<8>   
          	               	19        	93B1      	GND                 
          	               	20        	93B4      	M_F_CPU0_SA_DQ<9>   
          	               	21        	93B1      	GND                 
          	               	22        	93B2      	M_F_CPU0_SA_DQS_DP<1>
          	               	23        	93B2      	M_F_CPU0_SA_DQS_DN<1>
          	               	24        	93B1      	GND                 
          	               	25        	93B4      	M_F_CPU0_SA_DQ<12>  
          	               	26        	93B1      	GND                 
          	               	27        	93B4      	M_F_CPU0_SA_DQ<13>  
          	               	28        	93B1      	GND                 
          	               	29        	93B4      	M_F_CPU0_SA_DQ<16>  
          	               	30        	93B1      	GND                 
          	               	31        	93B4      	M_F_CPU0_SA_DQ<17>  
          	               	32        	93B1      	GND                 
          	               	33        	93B2      	M_F_CPU0_SA_DQS_DP<2>
          	               	34        	93B2      	M_F_CPU0_SA_DQS_DN<2>
          	               	35        	93B1      	GND                 
          	               	36        	93B4      	M_F_CPU0_SA_DQ<20>  
          	               	37        	93B1      	GND                 
          	               	38        	93B4      	M_F_CPU0_SA_DQ<21>  
          	               	39        	93B1      	GND                 
          	               	40        	93B4      	M_F_CPU0_SA_DQ<24>  
          	               	41        	93B1      	GND                 
          	               	42        	93B4      	M_F_CPU0_SA_DQ<25>  
          	               	43        	93B1      	GND                 
          	               	44        	93B2      	M_F_CPU0_SA_DQS_DP<3>
          	               	45        	93B2      	M_F_CPU0_SA_DQS_DN<3>
          	               	46        	93B1      	GND                 
          	               	47        	93B4      	M_F_CPU0_SA_DQ<28>  
          	               	48        	93B1      	GND                 
          	               	49        	93B4      	M_F_CPU0_SA_DQ<29>  
          	               	50        	93B1      	GND                 
          	               	51        	93B4      	M_F_CPU0_SA_CB<0>   
          	               	52        	93B1      	GND                 
          	               	53        	93B4      	M_F_CPU0_SA_CB<1>   
          	               	54        	93B1      	GND                 
          	               	55        	93B2      	M_F_CPU0_SA_DQS_DP<4>
          	               	56        	93B2      	M_F_CPU0_SA_DQS_DN<4>
          	               	57        	93B1      	GND                 
          	               	58        	93B4      	M_F_CPU0_SA_CB<4>   
          	               	59        	93B1      	GND                 
          	               	60        	93B4      	M_F_CPU0_SA_CB<5>   
          	               	61        	93B1      	GND                 
          	               	62        	93B4      	M_F_CPU0_ALERT_N    
          	               	63        	93B1      	GND                 
          	               	64        	93B4      	M_F_CPU0_SA_CS_N<2> 
          	               	65        	93B1      	GND                 
          	               	66        	93B4      	M_F_CPU0_SA_CA<0>   
          	               	67        	93B1      	GND                 
          	               	68        	93B4      	M_F_CPU0_SA_CA<2>   
          	               	69        	93B1      	GND                 
          	               	70        	93B4      	M_F_CPU0_SA_CA<4>   
          	               	71        	93B1      	GND                 
          	               	72        	93B4      	M_F_CPU0_SA_CA<6>   
          	               	73        	93B1      	GND                 
          	               	74        	93B4      	M_F_CPU0_SA_PAR     
          	               	75        	93B1      	GND                 
          	               	76        	93B4      	M_F_CPU0_SB_CA<0>   
          	               	77        	93B1      	GND                 
          	               	78        	93B4      	M_F_CPU0_SB_CA<2>   
          	               	79        	93B1      	GND                 
          	               	80        	93B4      	M_F_CPU0_SB_CA<4>   
          	               	81        	93B1      	GND                 
          	               	82        	93B4      	M_F_CPU0_SB_CA<6>   
          	               	83        	93B1      	GND                 
          	               	84        	93B4      	M_F_CPU0_SB_CS_N<2> 
          	               	85        	93B1      	GND                 
          	               	86        	93A4      	M_F_CPU0_SA_RSP<1>  
          	               	87        	93A4      	M_F_CPU0_SB_RSP<1>  
          	               	88        	93B1      	GND                 
          	               	89        	93B4      	M_F_CPU0_SB_CB<4>   
          	               	90        	93B1      	GND                 
          	               	91        	93B4      	M_F_CPU0_SB_CB<5>   
          	               	92        	93B1      	GND                 
          	               	93        	93B2      	M_F_CPU0_SB_DQS_DP<9>
          	               	94        	93B2      	M_F_CPU0_SB_DQS_DN<9>
          	               	95        	93B1      	GND                 
          	               	96        	93B4      	M_F_CPU0_SB_CB<0>   
          	               	97        	93B1      	GND                 
          	               	98        	93B4      	M_F_CPU0_SB_CB<1>   
          	               	99        	93B1      	GND                 
          	               	100       	93B4      	M_F_CPU0_SB_DQ<0>   
          	               	101       	93B1      	GND                 
          	               	102       	93B4      	M_F_CPU0_SB_DQ<1>   
          	               	103       	93B1      	GND                 
          	               	104       	93B2      	M_F_CPU0_SB_DQS_DP<0>
          	               	105       	93B2      	M_F_CPU0_SB_DQS_DN<0>
          	               	106       	93B1      	GND                 
          	               	107       	93B4      	M_F_CPU0_SB_DQ<4>   
          	               	108       	93B1      	GND                 
          	               	109       	93B4      	M_F_CPU0_SB_DQ<5>   
          	               	110       	93B1      	GND                 
          	               	111       	93B4      	M_F_CPU0_SB_DQ<8>   
          	               	112       	93B1      	GND                 
          	               	113       	93B4      	M_F_CPU0_SB_DQ<9>   
          	               	114       	93B1      	GND                 
          	               	115       	93B2      	M_F_CPU0_SB_DQS_DP<1>
          	               	116       	93B2      	M_F_CPU0_SB_DQS_DN<1>
          	               	117       	93B1      	GND                 
          	               	118       	93B4      	M_F_CPU0_SB_DQ<12>  
          	               	119       	93B1      	GND                 
          	               	120       	93B4      	M_F_CPU0_SB_DQ<13>  
          	               	121       	93B1      	GND                 
          	               	122       	93B4      	M_F_CPU0_SB_DQ<16>  
          	               	123       	93B1      	GND                 
          	               	124       	93B4      	M_F_CPU0_SB_DQ<17>  
          	               	125       	93B1      	GND                 
          	               	126       	93B2      	M_F_CPU0_SB_DQS_DP<2>
          	               	127       	93B2      	M_F_CPU0_SB_DQS_DN<2>
          	               	128       	93B1      	GND                 
          	               	129       	93B4      	M_F_CPU0_SB_DQ<20>  
          	               	130       	93B1      	GND                 
          	               	131       	93B4      	M_F_CPU0_SB_DQ<21>  
          	               	132       	93B1      	GND                 
          	               	133       	93B4      	M_F_CPU0_SB_DQ<24>  
          	               	134       	93B1      	GND                 
          	               	135       	93B4      	M_F_CPU0_SB_DQ<25>  
          	               	136       	93B1      	GND                 
          	               	137       	93B2      	M_F_CPU0_SB_DQS_DP<3>
          	               	138       	93B2      	M_F_CPU0_SB_DQS_DN<3>
          	               	139       	93B1      	GND                 
          	               	140       	93B4      	M_F_CPU0_SB_DQ<28>  
          	               	141       	93B1      	GND                 
          	               	142       	93B4      	M_F_CPU0_SB_DQ<29>  
          	               	143       	93B1      	GND                 
          	               	144       	93B4      	TP_CHF_CPU0_DIMM2_FRU_1
          	               	145       	93B1      	P12V_S3_AUX_CPU0_NVDIMM
          	               	146       	93B1      	P12V_S3_AUX_CPU0_NVDIMM
          	               	147       	93B4      	PWRGD_CHF_CPU0_DIMM2
          	               	148       	93B4      	PD_CHF_CPU0_DIMM2_SAA
          	               	149       	93B4      	TP_CHF_CPU0_DIMM2_FRU_2
          	               	150       	93B4      	TP_CHF_CPU0_DIMM2_FRU_3
          	               	151       	93B1      	GND                 
          	               	152       	93B4      	M_F_CPU0_SA_DQ<2>   
          	               	153       	93B1      	GND                 
          	               	154       	93B4      	M_F_CPU0_SA_DQ<3>   
          	               	155       	93B1      	GND                 
          	               	156       	93B2      	M_F_CPU0_SA_DQS_DN<5>
          	               	157       	93B2      	M_F_CPU0_SA_DQS_DP<5>
          	               	158       	93B1      	GND                 
          	               	159       	93B4      	M_F_CPU0_SA_DQ<6>   
          	               	160       	93B1      	GND                 
          	               	161       	93B4      	M_F_CPU0_SA_DQ<7>   
          	               	162       	93B1      	GND                 
          	               	163       	93B4      	M_F_CPU0_SA_DQ<10>  
          	               	164       	93B1      	GND                 
          	               	165       	93B4      	M_F_CPU0_SA_DQ<11>  
          	               	166       	93B1      	GND                 
          	               	167       	93B2      	M_F_CPU0_SA_DQS_DN<6>
          	               	168       	93B2      	M_F_CPU0_SA_DQS_DP<6>
          	               	169       	93B1      	GND                 
          	               	170       	93B4      	M_F_CPU0_SA_DQ<14>  
          	               	171       	93B1      	GND                 
          	               	172       	93B4      	M_F_CPU0_SA_DQ<15>  
          	               	173       	93B1      	GND                 
          	               	174       	93B4      	M_F_CPU0_SA_DQ<18>  
          	               	175       	93B1      	GND                 
          	               	176       	93B4      	M_F_CPU0_SA_DQ<19>  
          	               	177       	93B1      	GND                 
          	               	178       	93B2      	M_F_CPU0_SA_DQS_DN<7>
          	               	179       	93B2      	M_F_CPU0_SA_DQS_DP<7>
          	               	180       	93B1      	GND                 
          	               	181       	93B4      	M_F_CPU0_SA_DQ<22>  
          	               	182       	93B1      	GND                 
          	               	183       	93B4      	M_F_CPU0_SA_DQ<23>  
          	               	184       	93B1      	GND                 
          	               	185       	93B4      	M_F_CPU0_SA_DQ<26>  
          	               	186       	93B1      	GND                 
          	               	187       	93B4      	M_F_CPU0_SA_DQ<27>  
          	               	188       	93B1      	GND                 
          	               	189       	93B2      	M_F_CPU0_SA_DQS_DN<8>
          	               	190       	93B2      	M_F_CPU0_SA_DQS_DP<8>
          	               	191       	93B1      	GND                 
          	               	192       	93B4      	M_F_CPU0_SA_DQ<30>  
          	               	193       	93B1      	GND                 
          	               	194       	93B4      	M_F_CPU0_SA_DQ<31>  
          	               	195       	93B1      	GND                 
          	               	196       	93B4      	M_F_CPU0_SA_CB<2>   
          	               	197       	93B1      	GND                 
          	               	198       	93B4      	M_F_CPU0_SA_CB<3>   
          	               	199       	93B1      	GND                 
          	               	200       	93B2      	M_F_CPU0_SA_DQS_DN<9>
          	               	201       	93B2      	M_F_CPU0_SA_DQS_DP<9>
          	               	202       	93B1      	GND                 
          	               	203       	93B4      	M_F_CPU0_SA_CB<6>   
          	               	204       	93B1      	GND                 
          	               	205       	93B4      	M_F_CPU0_SA_CB<7>   
          	               	206       	93B1      	GND                 
          	               	207       	93B4      	RST_M_EF_CPU0_FPGA_N
          	               	208       	93B1      	GND                 
          	               	209       	93B4      	M_F_CPU0_SA_CS_N<3> 
          	               	210       	93B1      	GND                 
          	               	211       	93B4      	M_F_CPU0_SA_CA<1>   
          	               	212       	93B1      	GND                 
          	               	213       	93B4      	M_F_CPU0_SA_CA<3>   
          	               	214       	93B1      	GND                 
          	               	215       	93B4      	M_F_CPU0_SA_CA<5>   
          	               	216       	93B1      	GND                 
          	               	217       	93B4      	M_F_CPU0_CLK_DP<1>  
          	               	218       	93B4      	M_F_CPU0_CLK_DN<1>  
          	               	219       	93B1      	GND                 
          	               	220       	93B4      	TP_CHF_CPU0_DIMM2_FRU_4
          	               	221       	93B4      	M_F_CPU0_SB_CA<1>   
          	               	222       	93B1      	GND                 
          	               	223       	93B4      	M_F_CPU0_SB_CA<3>   
          	               	224       	93B1      	GND                 
          	               	225       	93B4      	M_F_CPU0_SB_CA<5>   
          	               	226       	93B1      	GND                 
          	               	227       	93B4      	M_F_CPU0_SB_PAR     
          	               	228       	93B1      	GND                 
          	               	229       	93B4      	M_F_CPU0_SB_CS_N<3> 
          	               	230       	93B1      	GND                 
          	               	231       	93B4      	TP_CHF_CPU0_DIMM2_FRU_5
          	               	232       	93B4      	TP_CHF_CPU0_DIMM2_FRU_6
          	               	233       	93B1      	GND                 
          	               	234       	93B4      	M_F_CPU0_SB_CB<6>   
          	               	235       	93B1      	GND                 
          	               	236       	93B4      	M_F_CPU0_SB_CB<7>   
          	               	237       	93B1      	GND                 
          	               	238       	93B2      	M_F_CPU0_SB_DQS_DN<4>
          	               	239       	93B2      	M_F_CPU0_SB_DQS_DP<4>
          	               	240       	93B1      	GND                 
          	               	241       	93B4      	M_F_CPU0_SB_CB<2>   
          	               	242       	93B1      	GND                 
          	               	243       	93B4      	M_F_CPU0_SB_CB<3>   
          	               	244       	93B1      	GND                 
          	               	245       	93B4      	M_F_CPU0_SB_DQ<2>   
          	               	246       	93B1      	GND                 
          	               	247       	93B4      	M_F_CPU0_SB_DQ<3>   
          	               	248       	93B1      	GND                 
          	               	249       	93B2      	M_F_CPU0_SB_DQS_DN<5>
          	               	250       	93B2      	M_F_CPU0_SB_DQS_DP<5>
          	               	251       	93B1      	GND                 
          	               	252       	93B4      	M_F_CPU0_SB_DQ<6>   
          	               	253       	93B1      	GND                 
          	               	254       	93B4      	M_F_CPU0_SB_DQ<7>   
          	               	255       	93B1      	GND                 
          	               	256       	93B4      	M_F_CPU0_SB_DQ<10>  
          	               	257       	93B1      	GND                 
          	               	258       	93B4      	M_F_CPU0_SB_DQ<11>  
          	               	259       	93B1      	GND                 
          	               	260       	93B2      	M_F_CPU0_SB_DQS_DN<6>
          	               	261       	93B2      	M_F_CPU0_SB_DQS_DP<6>
          	               	262       	93B1      	GND                 
          	               	263       	93B4      	M_F_CPU0_SB_DQ<14>  
          	               	264       	93B1      	GND                 
          	               	265       	93B4      	M_F_CPU0_SB_DQ<15>  
          	               	266       	93B1      	GND                 
          	               	267       	93B4      	M_F_CPU0_SB_DQ<18>  
          	               	268       	93B1      	GND                 
          	               	269       	93B4      	M_F_CPU0_SB_DQ<19>  
          	               	270       	93B1      	GND                 
          	               	271       	93B2      	M_F_CPU0_SB_DQS_DN<7>
          	               	272       	93B2      	M_F_CPU0_SB_DQS_DP<7>
          	               	273       	93B1      	GND                 
          	               	274       	93B4      	M_F_CPU0_SB_DQ<22>  
          	               	275       	93B1      	GND                 
          	               	276       	93B4      	M_F_CPU0_SB_DQ<23>  
          	               	277       	93B1      	GND                 
          	               	278       	93B4      	M_F_CPU0_SB_DQ<26>  
          	               	279       	93B1      	GND                 
          	               	280       	93B4      	M_F_CPU0_SB_DQ<27>  
          	               	281       	93B1      	GND                 
          	               	282       	93B2      	M_F_CPU0_SB_DQS_DN<8>
          	               	283       	93B2      	M_F_CPU0_SB_DQS_DP<8>
          	               	284       	93B1      	GND                 
          	               	285       	93B4      	M_F_CPU0_SB_DQ<30>  
          	               	286       	93B1      	GND                 
          	               	287       	93B4      	M_F_CPU0_SB_DQ<31>  
          	               	288       	93B1      	GND                 
          	               	G1        	93B1      	GND                 
          	               	G2        	93A1      	GND                 
          	               	G3        	93A1      	GND                 

J13       	SCONN288_ADR50017P130CC	          	          	                    
          	               	1         	94B1      	P12V_S3_AUX_CPU0_NVDIMM
          	               	2         	94B4      	TP_CHG_CPU0_DIMM1_FRU_0
          	               	3         	94B4      	P3V3_AUX            
          	               	4         	94B4      	I3C_SPD_DDREFGH_CPU0_LVC1_SCL_4
          	               	5         	94B4      	I3C_SPD_DDREFGH_CPU0_LVC1_SDA
          	               	6         	94B1      	GND                 
          	               	7         	94B4      	M_G_CPU0_SA_DQ<0>   
          	               	8         	94B1      	GND                 
          	               	9         	94B4      	M_G_CPU0_SA_DQ<1>   
          	               	10        	94B1      	GND                 
          	               	11        	94B2      	M_G_CPU0_SA_DQS_DP<0>
          	               	12        	94B2      	M_G_CPU0_SA_DQS_DN<0>
          	               	13        	94B1      	GND                 
          	               	14        	94B4      	M_G_CPU0_SA_DQ<4>   
          	               	15        	94B1      	GND                 
          	               	16        	94B4      	M_G_CPU0_SA_DQ<5>   
          	               	17        	94B1      	GND                 
          	               	18        	94B4      	M_G_CPU0_SA_DQ<8>   
          	               	19        	94B1      	GND                 
          	               	20        	94B4      	M_G_CPU0_SA_DQ<9>   
          	               	21        	94B1      	GND                 
          	               	22        	94B2      	M_G_CPU0_SA_DQS_DP<1>
          	               	23        	94B2      	M_G_CPU0_SA_DQS_DN<1>
          	               	24        	94B1      	GND                 
          	               	25        	94B4      	M_G_CPU0_SA_DQ<12>  
          	               	26        	94B1      	GND                 
          	               	27        	94B4      	M_G_CPU0_SA_DQ<13>  
          	               	28        	94B1      	GND                 
          	               	29        	94B4      	M_G_CPU0_SA_DQ<16>  
          	               	30        	94B1      	GND                 
          	               	31        	94B4      	M_G_CPU0_SA_DQ<17>  
          	               	32        	94B1      	GND                 
          	               	33        	94B2      	M_G_CPU0_SA_DQS_DP<2>
          	               	34        	94B2      	M_G_CPU0_SA_DQS_DN<2>
          	               	35        	94B1      	GND                 
          	               	36        	94B4      	M_G_CPU0_SA_DQ<20>  
          	               	37        	94B1      	GND                 
          	               	38        	94B4      	M_G_CPU0_SA_DQ<21>  
          	               	39        	94B1      	GND                 
          	               	40        	94B4      	M_G_CPU0_SA_DQ<24>  
          	               	41        	94B1      	GND                 
          	               	42        	94B4      	M_G_CPU0_SA_DQ<25>  
          	               	43        	94B1      	GND                 
          	               	44        	94B2      	M_G_CPU0_SA_DQS_DP<3>
          	               	45        	94B2      	M_G_CPU0_SA_DQS_DN<3>
          	               	46        	94B1      	GND                 
          	               	47        	94B4      	M_G_CPU0_SA_DQ<28>  
          	               	48        	94B1      	GND                 
          	               	49        	94B4      	M_G_CPU0_SA_DQ<29>  
          	               	50        	94B1      	GND                 
          	               	51        	94B4      	M_G_CPU0_SA_CB<0>   
          	               	52        	94B1      	GND                 
          	               	53        	94B4      	M_G_CPU0_SA_CB<1>   
          	               	54        	94B1      	GND                 
          	               	55        	94B2      	M_G_CPU0_SA_DQS_DP<4>
          	               	56        	94B2      	M_G_CPU0_SA_DQS_DN<4>
          	               	57        	94B1      	GND                 
          	               	58        	94B4      	M_G_CPU0_SA_CB<4>   
          	               	59        	94B1      	GND                 
          	               	60        	94B4      	M_G_CPU0_SA_CB<5>   
          	               	61        	94B1      	GND                 
          	               	62        	94B4      	M_G_CPU0_ALERT_N    
          	               	63        	94B1      	GND                 
          	               	64        	94B4      	M_G_CPU0_SA_CS_N<0> 
          	               	65        	94B1      	GND                 
          	               	66        	94B4      	M_G_CPU0_SA_CA<0>   
          	               	67        	94B1      	GND                 
          	               	68        	94B4      	M_G_CPU0_SA_CA<2>   
          	               	69        	94B1      	GND                 
          	               	70        	94B4      	M_G_CPU0_SA_CA<4>   
          	               	71        	94B1      	GND                 
          	               	72        	94B4      	M_G_CPU0_SA_CA<6>   
          	               	73        	94B1      	GND                 
          	               	74        	94B4      	M_G_CPU0_SA_PAR     
          	               	75        	94B1      	GND                 
          	               	76        	94B4      	M_G_CPU0_SB_CA<0>   
          	               	77        	94B1      	GND                 
          	               	78        	94B4      	M_G_CPU0_SB_CA<2>   
          	               	79        	94B1      	GND                 
          	               	80        	94B4      	M_G_CPU0_SB_CA<4>   
          	               	81        	94B1      	GND                 
          	               	82        	94B4      	M_G_CPU0_SB_CA<6>   
          	               	83        	94B1      	GND                 
          	               	84        	94B4      	M_G_CPU0_SB_CS_N<0> 
          	               	85        	94B1      	GND                 
          	               	86        	94A4      	M_G_CPU0_SA_RSP<0>  
          	               	87        	94A4      	M_G_CPU0_SB_RSP<0>  
          	               	88        	94B1      	GND                 
          	               	89        	94B4      	M_G_CPU0_SB_CB<4>   
          	               	90        	94B1      	GND                 
          	               	91        	94B4      	M_G_CPU0_SB_CB<5>   
          	               	92        	94B1      	GND                 
          	               	93        	94B2      	M_G_CPU0_SB_DQS_DP<9>
          	               	94        	94B2      	M_G_CPU0_SB_DQS_DN<9>
          	               	95        	94B1      	GND                 
          	               	96        	94B4      	M_G_CPU0_SB_CB<0>   
          	               	97        	94B1      	GND                 
          	               	98        	94B4      	M_G_CPU0_SB_CB<1>   
          	               	99        	94B1      	GND                 
          	               	100       	94B4      	M_G_CPU0_SB_DQ<0>   
          	               	101       	94B1      	GND                 
          	               	102       	94B4      	M_G_CPU0_SB_DQ<1>   
          	               	103       	94B1      	GND                 
          	               	104       	94B2      	M_G_CPU0_SB_DQS_DP<0>
          	               	105       	94B2      	M_G_CPU0_SB_DQS_DN<0>
          	               	106       	94B1      	GND                 
          	               	107       	94B4      	M_G_CPU0_SB_DQ<4>   
          	               	108       	94B1      	GND                 
          	               	109       	94B4      	M_G_CPU0_SB_DQ<5>   
          	               	110       	94B1      	GND                 
          	               	111       	94B4      	M_G_CPU0_SB_DQ<8>   
          	               	112       	94B1      	GND                 
          	               	113       	94B4      	M_G_CPU0_SB_DQ<9>   
          	               	114       	94B1      	GND                 
          	               	115       	94B2      	M_G_CPU0_SB_DQS_DP<1>
          	               	116       	94B2      	M_G_CPU0_SB_DQS_DN<1>
          	               	117       	94B1      	GND                 
          	               	118       	94B4      	M_G_CPU0_SB_DQ<12>  
          	               	119       	94B1      	GND                 
          	               	120       	94B4      	M_G_CPU0_SB_DQ<13>  
          	               	121       	94B1      	GND                 
          	               	122       	94B4      	M_G_CPU0_SB_DQ<16>  
          	               	123       	94B1      	GND                 
          	               	124       	94B4      	M_G_CPU0_SB_DQ<17>  
          	               	125       	94B1      	GND                 
          	               	126       	94B2      	M_G_CPU0_SB_DQS_DP<2>
          	               	127       	94B2      	M_G_CPU0_SB_DQS_DN<2>
          	               	128       	94B1      	GND                 
          	               	129       	94B4      	M_G_CPU0_SB_DQ<20>  
          	               	130       	94B1      	GND                 
          	               	131       	94B4      	M_G_CPU0_SB_DQ<21>  
          	               	132       	94B1      	GND                 
          	               	133       	94B4      	M_G_CPU0_SB_DQ<24>  
          	               	134       	94B1      	GND                 
          	               	135       	94B4      	M_G_CPU0_SB_DQ<25>  
          	               	136       	94B1      	GND                 
          	               	137       	94B2      	M_G_CPU0_SB_DQS_DP<3>
          	               	138       	94B2      	M_G_CPU0_SB_DQS_DN<3>
          	               	139       	94B1      	GND                 
          	               	140       	94B4      	M_G_CPU0_SB_DQ<28>  
          	               	141       	94B1      	GND                 
          	               	142       	94B4      	M_G_CPU0_SB_DQ<29>  
          	               	143       	94B1      	GND                 
          	               	144       	94B4      	TP_CHG_CPU0_DIMM1_FRU_1
          	               	145       	94B1      	P12V_S3_AUX_CPU0_NVDIMM
          	               	146       	94B1      	P12V_S3_AUX_CPU0_NVDIMM
          	               	147       	94B4      	PWRGD_CHG_CPU0_DIMM1
          	               	148       	94B4      	PD_CHG_CPU0_DIMM1_SAA
          	               	149       	94B4      	TP_CHG_CPU0_DIMM1_FRU_2
          	               	150       	94B4      	TP_CHG_CPU0_DIMM1_FRU_3
          	               	151       	94B1      	GND                 
          	               	152       	94B4      	M_G_CPU0_SA_DQ<2>   
          	               	153       	94B1      	GND                 
          	               	154       	94B4      	M_G_CPU0_SA_DQ<3>   
          	               	155       	94B1      	GND                 
          	               	156       	94B2      	M_G_CPU0_SA_DQS_DN<5>
          	               	157       	94B2      	M_G_CPU0_SA_DQS_DP<5>
          	               	158       	94B1      	GND                 
          	               	159       	94B4      	M_G_CPU0_SA_DQ<6>   
          	               	160       	94B1      	GND                 
          	               	161       	94B4      	M_G_CPU0_SA_DQ<7>   
          	               	162       	94B1      	GND                 
          	               	163       	94B4      	M_G_CPU0_SA_DQ<10>  
          	               	164       	94B1      	GND                 
          	               	165       	94B4      	M_G_CPU0_SA_DQ<11>  
          	               	166       	94B1      	GND                 
          	               	167       	94B2      	M_G_CPU0_SA_DQS_DN<6>
          	               	168       	94B2      	M_G_CPU0_SA_DQS_DP<6>
          	               	169       	94B1      	GND                 
          	               	170       	94B4      	M_G_CPU0_SA_DQ<14>  
          	               	171       	94B1      	GND                 
          	               	172       	94B4      	M_G_CPU0_SA_DQ<15>  
          	               	173       	94B1      	GND                 
          	               	174       	94B4      	M_G_CPU0_SA_DQ<18>  
          	               	175       	94B1      	GND                 
          	               	176       	94B4      	M_G_CPU0_SA_DQ<19>  
          	               	177       	94B1      	GND                 
          	               	178       	94B2      	M_G_CPU0_SA_DQS_DN<7>
          	               	179       	94B2      	M_G_CPU0_SA_DQS_DP<7>
          	               	180       	94B1      	GND                 
          	               	181       	94B4      	M_G_CPU0_SA_DQ<22>  
          	               	182       	94B1      	GND                 
          	               	183       	94B4      	M_G_CPU0_SA_DQ<23>  
          	               	184       	94B1      	GND                 
          	               	185       	94B4      	M_G_CPU0_SA_DQ<26>  
          	               	186       	94B1      	GND                 
          	               	187       	94B4      	M_G_CPU0_SA_DQ<27>  
          	               	188       	94B1      	GND                 
          	               	189       	94B2      	M_G_CPU0_SA_DQS_DN<8>
          	               	190       	94B2      	M_G_CPU0_SA_DQS_DP<8>
          	               	191       	94B1      	GND                 
          	               	192       	94B4      	M_G_CPU0_SA_DQ<30>  
          	               	193       	94B1      	GND                 
          	               	194       	94B4      	M_G_CPU0_SA_DQ<31>  
          	               	195       	94B1      	GND                 
          	               	196       	94B4      	M_G_CPU0_SA_CB<2>   
          	               	197       	94B1      	GND                 
          	               	198       	94B4      	M_G_CPU0_SA_CB<3>   
          	               	199       	94B1      	GND                 
          	               	200       	94B2      	M_G_CPU0_SA_DQS_DN<9>
          	               	201       	94B2      	M_G_CPU0_SA_DQS_DP<9>
          	               	202       	94B1      	GND                 
          	               	203       	94B4      	M_G_CPU0_SA_CB<6>   
          	               	204       	94B1      	GND                 
          	               	205       	94B4      	M_G_CPU0_SA_CB<7>   
          	               	206       	94B1      	GND                 
          	               	207       	94B4      	RST_M_GH_CPU0_FPGA_N
          	               	208       	94B1      	GND                 
          	               	209       	94B4      	M_G_CPU0_SA_CS_N<1> 
          	               	210       	94B1      	GND                 
          	               	211       	94B4      	M_G_CPU0_SA_CA<1>   
          	               	212       	94B1      	GND                 
          	               	213       	94B4      	M_G_CPU0_SA_CA<3>   
          	               	214       	94B1      	GND                 
          	               	215       	94B4      	M_G_CPU0_SA_CA<5>   
          	               	216       	94B1      	GND                 
          	               	217       	94B4      	M_G_CPU0_CLK_DP<0>  
          	               	218       	94B4      	M_G_CPU0_CLK_DN<0>  
          	               	219       	94B1      	GND                 
          	               	220       	94B4      	TP_CHG_CPU0_DIMM1_FRU_4
          	               	221       	94B4      	M_G_CPU0_SB_CA<1>   
          	               	222       	94B1      	GND                 
          	               	223       	94B4      	M_G_CPU0_SB_CA<3>   
          	               	224       	94B1      	GND                 
          	               	225       	94B4      	M_G_CPU0_SB_CA<5>   
          	               	226       	94B1      	GND                 
          	               	227       	94B4      	M_G_CPU0_SB_PAR     
          	               	228       	94B1      	GND                 
          	               	229       	94B4      	M_G_CPU0_SB_CS_N<1> 
          	               	230       	94B1      	GND                 
          	               	231       	94B4      	TP_CHG_CPU0_DIMM1_FRU_5
          	               	232       	94B4      	TP_CHG_CPU0_DIMM1_FRU_6
          	               	233       	94B1      	GND                 
          	               	234       	94B4      	M_G_CPU0_SB_CB<6>   
          	               	235       	94B1      	GND                 
          	               	236       	94B4      	M_G_CPU0_SB_CB<7>   
          	               	237       	94B1      	GND                 
          	               	238       	94B2      	M_G_CPU0_SB_DQS_DN<4>
          	               	239       	94B2      	M_G_CPU0_SB_DQS_DP<4>
          	               	240       	94B1      	GND                 
          	               	241       	94B4      	M_G_CPU0_SB_CB<2>   
          	               	242       	94B1      	GND                 
          	               	243       	94B4      	M_G_CPU0_SB_CB<3>   
          	               	244       	94B1      	GND                 
          	               	245       	94B4      	M_G_CPU0_SB_DQ<2>   
          	               	246       	94B1      	GND                 
          	               	247       	94B4      	M_G_CPU0_SB_DQ<3>   
          	               	248       	94B1      	GND                 
          	               	249       	94B2      	M_G_CPU0_SB_DQS_DN<5>
          	               	250       	94B2      	M_G_CPU0_SB_DQS_DP<5>
          	               	251       	94B1      	GND                 
          	               	252       	94B4      	M_G_CPU0_SB_DQ<6>   
          	               	253       	94B1      	GND                 
          	               	254       	94B4      	M_G_CPU0_SB_DQ<7>   
          	               	255       	94B1      	GND                 
          	               	256       	94B4      	M_G_CPU0_SB_DQ<10>  
          	               	257       	94B1      	GND                 
          	               	258       	94B4      	M_G_CPU0_SB_DQ<11>  
          	               	259       	94B1      	GND                 
          	               	260       	94B2      	M_G_CPU0_SB_DQS_DN<6>
          	               	261       	94B2      	M_G_CPU0_SB_DQS_DP<6>
          	               	262       	94B1      	GND                 
          	               	263       	94B4      	M_G_CPU0_SB_DQ<14>  
          	               	264       	94B1      	GND                 
          	               	265       	94B4      	M_G_CPU0_SB_DQ<15>  
          	               	266       	94B1      	GND                 
          	               	267       	94B4      	M_G_CPU0_SB_DQ<18>  
          	               	268       	94B1      	GND                 
          	               	269       	94B4      	M_G_CPU0_SB_DQ<19>  
          	               	270       	94B1      	GND                 
          	               	271       	94B2      	M_G_CPU0_SB_DQS_DN<7>
          	               	272       	94B2      	M_G_CPU0_SB_DQS_DP<7>
          	               	273       	94B1      	GND                 
          	               	274       	94B4      	M_G_CPU0_SB_DQ<22>  
          	               	275       	94B1      	GND                 
          	               	276       	94B4      	M_G_CPU0_SB_DQ<23>  
          	               	277       	94B1      	GND                 
          	               	278       	94B4      	M_G_CPU0_SB_DQ<26>  
          	               	279       	94B1      	GND                 
          	               	280       	94B4      	M_G_CPU0_SB_DQ<27>  
          	               	281       	94B1      	GND                 
          	               	282       	94B2      	M_G_CPU0_SB_DQS_DN<8>
          	               	283       	94B2      	M_G_CPU0_SB_DQS_DP<8>
          	               	284       	94B1      	GND                 
          	               	285       	94B4      	M_G_CPU0_SB_DQ<30>  
          	               	286       	94B1      	GND                 
          	               	287       	94B4      	M_G_CPU0_SB_DQ<31>  
          	               	288       	94B1      	GND                 
          	               	G1        	94B1      	GND                 
          	               	G2        	94A1      	GND                 
          	               	G3        	94A1      	GND                 

J14       	SCONN288_ADR50017P087CC	          	          	                    
          	               	1         	95B1      	P12V_S3_AUX_CPU0_NVDIMM
          	               	2         	95B4      	TP_CHG_CPU0_DIMM2_FRU_0
          	               	3         	95B4      	P3V3_AUX            
          	               	4         	95B4      	I3C_SPD_DDREFGH_CPU0_LVC1_SCL_5
          	               	5         	95B4      	I3C_SPD_DDREFGH_CPU0_LVC1_SDA
          	               	6         	95B1      	GND                 
          	               	7         	95B4      	M_G_CPU0_SA_DQ<0>   
          	               	8         	95B1      	GND                 
          	               	9         	95B4      	M_G_CPU0_SA_DQ<1>   
          	               	10        	95B1      	GND                 
          	               	11        	95B2      	M_G_CPU0_SA_DQS_DP<0>
          	               	12        	95B2      	M_G_CPU0_SA_DQS_DN<0>
          	               	13        	95B1      	GND                 
          	               	14        	95B4      	M_G_CPU0_SA_DQ<4>   
          	               	15        	95B1      	GND                 
          	               	16        	95B4      	M_G_CPU0_SA_DQ<5>   
          	               	17        	95B1      	GND                 
          	               	18        	95B4      	M_G_CPU0_SA_DQ<8>   
          	               	19        	95B1      	GND                 
          	               	20        	95B4      	M_G_CPU0_SA_DQ<9>   
          	               	21        	95B1      	GND                 
          	               	22        	95B2      	M_G_CPU0_SA_DQS_DP<1>
          	               	23        	95B2      	M_G_CPU0_SA_DQS_DN<1>
          	               	24        	95B1      	GND                 
          	               	25        	95B4      	M_G_CPU0_SA_DQ<12>  
          	               	26        	95B1      	GND                 
          	               	27        	95B4      	M_G_CPU0_SA_DQ<13>  
          	               	28        	95B1      	GND                 
          	               	29        	95B4      	M_G_CPU0_SA_DQ<16>  
          	               	30        	95B1      	GND                 
          	               	31        	95B4      	M_G_CPU0_SA_DQ<17>  
          	               	32        	95B1      	GND                 
          	               	33        	95B2      	M_G_CPU0_SA_DQS_DP<2>
          	               	34        	95B2      	M_G_CPU0_SA_DQS_DN<2>
          	               	35        	95B1      	GND                 
          	               	36        	95B4      	M_G_CPU0_SA_DQ<20>  
          	               	37        	95B1      	GND                 
          	               	38        	95B4      	M_G_CPU0_SA_DQ<21>  
          	               	39        	95B1      	GND                 
          	               	40        	95B4      	M_G_CPU0_SA_DQ<24>  
          	               	41        	95B1      	GND                 
          	               	42        	95B4      	M_G_CPU0_SA_DQ<25>  
          	               	43        	95B1      	GND                 
          	               	44        	95B2      	M_G_CPU0_SA_DQS_DP<3>
          	               	45        	95B2      	M_G_CPU0_SA_DQS_DN<3>
          	               	46        	95B1      	GND                 
          	               	47        	95B4      	M_G_CPU0_SA_DQ<28>  
          	               	48        	95B1      	GND                 
          	               	49        	95B4      	M_G_CPU0_SA_DQ<29>  
          	               	50        	95B1      	GND                 
          	               	51        	95B4      	M_G_CPU0_SA_CB<0>   
          	               	52        	95B1      	GND                 
          	               	53        	95B4      	M_G_CPU0_SA_CB<1>   
          	               	54        	95B1      	GND                 
          	               	55        	95B2      	M_G_CPU0_SA_DQS_DP<4>
          	               	56        	95B2      	M_G_CPU0_SA_DQS_DN<4>
          	               	57        	95B1      	GND                 
          	               	58        	95B4      	M_G_CPU0_SA_CB<4>   
          	               	59        	95B1      	GND                 
          	               	60        	95B4      	M_G_CPU0_SA_CB<5>   
          	               	61        	95B1      	GND                 
          	               	62        	95B4      	M_G_CPU0_ALERT_N    
          	               	63        	95B1      	GND                 
          	               	64        	95B4      	M_G_CPU0_SA_CS_N<2> 
          	               	65        	95B1      	GND                 
          	               	66        	95B4      	M_G_CPU0_SA_CA<0>   
          	               	67        	95B1      	GND                 
          	               	68        	95B4      	M_G_CPU0_SA_CA<2>   
          	               	69        	95B1      	GND                 
          	               	70        	95B4      	M_G_CPU0_SA_CA<4>   
          	               	71        	95B1      	GND                 
          	               	72        	95B4      	M_G_CPU0_SA_CA<6>   
          	               	73        	95B1      	GND                 
          	               	74        	95B4      	M_G_CPU0_SA_PAR     
          	               	75        	95B1      	GND                 
          	               	76        	95B4      	M_G_CPU0_SB_CA<0>   
          	               	77        	95B1      	GND                 
          	               	78        	95B4      	M_G_CPU0_SB_CA<2>   
          	               	79        	95B1      	GND                 
          	               	80        	95B4      	M_G_CPU0_SB_CA<4>   
          	               	81        	95B1      	GND                 
          	               	82        	95B4      	M_G_CPU0_SB_CA<6>   
          	               	83        	95B1      	GND                 
          	               	84        	95B4      	M_G_CPU0_SB_CS_N<2> 
          	               	85        	95B1      	GND                 
          	               	86        	95A4      	M_G_CPU0_SA_RSP<1>  
          	               	87        	95A4      	M_G_CPU0_SB_RSP<1>  
          	               	88        	95B1      	GND                 
          	               	89        	95B4      	M_G_CPU0_SB_CB<4>   
          	               	90        	95B1      	GND                 
          	               	91        	95B4      	M_G_CPU0_SB_CB<5>   
          	               	92        	95B1      	GND                 
          	               	93        	95B2      	M_G_CPU0_SB_DQS_DP<9>
          	               	94        	95B2      	M_G_CPU0_SB_DQS_DN<9>
          	               	95        	95B1      	GND                 
          	               	96        	95B4      	M_G_CPU0_SB_CB<0>   
          	               	97        	95B1      	GND                 
          	               	98        	95B4      	M_G_CPU0_SB_CB<1>   
          	               	99        	95B1      	GND                 
          	               	100       	95B4      	M_G_CPU0_SB_DQ<0>   
          	               	101       	95B1      	GND                 
          	               	102       	95B4      	M_G_CPU0_SB_DQ<1>   
          	               	103       	95B1      	GND                 
          	               	104       	95B2      	M_G_CPU0_SB_DQS_DP<0>
          	               	105       	95B2      	M_G_CPU0_SB_DQS_DN<0>
          	               	106       	95B1      	GND                 
          	               	107       	95B4      	M_G_CPU0_SB_DQ<4>   
          	               	108       	95B1      	GND                 
          	               	109       	95B4      	M_G_CPU0_SB_DQ<5>   
          	               	110       	95B1      	GND                 
          	               	111       	95B4      	M_G_CPU0_SB_DQ<8>   
          	               	112       	95B1      	GND                 
          	               	113       	95B4      	M_G_CPU0_SB_DQ<9>   
          	               	114       	95B1      	GND                 
          	               	115       	95B2      	M_G_CPU0_SB_DQS_DP<1>
          	               	116       	95B2      	M_G_CPU0_SB_DQS_DN<1>
          	               	117       	95B1      	GND                 
          	               	118       	95B4      	M_G_CPU0_SB_DQ<12>  
          	               	119       	95B1      	GND                 
          	               	120       	95B4      	M_G_CPU0_SB_DQ<13>  
          	               	121       	95B1      	GND                 
          	               	122       	95B4      	M_G_CPU0_SB_DQ<16>  
          	               	123       	95B1      	GND                 
          	               	124       	95B4      	M_G_CPU0_SB_DQ<17>  
          	               	125       	95B1      	GND                 
          	               	126       	95B2      	M_G_CPU0_SB_DQS_DP<2>
          	               	127       	95B2      	M_G_CPU0_SB_DQS_DN<2>
          	               	128       	95B1      	GND                 
          	               	129       	95B4      	M_G_CPU0_SB_DQ<20>  
          	               	130       	95B1      	GND                 
          	               	131       	95B4      	M_G_CPU0_SB_DQ<21>  
          	               	132       	95B1      	GND                 
          	               	133       	95B4      	M_G_CPU0_SB_DQ<24>  
          	               	134       	95B1      	GND                 
          	               	135       	95B4      	M_G_CPU0_SB_DQ<25>  
          	               	136       	95B1      	GND                 
          	               	137       	95B2      	M_G_CPU0_SB_DQS_DP<3>
          	               	138       	95B2      	M_G_CPU0_SB_DQS_DN<3>
          	               	139       	95B1      	GND                 
          	               	140       	95B4      	M_G_CPU0_SB_DQ<28>  
          	               	141       	95B1      	GND                 
          	               	142       	95B4      	M_G_CPU0_SB_DQ<29>  
          	               	143       	95B1      	GND                 
          	               	144       	95B4      	TP_CHG_CPU0_DIMM2_FRU_1
          	               	145       	95B1      	P12V_S3_AUX_CPU0_NVDIMM
          	               	146       	95B1      	P12V_S3_AUX_CPU0_NVDIMM
          	               	147       	95B4      	PWRGD_CHG_CPU0_DIMM2
          	               	148       	95B4      	PD_CHG_CPU0_DIMM2_SAA
          	               	149       	95B4      	TP_CHG_CPU0_DIMM2_FRU_2
          	               	150       	95B4      	TP_CHG_CPU0_DIMM2_FRU_3
          	               	151       	95B1      	GND                 
          	               	152       	95B4      	M_G_CPU0_SA_DQ<2>   
          	               	153       	95B1      	GND                 
          	               	154       	95B4      	M_G_CPU0_SA_DQ<3>   
          	               	155       	95B1      	GND                 
          	               	156       	95B2      	M_G_CPU0_SA_DQS_DN<5>
          	               	157       	95B2      	M_G_CPU0_SA_DQS_DP<5>
          	               	158       	95B1      	GND                 
          	               	159       	95B4      	M_G_CPU0_SA_DQ<6>   
          	               	160       	95B1      	GND                 
          	               	161       	95B4      	M_G_CPU0_SA_DQ<7>   
          	               	162       	95B1      	GND                 
          	               	163       	95B4      	M_G_CPU0_SA_DQ<10>  
          	               	164       	95B1      	GND                 
          	               	165       	95B4      	M_G_CPU0_SA_DQ<11>  
          	               	166       	95B1      	GND                 
          	               	167       	95B2      	M_G_CPU0_SA_DQS_DN<6>
          	               	168       	95B2      	M_G_CPU0_SA_DQS_DP<6>
          	               	169       	95B1      	GND                 
          	               	170       	95B4      	M_G_CPU0_SA_DQ<14>  
          	               	171       	95B1      	GND                 
          	               	172       	95B4      	M_G_CPU0_SA_DQ<15>  
          	               	173       	95B1      	GND                 
          	               	174       	95B4      	M_G_CPU0_SA_DQ<18>  
          	               	175       	95B1      	GND                 
          	               	176       	95B4      	M_G_CPU0_SA_DQ<19>  
          	               	177       	95B1      	GND                 
          	               	178       	95B2      	M_G_CPU0_SA_DQS_DN<7>
          	               	179       	95B2      	M_G_CPU0_SA_DQS_DP<7>
          	               	180       	95B1      	GND                 
          	               	181       	95B4      	M_G_CPU0_SA_DQ<22>  
          	               	182       	95B1      	GND                 
          	               	183       	95B4      	M_G_CPU0_SA_DQ<23>  
          	               	184       	95B1      	GND                 
          	               	185       	95B4      	M_G_CPU0_SA_DQ<26>  
          	               	186       	95B1      	GND                 
          	               	187       	95B4      	M_G_CPU0_SA_DQ<27>  
          	               	188       	95B1      	GND                 
          	               	189       	95B2      	M_G_CPU0_SA_DQS_DN<8>
          	               	190       	95B2      	M_G_CPU0_SA_DQS_DP<8>
          	               	191       	95B1      	GND                 
          	               	192       	95B4      	M_G_CPU0_SA_DQ<30>  
          	               	193       	95B1      	GND                 
          	               	194       	95B4      	M_G_CPU0_SA_DQ<31>  
          	               	195       	95B1      	GND                 
          	               	196       	95B4      	M_G_CPU0_SA_CB<2>   
          	               	197       	95B1      	GND                 
          	               	198       	95B4      	M_G_CPU0_SA_CB<3>   
          	               	199       	95B1      	GND                 
          	               	200       	95B2      	M_G_CPU0_SA_DQS_DN<9>
          	               	201       	95B2      	M_G_CPU0_SA_DQS_DP<9>
          	               	202       	95B1      	GND                 
          	               	203       	95B4      	M_G_CPU0_SA_CB<6>   
          	               	204       	95B1      	GND                 
          	               	205       	95B4      	M_G_CPU0_SA_CB<7>   
          	               	206       	95B1      	GND                 
          	               	207       	95B4      	RST_M_GH_CPU0_FPGA_N
          	               	208       	95B1      	GND                 
          	               	209       	95B4      	M_G_CPU0_SA_CS_N<3> 
          	               	210       	95B1      	GND                 
          	               	211       	95B4      	M_G_CPU0_SA_CA<1>   
          	               	212       	95B1      	GND                 
          	               	213       	95B4      	M_G_CPU0_SA_CA<3>   
          	               	214       	95B1      	GND                 
          	               	215       	95B4      	M_G_CPU0_SA_CA<5>   
          	               	216       	95B1      	GND                 
          	               	217       	95B4      	M_G_CPU0_CLK_DP<1>  
          	               	218       	95B4      	M_G_CPU0_CLK_DN<1>  
          	               	219       	95B1      	GND                 
          	               	220       	95B4      	TP_CHG_CPU0_DIMM2_FRU_4
          	               	221       	95B4      	M_G_CPU0_SB_CA<1>   
          	               	222       	95B1      	GND                 
          	               	223       	95B4      	M_G_CPU0_SB_CA<3>   
          	               	224       	95B1      	GND                 
          	               	225       	95B4      	M_G_CPU0_SB_CA<5>   
          	               	226       	95B1      	GND                 
          	               	227       	95B4      	M_G_CPU0_SB_PAR     
          	               	228       	95B1      	GND                 
          	               	229       	95B4      	M_G_CPU0_SB_CS_N<3> 
          	               	230       	95B1      	GND                 
          	               	231       	95B4      	TP_CHG_CPU0_DIMM2_FRU_5
          	               	232       	95B4      	TP_CHG_CPU0_DIMM2_FRU_6
          	               	233       	95B1      	GND                 
          	               	234       	95B4      	M_G_CPU0_SB_CB<6>   
          	               	235       	95B1      	GND                 
          	               	236       	95B4      	M_G_CPU0_SB_CB<7>   
          	               	237       	95B1      	GND                 
          	               	238       	95B2      	M_G_CPU0_SB_DQS_DN<4>
          	               	239       	95B2      	M_G_CPU0_SB_DQS_DP<4>
          	               	240       	95B1      	GND                 
          	               	241       	95B4      	M_G_CPU0_SB_CB<2>   
          	               	242       	95B1      	GND                 
          	               	243       	95B4      	M_G_CPU0_SB_CB<3>   
          	               	244       	95B1      	GND                 
          	               	245       	95B4      	M_G_CPU0_SB_DQ<2>   
          	               	246       	95B1      	GND                 
          	               	247       	95B4      	M_G_CPU0_SB_DQ<3>   
          	               	248       	95B1      	GND                 
          	               	249       	95B2      	M_G_CPU0_SB_DQS_DN<5>
          	               	250       	95B2      	M_G_CPU0_SB_DQS_DP<5>
          	               	251       	95B1      	GND                 
          	               	252       	95B4      	M_G_CPU0_SB_DQ<6>   
          	               	253       	95B1      	GND                 
          	               	254       	95B4      	M_G_CPU0_SB_DQ<7>   
          	               	255       	95B1      	GND                 
          	               	256       	95B4      	M_G_CPU0_SB_DQ<10>  
          	               	257       	95B1      	GND                 
          	               	258       	95B4      	M_G_CPU0_SB_DQ<11>  
          	               	259       	95B1      	GND                 
          	               	260       	95B2      	M_G_CPU0_SB_DQS_DN<6>
          	               	261       	95B2      	M_G_CPU0_SB_DQS_DP<6>
          	               	262       	95B1      	GND                 
          	               	263       	95B4      	M_G_CPU0_SB_DQ<14>  
          	               	264       	95B1      	GND                 
          	               	265       	95B4      	M_G_CPU0_SB_DQ<15>  
          	               	266       	95B1      	GND                 
          	               	267       	95B4      	M_G_CPU0_SB_DQ<18>  
          	               	268       	95B1      	GND                 
          	               	269       	95B4      	M_G_CPU0_SB_DQ<19>  
          	               	270       	95B1      	GND                 
          	               	271       	95B2      	M_G_CPU0_SB_DQS_DN<7>
          	               	272       	95B2      	M_G_CPU0_SB_DQS_DP<7>
          	               	273       	95B1      	GND                 
          	               	274       	95B4      	M_G_CPU0_SB_DQ<22>  
          	               	275       	95B1      	GND                 
          	               	276       	95B4      	M_G_CPU0_SB_DQ<23>  
          	               	277       	95B1      	GND                 
          	               	278       	95B4      	M_G_CPU0_SB_DQ<26>  
          	               	279       	95B1      	GND                 
          	               	280       	95B4      	M_G_CPU0_SB_DQ<27>  
          	               	281       	95B1      	GND                 
          	               	282       	95B2      	M_G_CPU0_SB_DQS_DN<8>
          	               	283       	95B2      	M_G_CPU0_SB_DQS_DP<8>
          	               	284       	95B1      	GND                 
          	               	285       	95B4      	M_G_CPU0_SB_DQ<30>  
          	               	286       	95B1      	GND                 
          	               	287       	95B4      	M_G_CPU0_SB_DQ<31>  
          	               	288       	95B1      	GND                 
          	               	G1        	95B1      	GND                 
          	               	G2        	95A1      	GND                 
          	               	G3        	95A1      	GND                 

J15       	SCONN288_ADR50017P130CC	          	          	                    
          	               	1         	96B1      	P12V_S3_AUX_CPU0_NVDIMM
          	               	2         	96B4      	TP_CHH_CPU0_DIMM1_FRU_0
          	               	3         	96B4      	P3V3_AUX            
          	               	4         	96B4      	I3C_SPD_DDREFGH_CPU0_LVC1_SCL_6
          	               	5         	96B4      	I3C_SPD_DDREFGH_CPU0_LVC1_SDA
          	               	6         	96B1      	GND                 
          	               	7         	96B4      	M_H_CPU0_SA_DQ<0>   
          	               	8         	96B1      	GND                 
          	               	9         	96B4      	M_H_CPU0_SA_DQ<1>   
          	               	10        	96B1      	GND                 
          	               	11        	96B2      	M_H_CPU0_SA_DQS_DP<0>
          	               	12        	96B2      	M_H_CPU0_SA_DQS_DN<0>
          	               	13        	96B1      	GND                 
          	               	14        	96B4      	M_H_CPU0_SA_DQ<4>   
          	               	15        	96B1      	GND                 
          	               	16        	96B4      	M_H_CPU0_SA_DQ<5>   
          	               	17        	96B1      	GND                 
          	               	18        	96B4      	M_H_CPU0_SA_DQ<8>   
          	               	19        	96B1      	GND                 
          	               	20        	96B4      	M_H_CPU0_SA_DQ<9>   
          	               	21        	96B1      	GND                 
          	               	22        	96B2      	M_H_CPU0_SA_DQS_DP<1>
          	               	23        	96B2      	M_H_CPU0_SA_DQS_DN<1>
          	               	24        	96B1      	GND                 
          	               	25        	96B4      	M_H_CPU0_SA_DQ<12>  
          	               	26        	96B1      	GND                 
          	               	27        	96B4      	M_H_CPU0_SA_DQ<13>  
          	               	28        	96B1      	GND                 
          	               	29        	96B4      	M_H_CPU0_SA_DQ<16>  
          	               	30        	96B1      	GND                 
          	               	31        	96B4      	M_H_CPU0_SA_DQ<17>  
          	               	32        	96B1      	GND                 
          	               	33        	96B2      	M_H_CPU0_SA_DQS_DP<2>
          	               	34        	96B2      	M_H_CPU0_SA_DQS_DN<2>
          	               	35        	96B1      	GND                 
          	               	36        	96B4      	M_H_CPU0_SA_DQ<20>  
          	               	37        	96B1      	GND                 
          	               	38        	96B4      	M_H_CPU0_SA_DQ<21>  
          	               	39        	96B1      	GND                 
          	               	40        	96B4      	M_H_CPU0_SA_DQ<24>  
          	               	41        	96B1      	GND                 
          	               	42        	96B4      	M_H_CPU0_SA_DQ<25>  
          	               	43        	96B1      	GND                 
          	               	44        	96B2      	M_H_CPU0_SA_DQS_DP<3>
          	               	45        	96B2      	M_H_CPU0_SA_DQS_DN<3>
          	               	46        	96B1      	GND                 
          	               	47        	96B4      	M_H_CPU0_SA_DQ<28>  
          	               	48        	96B1      	GND                 
          	               	49        	96B4      	M_H_CPU0_SA_DQ<29>  
          	               	50        	96B1      	GND                 
          	               	51        	96B4      	M_H_CPU0_SA_CB<0>   
          	               	52        	96B1      	GND                 
          	               	53        	96B4      	M_H_CPU0_SA_CB<1>   
          	               	54        	96B1      	GND                 
          	               	55        	96B2      	M_H_CPU0_SA_DQS_DP<4>
          	               	56        	96B2      	M_H_CPU0_SA_DQS_DN<4>
          	               	57        	96B1      	GND                 
          	               	58        	96B4      	M_H_CPU0_SA_CB<4>   
          	               	59        	96B1      	GND                 
          	               	60        	96B4      	M_H_CPU0_SA_CB<5>   
          	               	61        	96B1      	GND                 
          	               	62        	96B4      	M_H_CPU0_ALERT_N    
          	               	63        	96B1      	GND                 
          	               	64        	96B4      	M_H_CPU0_SA_CS_N<0> 
          	               	65        	96B1      	GND                 
          	               	66        	96B4      	M_H_CPU0_SA_CA<0>   
          	               	67        	96B1      	GND                 
          	               	68        	96B4      	M_H_CPU0_SA_CA<2>   
          	               	69        	96B1      	GND                 
          	               	70        	96B4      	M_H_CPU0_SA_CA<4>   
          	               	71        	96B1      	GND                 
          	               	72        	96B4      	M_H_CPU0_SA_CA<6>   
          	               	73        	96B1      	GND                 
          	               	74        	96B4      	M_H_CPU0_SA_PAR     
          	               	75        	96B1      	GND                 
          	               	76        	96B4      	M_H_CPU0_SB_CA<0>   
          	               	77        	96B1      	GND                 
          	               	78        	96B4      	M_H_CPU0_SB_CA<2>   
          	               	79        	96B1      	GND                 
          	               	80        	96B4      	M_H_CPU0_SB_CA<4>   
          	               	81        	96B1      	GND                 
          	               	82        	96B4      	M_H_CPU0_SB_CA<6>   
          	               	83        	96B1      	GND                 
          	               	84        	96B4      	M_H_CPU0_SB_CS_N<0> 
          	               	85        	96B1      	GND                 
          	               	86        	96A4      	M_H_CPU0_SA_RSP<0>  
          	               	87        	96A4      	M_H_CPU0_SB_RSP<0>  
          	               	88        	96B1      	GND                 
          	               	89        	96B4      	M_H_CPU0_SB_CB<4>   
          	               	90        	96B1      	GND                 
          	               	91        	96B4      	M_H_CPU0_SB_CB<5>   
          	               	92        	96B1      	GND                 
          	               	93        	96B2      	M_H_CPU0_SB_DQS_DP<9>
          	               	94        	96B2      	M_H_CPU0_SB_DQS_DN<9>
          	               	95        	96B1      	GND                 
          	               	96        	96B4      	M_H_CPU0_SB_CB<0>   
          	               	97        	96B1      	GND                 
          	               	98        	96B4      	M_H_CPU0_SB_CB<1>   
          	               	99        	96B1      	GND                 
          	               	100       	96B4      	M_H_CPU0_SB_DQ<0>   
          	               	101       	96B1      	GND                 
          	               	102       	96B4      	M_H_CPU0_SB_DQ<1>   
          	               	103       	96B1      	GND                 
          	               	104       	96B2      	M_H_CPU0_SB_DQS_DP<0>
          	               	105       	96B2      	M_H_CPU0_SB_DQS_DN<0>
          	               	106       	96B1      	GND                 
          	               	107       	96B4      	M_H_CPU0_SB_DQ<4>   
          	               	108       	96B1      	GND                 
          	               	109       	96B4      	M_H_CPU0_SB_DQ<5>   
          	               	110       	96B1      	GND                 
          	               	111       	96B4      	M_H_CPU0_SB_DQ<8>   
          	               	112       	96B1      	GND                 
          	               	113       	96B4      	M_H_CPU0_SB_DQ<9>   
          	               	114       	96B1      	GND                 
          	               	115       	96B2      	M_H_CPU0_SB_DQS_DP<1>
          	               	116       	96B2      	M_H_CPU0_SB_DQS_DN<1>
          	               	117       	96B1      	GND                 
          	               	118       	96B4      	M_H_CPU0_SB_DQ<12>  
          	               	119       	96B1      	GND                 
          	               	120       	96B4      	M_H_CPU0_SB_DQ<13>  
          	               	121       	96B1      	GND                 
          	               	122       	96B4      	M_H_CPU0_SB_DQ<16>  
          	               	123       	96B1      	GND                 
          	               	124       	96B4      	M_H_CPU0_SB_DQ<17>  
          	               	125       	96B1      	GND                 
          	               	126       	96B2      	M_H_CPU0_SB_DQS_DP<2>
          	               	127       	96B2      	M_H_CPU0_SB_DQS_DN<2>
          	               	128       	96B1      	GND                 
          	               	129       	96B4      	M_H_CPU0_SB_DQ<20>  
          	               	130       	96B1      	GND                 
          	               	131       	96B4      	M_H_CPU0_SB_DQ<21>  
          	               	132       	96B1      	GND                 
          	               	133       	96B4      	M_H_CPU0_SB_DQ<24>  
          	               	134       	96B1      	GND                 
          	               	135       	96B4      	M_H_CPU0_SB_DQ<25>  
          	               	136       	96B1      	GND                 
          	               	137       	96B2      	M_H_CPU0_SB_DQS_DP<3>
          	               	138       	96B2      	M_H_CPU0_SB_DQS_DN<3>
          	               	139       	96B1      	GND                 
          	               	140       	96B4      	M_H_CPU0_SB_DQ<28>  
          	               	141       	96B1      	GND                 
          	               	142       	96B4      	M_H_CPU0_SB_DQ<29>  
          	               	143       	96B1      	GND                 
          	               	144       	96B4      	TP_CHH_CPU0_DIMM1_FRU_1
          	               	145       	96B1      	P12V_S3_AUX_CPU0_NVDIMM
          	               	146       	96B1      	P12V_S3_AUX_CPU0_NVDIMM
          	               	147       	96B4      	PWRGD_CHH_CPU0_DIMM1
          	               	148       	96B4      	PD_CHH_CPU0_DIMM1_SAA
          	               	149       	96B4      	TP_CHH_CPU0_DIMM1_FRU_2
          	               	150       	96B4      	TP_CHH_CPU0_DIMM1_FRU_3
          	               	151       	96B1      	GND                 
          	               	152       	96B4      	M_H_CPU0_SA_DQ<2>   
          	               	153       	96B1      	GND                 
          	               	154       	96B4      	M_H_CPU0_SA_DQ<3>   
          	               	155       	96B1      	GND                 
          	               	156       	96B2      	M_H_CPU0_SA_DQS_DN<5>
          	               	157       	96B2      	M_H_CPU0_SA_DQS_DP<5>
          	               	158       	96B1      	GND                 
          	               	159       	96B4      	M_H_CPU0_SA_DQ<6>   
          	               	160       	96B1      	GND                 
          	               	161       	96B4      	M_H_CPU0_SA_DQ<7>   
          	               	162       	96B1      	GND                 
          	               	163       	96B4      	M_H_CPU0_SA_DQ<10>  
          	               	164       	96B1      	GND                 
          	               	165       	96B4      	M_H_CPU0_SA_DQ<11>  
          	               	166       	96B1      	GND                 
          	               	167       	96B2      	M_H_CPU0_SA_DQS_DN<6>
          	               	168       	96B2      	M_H_CPU0_SA_DQS_DP<6>
          	               	169       	96B1      	GND                 
          	               	170       	96B4      	M_H_CPU0_SA_DQ<14>  
          	               	171       	96B1      	GND                 
          	               	172       	96B4      	M_H_CPU0_SA_DQ<15>  
          	               	173       	96B1      	GND                 
          	               	174       	96B4      	M_H_CPU0_SA_DQ<18>  
          	               	175       	96B1      	GND                 
          	               	176       	96B4      	M_H_CPU0_SA_DQ<19>  
          	               	177       	96B1      	GND                 
          	               	178       	96B2      	M_H_CPU0_SA_DQS_DN<7>
          	               	179       	96B2      	M_H_CPU0_SA_DQS_DP<7>
          	               	180       	96B1      	GND                 
          	               	181       	96B4      	M_H_CPU0_SA_DQ<22>  
          	               	182       	96B1      	GND                 
          	               	183       	96B4      	M_H_CPU0_SA_DQ<23>  
          	               	184       	96B1      	GND                 
          	               	185       	96B4      	M_H_CPU0_SA_DQ<26>  
          	               	186       	96B1      	GND                 
          	               	187       	96B4      	M_H_CPU0_SA_DQ<27>  
          	               	188       	96B1      	GND                 
          	               	189       	96B2      	M_H_CPU0_SA_DQS_DN<8>
          	               	190       	96B2      	M_H_CPU0_SA_DQS_DP<8>
          	               	191       	96B1      	GND                 
          	               	192       	96B4      	M_H_CPU0_SA_DQ<30>  
          	               	193       	96B1      	GND                 
          	               	194       	96B4      	M_H_CPU0_SA_DQ<31>  
          	               	195       	96B1      	GND                 
          	               	196       	96B4      	M_H_CPU0_SA_CB<2>   
          	               	197       	96B1      	GND                 
          	               	198       	96B4      	M_H_CPU0_SA_CB<3>   
          	               	199       	96B1      	GND                 
          	               	200       	96B2      	M_H_CPU0_SA_DQS_DN<9>
          	               	201       	96B2      	M_H_CPU0_SA_DQS_DP<9>
          	               	202       	96B1      	GND                 
          	               	203       	96B4      	M_H_CPU0_SA_CB<6>   
          	               	204       	96B1      	GND                 
          	               	205       	96B4      	M_H_CPU0_SA_CB<7>   
          	               	206       	96B1      	GND                 
          	               	207       	96B4      	RST_M_GH_CPU0_FPGA_N
          	               	208       	96B1      	GND                 
          	               	209       	96B4      	M_H_CPU0_SA_CS_N<1> 
          	               	210       	96B1      	GND                 
          	               	211       	96B4      	M_H_CPU0_SA_CA<1>   
          	               	212       	96B1      	GND                 
          	               	213       	96B4      	M_H_CPU0_SA_CA<3>   
          	               	214       	96B1      	GND                 
          	               	215       	96B4      	M_H_CPU0_SA_CA<5>   
          	               	216       	96B1      	GND                 
          	               	217       	96B4      	M_H_CPU0_CLK_DP<0>  
          	               	218       	96B4      	M_H_CPU0_CLK_DN<0>  
          	               	219       	96B1      	GND                 
          	               	220       	96B4      	TP_CHH_CPU0_DIMM1_FRU_4
          	               	221       	96B4      	M_H_CPU0_SB_CA<1>   
          	               	222       	96B1      	GND                 
          	               	223       	96B4      	M_H_CPU0_SB_CA<3>   
          	               	224       	96B1      	GND                 
          	               	225       	96B4      	M_H_CPU0_SB_CA<5>   
          	               	226       	96B1      	GND                 
          	               	227       	96B4      	M_H_CPU0_SB_PAR     
          	               	228       	96B1      	GND                 
          	               	229       	96B4      	M_H_CPU0_SB_CS_N<1> 
          	               	230       	96B1      	GND                 
          	               	231       	96B4      	TP_CHH_CPU0_DIMM1_FRU_5
          	               	232       	96B4      	TP_CHH_CPU0_DIMM1_FRU_6
          	               	233       	96B1      	GND                 
          	               	234       	96B4      	M_H_CPU0_SB_CB<6>   
          	               	235       	96B1      	GND                 
          	               	236       	96B4      	M_H_CPU0_SB_CB<7>   
          	               	237       	96B1      	GND                 
          	               	238       	96B2      	M_H_CPU0_SB_DQS_DN<4>
          	               	239       	96B2      	M_H_CPU0_SB_DQS_DP<4>
          	               	240       	96B1      	GND                 
          	               	241       	96B4      	M_H_CPU0_SB_CB<2>   
          	               	242       	96B1      	GND                 
          	               	243       	96B4      	M_H_CPU0_SB_CB<3>   
          	               	244       	96B1      	GND                 
          	               	245       	96B4      	M_H_CPU0_SB_DQ<2>   
          	               	246       	96B1      	GND                 
          	               	247       	96B4      	M_H_CPU0_SB_DQ<3>   
          	               	248       	96B1      	GND                 
          	               	249       	96B2      	M_H_CPU0_SB_DQS_DN<5>
          	               	250       	96B2      	M_H_CPU0_SB_DQS_DP<5>
          	               	251       	96B1      	GND                 
          	               	252       	96B4      	M_H_CPU0_SB_DQ<6>   
          	               	253       	96B1      	GND                 
          	               	254       	96B4      	M_H_CPU0_SB_DQ<7>   
          	               	255       	96B1      	GND                 
          	               	256       	96B4      	M_H_CPU0_SB_DQ<10>  
          	               	257       	96B1      	GND                 
          	               	258       	96B4      	M_H_CPU0_SB_DQ<11>  
          	               	259       	96B1      	GND                 
          	               	260       	96B2      	M_H_CPU0_SB_DQS_DN<6>
          	               	261       	96B2      	M_H_CPU0_SB_DQS_DP<6>
          	               	262       	96B1      	GND                 
          	               	263       	96B4      	M_H_CPU0_SB_DQ<14>  
          	               	264       	96B1      	GND                 
          	               	265       	96B4      	M_H_CPU0_SB_DQ<15>  
          	               	266       	96B1      	GND                 
          	               	267       	96B4      	M_H_CPU0_SB_DQ<18>  
          	               	268       	96B1      	GND                 
          	               	269       	96B4      	M_H_CPU0_SB_DQ<19>  
          	               	270       	96B1      	GND                 
          	               	271       	96B2      	M_H_CPU0_SB_DQS_DN<7>
          	               	272       	96B2      	M_H_CPU0_SB_DQS_DP<7>
          	               	273       	96B1      	GND                 
          	               	274       	96B4      	M_H_CPU0_SB_DQ<22>  
          	               	275       	96B1      	GND                 
          	               	276       	96B4      	M_H_CPU0_SB_DQ<23>  
          	               	277       	96B1      	GND                 
          	               	278       	96B4      	M_H_CPU0_SB_DQ<26>  
          	               	279       	96B1      	GND                 
          	               	280       	96B4      	M_H_CPU0_SB_DQ<27>  
          	               	281       	96B1      	GND                 
          	               	282       	96B2      	M_H_CPU0_SB_DQS_DN<8>
          	               	283       	96B2      	M_H_CPU0_SB_DQS_DP<8>
          	               	284       	96B1      	GND                 
          	               	285       	96B4      	M_H_CPU0_SB_DQ<30>  
          	               	286       	96B1      	GND                 
          	               	287       	96B4      	M_H_CPU0_SB_DQ<31>  
          	               	288       	96B1      	GND                 
          	               	G1        	96B1      	GND                 
          	               	G2        	96A1      	GND                 
          	               	G3        	96A1      	GND                 

J16       	SCONN288_ADR50017P087CC	          	          	                    
          	               	1         	97B1      	P12V_S3_AUX_CPU0_NVDIMM
          	               	2         	97A4      	TP_CHH_CPU0_DIMM2_FRU_0
          	               	3         	97B4      	P3V3_AUX            
          	               	4         	97B4      	I3C_SPD_DDREFGH_CPU0_LVC1_SCL_7
          	               	5         	97B4      	I3C_SPD_DDREFGH_CPU0_LVC1_SDA
          	               	6         	97B1      	GND                 
          	               	7         	97B4      	M_H_CPU0_SA_DQ<0>   
          	               	8         	97B1      	GND                 
          	               	9         	97B4      	M_H_CPU0_SA_DQ<1>   
          	               	10        	97B1      	GND                 
          	               	11        	97B2      	M_H_CPU0_SA_DQS_DP<0>
          	               	12        	97B2      	M_H_CPU0_SA_DQS_DN<0>
          	               	13        	97B1      	GND                 
          	               	14        	97B4      	M_H_CPU0_SA_DQ<4>   
          	               	15        	97B1      	GND                 
          	               	16        	97B4      	M_H_CPU0_SA_DQ<5>   
          	               	17        	97B1      	GND                 
          	               	18        	97B4      	M_H_CPU0_SA_DQ<8>   
          	               	19        	97B1      	GND                 
          	               	20        	97B4      	M_H_CPU0_SA_DQ<9>   
          	               	21        	97B1      	GND                 
          	               	22        	97B2      	M_H_CPU0_SA_DQS_DP<1>
          	               	23        	97B2      	M_H_CPU0_SA_DQS_DN<1>
          	               	24        	97B1      	GND                 
          	               	25        	97B4      	M_H_CPU0_SA_DQ<12>  
          	               	26        	97B1      	GND                 
          	               	27        	97B4      	M_H_CPU0_SA_DQ<13>  
          	               	28        	97B1      	GND                 
          	               	29        	97B4      	M_H_CPU0_SA_DQ<16>  
          	               	30        	97B1      	GND                 
          	               	31        	97B4      	M_H_CPU0_SA_DQ<17>  
          	               	32        	97B1      	GND                 
          	               	33        	97B2      	M_H_CPU0_SA_DQS_DP<2>
          	               	34        	97B2      	M_H_CPU0_SA_DQS_DN<2>
          	               	35        	97B1      	GND                 
          	               	36        	97B4      	M_H_CPU0_SA_DQ<20>  
          	               	37        	97B1      	GND                 
          	               	38        	97B4      	M_H_CPU0_SA_DQ<21>  
          	               	39        	97B1      	GND                 
          	               	40        	97B4      	M_H_CPU0_SA_DQ<24>  
          	               	41        	97B1      	GND                 
          	               	42        	97B4      	M_H_CPU0_SA_DQ<25>  
          	               	43        	97B1      	GND                 
          	               	44        	97B2      	M_H_CPU0_SA_DQS_DP<3>
          	               	45        	97B2      	M_H_CPU0_SA_DQS_DN<3>
          	               	46        	97B1      	GND                 
          	               	47        	97B4      	M_H_CPU0_SA_DQ<28>  
          	               	48        	97B1      	GND                 
          	               	49        	97B4      	M_H_CPU0_SA_DQ<29>  
          	               	50        	97B1      	GND                 
          	               	51        	97B4      	M_H_CPU0_SA_CB<0>   
          	               	52        	97B1      	GND                 
          	               	53        	97B4      	M_H_CPU0_SA_CB<1>   
          	               	54        	97B1      	GND                 
          	               	55        	97B2      	M_H_CPU0_SA_DQS_DP<4>
          	               	56        	97B2      	M_H_CPU0_SA_DQS_DN<4>
          	               	57        	97B1      	GND                 
          	               	58        	97B4      	M_H_CPU0_SA_CB<4>   
          	               	59        	97B1      	GND                 
          	               	60        	97B4      	M_H_CPU0_SA_CB<5>   
          	               	61        	97B1      	GND                 
          	               	62        	97B4      	M_H_CPU0_ALERT_N    
          	               	63        	97B1      	GND                 
          	               	64        	97B4      	M_H_CPU0_SA_CS_N<2> 
          	               	65        	97B1      	GND                 
          	               	66        	97B4      	M_H_CPU0_SA_CA<0>   
          	               	67        	97B1      	GND                 
          	               	68        	97B4      	M_H_CPU0_SA_CA<2>   
          	               	69        	97B1      	GND                 
          	               	70        	97B4      	M_H_CPU0_SA_CA<4>   
          	               	71        	97B1      	GND                 
          	               	72        	97B4      	M_H_CPU0_SA_CA<6>   
          	               	73        	97B1      	GND                 
          	               	74        	97B4      	M_H_CPU0_SA_PAR     
          	               	75        	97B1      	GND                 
          	               	76        	97B4      	M_H_CPU0_SB_CA<0>   
          	               	77        	97B1      	GND                 
          	               	78        	97B4      	M_H_CPU0_SB_CA<2>   
          	               	79        	97B1      	GND                 
          	               	80        	97B4      	M_H_CPU0_SB_CA<4>   
          	               	81        	97B1      	GND                 
          	               	82        	97B4      	M_H_CPU0_SB_CA<6>   
          	               	83        	97B1      	GND                 
          	               	84        	97B4      	M_H_CPU0_SB_CS_N<2> 
          	               	85        	97B1      	GND                 
          	               	86        	97A4      	M_H_CPU0_SA_RSP<1>  
          	               	87        	97A4      	M_H_CPU0_SB_RSP<1>  
          	               	88        	97B1      	GND                 
          	               	89        	97B4      	M_H_CPU0_SB_CB<4>   
          	               	90        	97B1      	GND                 
          	               	91        	97B4      	M_H_CPU0_SB_CB<5>   
          	               	92        	97B1      	GND                 
          	               	93        	97B2      	M_H_CPU0_SB_DQS_DP<9>
          	               	94        	97B2      	M_H_CPU0_SB_DQS_DN<9>
          	               	95        	97B1      	GND                 
          	               	96        	97B4      	M_H_CPU0_SB_CB<0>   
          	               	97        	97B1      	GND                 
          	               	98        	97B4      	M_H_CPU0_SB_CB<1>   
          	               	99        	97B1      	GND                 
          	               	100       	97B4      	M_H_CPU0_SB_DQ<0>   
          	               	101       	97B1      	GND                 
          	               	102       	97B4      	M_H_CPU0_SB_DQ<1>   
          	               	103       	97B1      	GND                 
          	               	104       	97B2      	M_H_CPU0_SB_DQS_DP<0>
          	               	105       	97B2      	M_H_CPU0_SB_DQS_DN<0>
          	               	106       	97B1      	GND                 
          	               	107       	97B4      	M_H_CPU0_SB_DQ<4>   
          	               	108       	97B1      	GND                 
          	               	109       	97B4      	M_H_CPU0_SB_DQ<5>   
          	               	110       	97B1      	GND                 
          	               	111       	97B4      	M_H_CPU0_SB_DQ<8>   
          	               	112       	97B1      	GND                 
          	               	113       	97B4      	M_H_CPU0_SB_DQ<9>   
          	               	114       	97B1      	GND                 
          	               	115       	97B2      	M_H_CPU0_SB_DQS_DP<1>
          	               	116       	97B2      	M_H_CPU0_SB_DQS_DN<1>
          	               	117       	97B1      	GND                 
          	               	118       	97B4      	M_H_CPU0_SB_DQ<12>  
          	               	119       	97B1      	GND                 
          	               	120       	97B4      	M_H_CPU0_SB_DQ<13>  
          	               	121       	97B1      	GND                 
          	               	122       	97B4      	M_H_CPU0_SB_DQ<16>  
          	               	123       	97B1      	GND                 
          	               	124       	97B4      	M_H_CPU0_SB_DQ<17>  
          	               	125       	97B1      	GND                 
          	               	126       	97B2      	M_H_CPU0_SB_DQS_DP<2>
          	               	127       	97B2      	M_H_CPU0_SB_DQS_DN<2>
          	               	128       	97B1      	GND                 
          	               	129       	97B4      	M_H_CPU0_SB_DQ<20>  
          	               	130       	97B1      	GND                 
          	               	131       	97B4      	M_H_CPU0_SB_DQ<21>  
          	               	132       	97B1      	GND                 
          	               	133       	97B4      	M_H_CPU0_SB_DQ<24>  
          	               	134       	97B1      	GND                 
          	               	135       	97B4      	M_H_CPU0_SB_DQ<25>  
          	               	136       	97B1      	GND                 
          	               	137       	97B2      	M_H_CPU0_SB_DQS_DP<3>
          	               	138       	97B2      	M_H_CPU0_SB_DQS_DN<3>
          	               	139       	97B1      	GND                 
          	               	140       	97B4      	M_H_CPU0_SB_DQ<28>  
          	               	141       	97B1      	GND                 
          	               	142       	97B4      	M_H_CPU0_SB_DQ<29>  
          	               	143       	97B1      	GND                 
          	               	144       	97B4      	TP_CHH_CPU0_DIMM2_FRU_1
          	               	145       	97B1      	P12V_S3_AUX_CPU0_NVDIMM
          	               	146       	97B1      	P12V_S3_AUX_CPU0_NVDIMM
          	               	147       	97B4      	PWRGD_CHH_CPU0_DIMM2
          	               	148       	97B4      	PD_CHH_CPU0_DIMM2_SAA
          	               	149       	97B4      	TP_CHH_CPU0_DIMM2_FRU_2
          	               	150       	97B4      	TP_CHH_CPU0_DIMM2_FRU_3
          	               	151       	97B1      	GND                 
          	               	152       	97B4      	M_H_CPU0_SA_DQ<2>   
          	               	153       	97B1      	GND                 
          	               	154       	97B4      	M_H_CPU0_SA_DQ<3>   
          	               	155       	97B1      	GND                 
          	               	156       	97B2      	M_H_CPU0_SA_DQS_DN<5>
          	               	157       	97B2      	M_H_CPU0_SA_DQS_DP<5>
          	               	158       	97B1      	GND                 
          	               	159       	97B4      	M_H_CPU0_SA_DQ<6>   
          	               	160       	97B1      	GND                 
          	               	161       	97B4      	M_H_CPU0_SA_DQ<7>   
          	               	162       	97B1      	GND                 
          	               	163       	97B4      	M_H_CPU0_SA_DQ<10>  
          	               	164       	97B1      	GND                 
          	               	165       	97B4      	M_H_CPU0_SA_DQ<11>  
          	               	166       	97B1      	GND                 
          	               	167       	97B2      	M_H_CPU0_SA_DQS_DN<6>
          	               	168       	97B2      	M_H_CPU0_SA_DQS_DP<6>
          	               	169       	97B1      	GND                 
          	               	170       	97B4      	M_H_CPU0_SA_DQ<14>  
          	               	171       	97B1      	GND                 
          	               	172       	97B4      	M_H_CPU0_SA_DQ<15>  
          	               	173       	97B1      	GND                 
          	               	174       	97B4      	M_H_CPU0_SA_DQ<18>  
          	               	175       	97B1      	GND                 
          	               	176       	97B4      	M_H_CPU0_SA_DQ<19>  
          	               	177       	97B1      	GND                 
          	               	178       	97B2      	M_H_CPU0_SA_DQS_DN<7>
          	               	179       	97B2      	M_H_CPU0_SA_DQS_DP<7>
          	               	180       	97B1      	GND                 
          	               	181       	97B4      	M_H_CPU0_SA_DQ<22>  
          	               	182       	97B1      	GND                 
          	               	183       	97B4      	M_H_CPU0_SA_DQ<23>  
          	               	184       	97B1      	GND                 
          	               	185       	97B4      	M_H_CPU0_SA_DQ<26>  
          	               	186       	97B1      	GND                 
          	               	187       	97B4      	M_H_CPU0_SA_DQ<27>  
          	               	188       	97B1      	GND                 
          	               	189       	97B2      	M_H_CPU0_SA_DQS_DN<8>
          	               	190       	97B2      	M_H_CPU0_SA_DQS_DP<8>
          	               	191       	97B1      	GND                 
          	               	192       	97B4      	M_H_CPU0_SA_DQ<30>  
          	               	193       	97B1      	GND                 
          	               	194       	97B4      	M_H_CPU0_SA_DQ<31>  
          	               	195       	97B1      	GND                 
          	               	196       	97B4      	M_H_CPU0_SA_CB<2>   
          	               	197       	97B1      	GND                 
          	               	198       	97B4      	M_H_CPU0_SA_CB<3>   
          	               	199       	97B1      	GND                 
          	               	200       	97B2      	M_H_CPU0_SA_DQS_DN<9>
          	               	201       	97B2      	M_H_CPU0_SA_DQS_DP<9>
          	               	202       	97B1      	GND                 
          	               	203       	97B4      	M_H_CPU0_SA_CB<6>   
          	               	204       	97B1      	GND                 
          	               	205       	97B4      	M_H_CPU0_SA_CB<7>   
          	               	206       	97B1      	GND                 
          	               	207       	97B4      	RST_M_GH_CPU0_FPGA_N
          	               	208       	97B1      	GND                 
          	               	209       	97B4      	M_H_CPU0_SA_CS_N<3> 
          	               	210       	97B1      	GND                 
          	               	211       	97B4      	M_H_CPU0_SA_CA<1>   
          	               	212       	97B1      	GND                 
          	               	213       	97B4      	M_H_CPU0_SA_CA<3>   
          	               	214       	97B1      	GND                 
          	               	215       	97B4      	M_H_CPU0_SA_CA<5>   
          	               	216       	97B1      	GND                 
          	               	217       	97B4      	M_H_CPU0_CLK_DP<1>  
          	               	218       	97B4      	M_H_CPU0_CLK_DN<1>  
          	               	219       	97B1      	GND                 
          	               	220       	97B4      	TP_CHH_CPU0_DIMM2_FRU_4
          	               	221       	97B4      	M_H_CPU0_SB_CA<1>   
          	               	222       	97B1      	GND                 
          	               	223       	97B4      	M_H_CPU0_SB_CA<3>   
          	               	224       	97B1      	GND                 
          	               	225       	97B4      	M_H_CPU0_SB_CA<5>   
          	               	226       	97B1      	GND                 
          	               	227       	97B4      	M_H_CPU0_SB_PAR     
          	               	228       	97B1      	GND                 
          	               	229       	97B4      	M_H_CPU0_SB_CS_N<3> 
          	               	230       	97B1      	GND                 
          	               	231       	97B4      	TP_CHH_CPU0_DIMM2_FRU_5
          	               	232       	97B4      	TP_CHH_CPU0_DIMM2_FRU_6
          	               	233       	97B1      	GND                 
          	               	234       	97B4      	M_H_CPU0_SB_CB<6>   
          	               	235       	97B1      	GND                 
          	               	236       	97B4      	M_H_CPU0_SB_CB<7>   
          	               	237       	97B1      	GND                 
          	               	238       	97B2      	M_H_CPU0_SB_DQS_DN<4>
          	               	239       	97B2      	M_H_CPU0_SB_DQS_DP<4>
          	               	240       	97B1      	GND                 
          	               	241       	97B4      	M_H_CPU0_SB_CB<2>   
          	               	242       	97B1      	GND                 
          	               	243       	97B4      	M_H_CPU0_SB_CB<3>   
          	               	244       	97B1      	GND                 
          	               	245       	97B4      	M_H_CPU0_SB_DQ<2>   
          	               	246       	97B1      	GND                 
          	               	247       	97B4      	M_H_CPU0_SB_DQ<3>   
          	               	248       	97B1      	GND                 
          	               	249       	97B2      	M_H_CPU0_SB_DQS_DN<5>
          	               	250       	97B2      	M_H_CPU0_SB_DQS_DP<5>
          	               	251       	97B1      	GND                 
          	               	252       	97B4      	M_H_CPU0_SB_DQ<6>   
          	               	253       	97B1      	GND                 
          	               	254       	97B4      	M_H_CPU0_SB_DQ<7>   
          	               	255       	97B1      	GND                 
          	               	256       	97B4      	M_H_CPU0_SB_DQ<10>  
          	               	257       	97B1      	GND                 
          	               	258       	97B4      	M_H_CPU0_SB_DQ<11>  
          	               	259       	97B1      	GND                 
          	               	260       	97B2      	M_H_CPU0_SB_DQS_DN<6>
          	               	261       	97B2      	M_H_CPU0_SB_DQS_DP<6>
          	               	262       	97B1      	GND                 
          	               	263       	97B4      	M_H_CPU0_SB_DQ<14>  
          	               	264       	97B1      	GND                 
          	               	265       	97B4      	M_H_CPU0_SB_DQ<15>  
          	               	266       	97B1      	GND                 
          	               	267       	97B4      	M_H_CPU0_SB_DQ<18>  
          	               	268       	97B1      	GND                 
          	               	269       	97B4      	M_H_CPU0_SB_DQ<19>  
          	               	270       	97B1      	GND                 
          	               	271       	97B2      	M_H_CPU0_SB_DQS_DN<7>
          	               	272       	97B2      	M_H_CPU0_SB_DQS_DP<7>
          	               	273       	97B1      	GND                 
          	               	274       	97B4      	M_H_CPU0_SB_DQ<22>  
          	               	275       	97B1      	GND                 
          	               	276       	97B4      	M_H_CPU0_SB_DQ<23>  
          	               	277       	97B1      	GND                 
          	               	278       	97B4      	M_H_CPU0_SB_DQ<26>  
          	               	279       	97B1      	GND                 
          	               	280       	97B4      	M_H_CPU0_SB_DQ<27>  
          	               	281       	97B1      	GND                 
          	               	282       	97B2      	M_H_CPU0_SB_DQS_DN<8>
          	               	283       	97B2      	M_H_CPU0_SB_DQS_DP<8>
          	               	284       	97B1      	GND                 
          	               	285       	97B4      	M_H_CPU0_SB_DQ<30>  
          	               	286       	97B1      	GND                 
          	               	287       	97B4      	M_H_CPU0_SB_DQ<31>  
          	               	288       	97B1      	GND                 
          	               	G1        	97B1      	GND                 
          	               	G2        	97A1      	GND                 
          	               	G3        	97A1      	GND                 

J17       	SCONN288_ADR50017P130CC	          	          	                    
          	               	1         	98B1      	P12V_S3_AUX_CPU1_NVDIMM
          	               	2         	98B4      	TP_CHA_CPU1_DIMM1_FRU_0
          	               	3         	98B4      	P3V3_AUX            
          	               	4         	98B4      	I3C_SPD_DDRABCD_CPU1_LVC1_SCL_R
          	               	5         	98B4      	I3C_SPD_DDRABCD_CPU1_LVC1_SDA
          	               	6         	98B1      	GND                 
          	               	7         	98B4      	M_A_CPU1_SA_DQ<0>   
          	               	8         	98B1      	GND                 
          	               	9         	98B4      	M_A_CPU1_SA_DQ<1>   
          	               	10        	98B1      	GND                 
          	               	11        	98B2      	M_A_CPU1_SA_DQS_DP<0>
          	               	12        	98B2      	M_A_CPU1_SA_DQS_DN<0>
          	               	13        	98B1      	GND                 
          	               	14        	98B4      	M_A_CPU1_SA_DQ<4>   
          	               	15        	98B1      	GND                 
          	               	16        	98B4      	M_A_CPU1_SA_DQ<5>   
          	               	17        	98B1      	GND                 
          	               	18        	98B4      	M_A_CPU1_SA_DQ<8>   
          	               	19        	98B1      	GND                 
          	               	20        	98B4      	M_A_CPU1_SA_DQ<9>   
          	               	21        	98B1      	GND                 
          	               	22        	98B2      	M_A_CPU1_SA_DQS_DP<1>
          	               	23        	98B2      	M_A_CPU1_SA_DQS_DN<1>
          	               	24        	98B1      	GND                 
          	               	25        	98B4      	M_A_CPU1_SA_DQ<12>  
          	               	26        	98B1      	GND                 
          	               	27        	98B4      	M_A_CPU1_SA_DQ<13>  
          	               	28        	98B1      	GND                 
          	               	29        	98B4      	M_A_CPU1_SA_DQ<16>  
          	               	30        	98B1      	GND                 
          	               	31        	98B4      	M_A_CPU1_SA_DQ<17>  
          	               	32        	98B1      	GND                 
          	               	33        	98B2      	M_A_CPU1_SA_DQS_DP<2>
          	               	34        	98B2      	M_A_CPU1_SA_DQS_DN<2>
          	               	35        	98B1      	GND                 
          	               	36        	98B4      	M_A_CPU1_SA_DQ<20>  
          	               	37        	98B1      	GND                 
          	               	38        	98B4      	M_A_CPU1_SA_DQ<21>  
          	               	39        	98B1      	GND                 
          	               	40        	98B4      	M_A_CPU1_SA_DQ<24>  
          	               	41        	98B1      	GND                 
          	               	42        	98B4      	M_A_CPU1_SA_DQ<25>  
          	               	43        	98B1      	GND                 
          	               	44        	98B2      	M_A_CPU1_SA_DQS_DP<3>
          	               	45        	98B2      	M_A_CPU1_SA_DQS_DN<3>
          	               	46        	98B1      	GND                 
          	               	47        	98B4      	M_A_CPU1_SA_DQ<28>  
          	               	48        	98B1      	GND                 
          	               	49        	98B4      	M_A_CPU1_SA_DQ<29>  
          	               	50        	98B1      	GND                 
          	               	51        	98B4      	M_A_CPU1_SA_CB<0>   
          	               	52        	98B1      	GND                 
          	               	53        	98B4      	M_A_CPU1_SA_CB<1>   
          	               	54        	98B1      	GND                 
          	               	55        	98B2      	M_A_CPU1_SA_DQS_DP<4>
          	               	56        	98B2      	M_A_CPU1_SA_DQS_DN<4>
          	               	57        	98B1      	GND                 
          	               	58        	98B4      	M_A_CPU1_SA_CB<4>   
          	               	59        	98B1      	GND                 
          	               	60        	98B4      	M_A_CPU1_SA_CB<5>   
          	               	61        	98B1      	GND                 
          	               	62        	98B4      	M_A_CPU1_ALERT_N    
          	               	63        	98B1      	GND                 
          	               	64        	98B4      	M_A_CPU1_SA_CS_N<0> 
          	               	65        	98B1      	GND                 
          	               	66        	98B4      	M_A_CPU1_SA_CA<0>   
          	               	67        	98B1      	GND                 
          	               	68        	98B4      	M_A_CPU1_SA_CA<2>   
          	               	69        	98B1      	GND                 
          	               	70        	98B4      	M_A_CPU1_SA_CA<4>   
          	               	71        	98B1      	GND                 
          	               	72        	98B4      	M_A_CPU1_SA_CA<6>   
          	               	73        	98B1      	GND                 
          	               	74        	98B4      	M_A_CPU1_SA_PAR     
          	               	75        	98B1      	GND                 
          	               	76        	98B4      	M_A_CPU1_SB_CA<0>   
          	               	77        	98B1      	GND                 
          	               	78        	98B4      	M_A_CPU1_SB_CA<2>   
          	               	79        	98B1      	GND                 
          	               	80        	98B4      	M_A_CPU1_SB_CA<4>   
          	               	81        	98B1      	GND                 
          	               	82        	98B4      	M_A_CPU1_SB_CA<6>   
          	               	83        	98B1      	GND                 
          	               	84        	98B4      	M_A_CPU1_SB_CS_N<0> 
          	               	85        	98B1      	GND                 
          	               	86        	98A4      	M_A_CPU1_SA_RSP<0>  
          	               	87        	98A4      	M_A_CPU1_SB_RSP<0>  
          	               	88        	98B1      	GND                 
          	               	89        	98B4      	M_A_CPU1_SB_CB<4>   
          	               	90        	98B1      	GND                 
          	               	91        	98B4      	M_A_CPU1_SB_CB<5>   
          	               	92        	98B1      	GND                 
          	               	93        	98B2      	M_A_CPU1_SB_DQS_DP<9>
          	               	94        	98B2      	M_A_CPU1_SB_DQS_DN<9>
          	               	95        	98B1      	GND                 
          	               	96        	98B4      	M_A_CPU1_SB_CB<0>   
          	               	97        	98B1      	GND                 
          	               	98        	98B4      	M_A_CPU1_SB_CB<1>   
          	               	99        	98B1      	GND                 
          	               	100       	98B4      	M_A_CPU1_SB_DQ<0>   
          	               	101       	98B1      	GND                 
          	               	102       	98B4      	M_A_CPU1_SB_DQ<1>   
          	               	103       	98B1      	GND                 
          	               	104       	98B2      	M_A_CPU1_SB_DQS_DP<0>
          	               	105       	98B2      	M_A_CPU1_SB_DQS_DN<0>
          	               	106       	98B1      	GND                 
          	               	107       	98B4      	M_A_CPU1_SB_DQ<4>   
          	               	108       	98B1      	GND                 
          	               	109       	98B4      	M_A_CPU1_SB_DQ<5>   
          	               	110       	98B1      	GND                 
          	               	111       	98B4      	M_A_CPU1_SB_DQ<8>   
          	               	112       	98B1      	GND                 
          	               	113       	98B4      	M_A_CPU1_SB_DQ<9>   
          	               	114       	98B1      	GND                 
          	               	115       	98B2      	M_A_CPU1_SB_DQS_DP<1>
          	               	116       	98B2      	M_A_CPU1_SB_DQS_DN<1>
          	               	117       	98B1      	GND                 
          	               	118       	98B4      	M_A_CPU1_SB_DQ<12>  
          	               	119       	98B1      	GND                 
          	               	120       	98B4      	M_A_CPU1_SB_DQ<13>  
          	               	121       	98B1      	GND                 
          	               	122       	98B4      	M_A_CPU1_SB_DQ<16>  
          	               	123       	98B1      	GND                 
          	               	124       	98B4      	M_A_CPU1_SB_DQ<17>  
          	               	125       	98B1      	GND                 
          	               	126       	98B2      	M_A_CPU1_SB_DQS_DP<2>
          	               	127       	98B2      	M_A_CPU1_SB_DQS_DN<2>
          	               	128       	98B1      	GND                 
          	               	129       	98B4      	M_A_CPU1_SB_DQ<20>  
          	               	130       	98B1      	GND                 
          	               	131       	98B4      	M_A_CPU1_SB_DQ<21>  
          	               	132       	98B1      	GND                 
          	               	133       	98B4      	M_A_CPU1_SB_DQ<24>  
          	               	134       	98B1      	GND                 
          	               	135       	98B4      	M_A_CPU1_SB_DQ<25>  
          	               	136       	98B1      	GND                 
          	               	137       	98B2      	M_A_CPU1_SB_DQS_DP<3>
          	               	138       	98B2      	M_A_CPU1_SB_DQS_DN<3>
          	               	139       	98B1      	GND                 
          	               	140       	98B4      	M_A_CPU1_SB_DQ<28>  
          	               	141       	98B1      	GND                 
          	               	142       	98B4      	M_A_CPU1_SB_DQ<29>  
          	               	143       	98B1      	GND                 
          	               	144       	98B4      	TP_CHA_CPU1_DIMM1_FRU_1
          	               	145       	98B1      	P12V_S3_AUX_CPU1_NVDIMM
          	               	146       	98B1      	P12V_S3_AUX_CPU1_NVDIMM
          	               	147       	98B4      	PWRGD_CHA_CPU1_DIMM1
          	               	148       	98B4      	PD_CHA_CPU1_DIMM1_SAA
          	               	149       	98B4      	TP_CHA_CPU1_DIMM1_FRU_2
          	               	150       	98B4      	TP_CHA_CPU1_DIMM1_FRU_3
          	               	151       	98B1      	GND                 
          	               	152       	98B4      	M_A_CPU1_SA_DQ<2>   
          	               	153       	98B1      	GND                 
          	               	154       	98B4      	M_A_CPU1_SA_DQ<3>   
          	               	155       	98B1      	GND                 
          	               	156       	98B2      	M_A_CPU1_SA_DQS_DN<5>
          	               	157       	98B2      	M_A_CPU1_SA_DQS_DP<5>
          	               	158       	98B1      	GND                 
          	               	159       	98B4      	M_A_CPU1_SA_DQ<6>   
          	               	160       	98B1      	GND                 
          	               	161       	98B4      	M_A_CPU1_SA_DQ<7>   
          	               	162       	98B1      	GND                 
          	               	163       	98B4      	M_A_CPU1_SA_DQ<10>  
          	               	164       	98B1      	GND                 
          	               	165       	98B4      	M_A_CPU1_SA_DQ<11>  
          	               	166       	98B1      	GND                 
          	               	167       	98B2      	M_A_CPU1_SA_DQS_DN<6>
          	               	168       	98B2      	M_A_CPU1_SA_DQS_DP<6>
          	               	169       	98B1      	GND                 
          	               	170       	98B4      	M_A_CPU1_SA_DQ<14>  
          	               	171       	98B1      	GND                 
          	               	172       	98B4      	M_A_CPU1_SA_DQ<15>  
          	               	173       	98B1      	GND                 
          	               	174       	98B4      	M_A_CPU1_SA_DQ<18>  
          	               	175       	98B1      	GND                 
          	               	176       	98B4      	M_A_CPU1_SA_DQ<19>  
          	               	177       	98B1      	GND                 
          	               	178       	98B2      	M_A_CPU1_SA_DQS_DN<7>
          	               	179       	98B2      	M_A_CPU1_SA_DQS_DP<7>
          	               	180       	98B1      	GND                 
          	               	181       	98B4      	M_A_CPU1_SA_DQ<22>  
          	               	182       	98B1      	GND                 
          	               	183       	98B4      	M_A_CPU1_SA_DQ<23>  
          	               	184       	98B1      	GND                 
          	               	185       	98B4      	M_A_CPU1_SA_DQ<26>  
          	               	186       	98B1      	GND                 
          	               	187       	98B4      	M_A_CPU1_SA_DQ<27>  
          	               	188       	98B1      	GND                 
          	               	189       	98B2      	M_A_CPU1_SA_DQS_DN<8>
          	               	190       	98B2      	M_A_CPU1_SA_DQS_DP<8>
          	               	191       	98B1      	GND                 
          	               	192       	98B4      	M_A_CPU1_SA_DQ<30>  
          	               	193       	98B1      	GND                 
          	               	194       	98B4      	M_A_CPU1_SA_DQ<31>  
          	               	195       	98B1      	GND                 
          	               	196       	98B4      	M_A_CPU1_SA_CB<2>   
          	               	197       	98B1      	GND                 
          	               	198       	98B4      	M_A_CPU1_SA_CB<3>   
          	               	199       	98B1      	GND                 
          	               	200       	98B2      	M_A_CPU1_SA_DQS_DN<9>
          	               	201       	98B2      	M_A_CPU1_SA_DQS_DP<9>
          	               	202       	98B1      	GND                 
          	               	203       	98B4      	M_A_CPU1_SA_CB<6>   
          	               	204       	98B1      	GND                 
          	               	205       	98B4      	M_A_CPU1_SA_CB<7>   
          	               	206       	98B1      	GND                 
          	               	207       	98B4      	RST_M_AB_CPU1_FPGA_N
          	               	208       	98B1      	GND                 
          	               	209       	98B4      	M_A_CPU1_SA_CS_N<1> 
          	               	210       	98B1      	GND                 
          	               	211       	98B4      	M_A_CPU1_SA_CA<1>   
          	               	212       	98B1      	GND                 
          	               	213       	98B4      	M_A_CPU1_SA_CA<3>   
          	               	214       	98B1      	GND                 
          	               	215       	98B4      	M_A_CPU1_SA_CA<5>   
          	               	216       	98B1      	GND                 
          	               	217       	98B4      	M_A_CPU1_CLK_DP<0>  
          	               	218       	98B4      	M_A_CPU1_CLK_DN<0>  
          	               	219       	98B1      	GND                 
          	               	220       	98B4      	TP_CHA_CPU1_DIMM1_FRU_4
          	               	221       	98B4      	M_A_CPU1_SB_CA<1>   
          	               	222       	98B1      	GND                 
          	               	223       	98B4      	M_A_CPU1_SB_CA<3>   
          	               	224       	98B1      	GND                 
          	               	225       	98B4      	M_A_CPU1_SB_CA<5>   
          	               	226       	98B1      	GND                 
          	               	227       	98B4      	M_A_CPU1_SB_PAR     
          	               	228       	98B1      	GND                 
          	               	229       	98B4      	M_A_CPU1_SB_CS_N<1> 
          	               	230       	98B1      	GND                 
          	               	231       	98B4      	TP_CHA_CPU1_DIMM1_FRU_5
          	               	232       	98B4      	TP_CHA_CPU1_DIMM1_FRU_6
          	               	233       	98B1      	GND                 
          	               	234       	98B4      	M_A_CPU1_SB_CB<6>   
          	               	235       	98B1      	GND                 
          	               	236       	98B4      	M_A_CPU1_SB_CB<7>   
          	               	237       	98B1      	GND                 
          	               	238       	98B2      	M_A_CPU1_SB_DQS_DN<4>
          	               	239       	98B2      	M_A_CPU1_SB_DQS_DP<4>
          	               	240       	98B1      	GND                 
          	               	241       	98B4      	M_A_CPU1_SB_CB<2>   
          	               	242       	98B1      	GND                 
          	               	243       	98B4      	M_A_CPU1_SB_CB<3>   
          	               	244       	98B1      	GND                 
          	               	245       	98B4      	M_A_CPU1_SB_DQ<2>   
          	               	246       	98B1      	GND                 
          	               	247       	98B4      	M_A_CPU1_SB_DQ<3>   
          	               	248       	98B1      	GND                 
          	               	249       	98B2      	M_A_CPU1_SB_DQS_DN<5>
          	               	250       	98B2      	M_A_CPU1_SB_DQS_DP<5>
          	               	251       	98B1      	GND                 
          	               	252       	98B4      	M_A_CPU1_SB_DQ<6>   
          	               	253       	98B1      	GND                 
          	               	254       	98B4      	M_A_CPU1_SB_DQ<7>   
          	               	255       	98B1      	GND                 
          	               	256       	98B4      	M_A_CPU1_SB_DQ<10>  
          	               	257       	98B1      	GND                 
          	               	258       	98B4      	M_A_CPU1_SB_DQ<11>  
          	               	259       	98B1      	GND                 
          	               	260       	98B2      	M_A_CPU1_SB_DQS_DN<6>
          	               	261       	98B2      	M_A_CPU1_SB_DQS_DP<6>
          	               	262       	98B1      	GND                 
          	               	263       	98B4      	M_A_CPU1_SB_DQ<14>  
          	               	264       	98B1      	GND                 
          	               	265       	98B4      	M_A_CPU1_SB_DQ<15>  
          	               	266       	98B1      	GND                 
          	               	267       	98B4      	M_A_CPU1_SB_DQ<18>  
          	               	268       	98B1      	GND                 
          	               	269       	98B4      	M_A_CPU1_SB_DQ<19>  
          	               	270       	98B1      	GND                 
          	               	271       	98B2      	M_A_CPU1_SB_DQS_DN<7>
          	               	272       	98B2      	M_A_CPU1_SB_DQS_DP<7>
          	               	273       	98B1      	GND                 
          	               	274       	98B4      	M_A_CPU1_SB_DQ<22>  
          	               	275       	98B1      	GND                 
          	               	276       	98B4      	M_A_CPU1_SB_DQ<23>  
          	               	277       	98B1      	GND                 
          	               	278       	98B4      	M_A_CPU1_SB_DQ<26>  
          	               	279       	98B1      	GND                 
          	               	280       	98B4      	M_A_CPU1_SB_DQ<27>  
          	               	281       	98B1      	GND                 
          	               	282       	98B2      	M_A_CPU1_SB_DQS_DN<8>
          	               	283       	98B2      	M_A_CPU1_SB_DQS_DP<8>
          	               	284       	98B1      	GND                 
          	               	285       	98B4      	M_A_CPU1_SB_DQ<30>  
          	               	286       	98B1      	GND                 
          	               	287       	98B4      	M_A_CPU1_SB_DQ<31>  
          	               	288       	98B1      	GND                 
          	               	G1        	98B1      	GND                 
          	               	G2        	98A1      	GND                 
          	               	G3        	98A1      	GND                 

J18       	SCONN288_ADR50017P087CC	          	          	                    
          	               	1         	99B1      	P12V_S3_AUX_CPU1_NVDIMM
          	               	2         	99B4      	TP_CHA_CPU1_DIMM2_FRU_0
          	               	3         	99B4      	P3V3_AUX            
          	               	4         	99B4      	I3C_SPD_DDRABCD_CPU1_LVC1_SCL_1
          	               	5         	99B4      	I3C_SPD_DDRABCD_CPU1_LVC1_SDA
          	               	6         	99B1      	GND                 
          	               	7         	99B4      	M_A_CPU1_SA_DQ<0>   
          	               	8         	99B1      	GND                 
          	               	9         	99B4      	M_A_CPU1_SA_DQ<1>   
          	               	10        	99B1      	GND                 
          	               	11        	99B2      	M_A_CPU1_SA_DQS_DP<0>
          	               	12        	99B2      	M_A_CPU1_SA_DQS_DN<0>
          	               	13        	99B1      	GND                 
          	               	14        	99B4      	M_A_CPU1_SA_DQ<4>   
          	               	15        	99B1      	GND                 
          	               	16        	99B4      	M_A_CPU1_SA_DQ<5>   
          	               	17        	99B1      	GND                 
          	               	18        	99B4      	M_A_CPU1_SA_DQ<8>   
          	               	19        	99B1      	GND                 
          	               	20        	99B4      	M_A_CPU1_SA_DQ<9>   
          	               	21        	99B1      	GND                 
          	               	22        	99B2      	M_A_CPU1_SA_DQS_DP<1>
          	               	23        	99B2      	M_A_CPU1_SA_DQS_DN<1>
          	               	24        	99B1      	GND                 
          	               	25        	99B4      	M_A_CPU1_SA_DQ<12>  
          	               	26        	99B1      	GND                 
          	               	27        	99B4      	M_A_CPU1_SA_DQ<13>  
          	               	28        	99B1      	GND                 
          	               	29        	99B4      	M_A_CPU1_SA_DQ<16>  
          	               	30        	99B1      	GND                 
          	               	31        	99B4      	M_A_CPU1_SA_DQ<17>  
          	               	32        	99B1      	GND                 
          	               	33        	99B2      	M_A_CPU1_SA_DQS_DP<2>
          	               	34        	99B2      	M_A_CPU1_SA_DQS_DN<2>
          	               	35        	99B1      	GND                 
          	               	36        	99B4      	M_A_CPU1_SA_DQ<20>  
          	               	37        	99B1      	GND                 
          	               	38        	99B4      	M_A_CPU1_SA_DQ<21>  
          	               	39        	99B1      	GND                 
          	               	40        	99B4      	M_A_CPU1_SA_DQ<24>  
          	               	41        	99B1      	GND                 
          	               	42        	99B4      	M_A_CPU1_SA_DQ<25>  
          	               	43        	99B1      	GND                 
          	               	44        	99B2      	M_A_CPU1_SA_DQS_DP<3>
          	               	45        	99B2      	M_A_CPU1_SA_DQS_DN<3>
          	               	46        	99B1      	GND                 
          	               	47        	99B4      	M_A_CPU1_SA_DQ<28>  
          	               	48        	99B1      	GND                 
          	               	49        	99B4      	M_A_CPU1_SA_DQ<29>  
          	               	50        	99B1      	GND                 
          	               	51        	99B4      	M_A_CPU1_SA_CB<0>   
          	               	52        	99B1      	GND                 
          	               	53        	99B4      	M_A_CPU1_SA_CB<1>   
          	               	54        	99B1      	GND                 
          	               	55        	99B2      	M_A_CPU1_SA_DQS_DP<4>
          	               	56        	99B2      	M_A_CPU1_SA_DQS_DN<4>
          	               	57        	99B1      	GND                 
          	               	58        	99B4      	M_A_CPU1_SA_CB<4>   
          	               	59        	99B1      	GND                 
          	               	60        	99B4      	M_A_CPU1_SA_CB<5>   
          	               	61        	99B1      	GND                 
          	               	62        	99B4      	M_A_CPU1_ALERT_N    
          	               	63        	99B1      	GND                 
          	               	64        	99B4      	M_A_CPU1_SA_CS_N<2> 
          	               	65        	99B1      	GND                 
          	               	66        	99B4      	M_A_CPU1_SA_CA<0>   
          	               	67        	99B1      	GND                 
          	               	68        	99B4      	M_A_CPU1_SA_CA<2>   
          	               	69        	99B1      	GND                 
          	               	70        	99B4      	M_A_CPU1_SA_CA<4>   
          	               	71        	99B1      	GND                 
          	               	72        	99B4      	M_A_CPU1_SA_CA<6>   
          	               	73        	99B1      	GND                 
          	               	74        	99B4      	M_A_CPU1_SA_PAR     
          	               	75        	99B1      	GND                 
          	               	76        	99B4      	M_A_CPU1_SB_CA<0>   
          	               	77        	99B1      	GND                 
          	               	78        	99B4      	M_A_CPU1_SB_CA<2>   
          	               	79        	99B1      	GND                 
          	               	80        	99B4      	M_A_CPU1_SB_CA<4>   
          	               	81        	99B1      	GND                 
          	               	82        	99B4      	M_A_CPU1_SB_CA<6>   
          	               	83        	99B1      	GND                 
          	               	84        	99B4      	M_A_CPU1_SB_CS_N<2> 
          	               	85        	99B1      	GND                 
          	               	86        	99A4      	M_A_CPU1_SA_RSP<1>  
          	               	87        	99A4      	M_A_CPU1_SB_RSP<1>  
          	               	88        	99B1      	GND                 
          	               	89        	99B4      	M_A_CPU1_SB_CB<4>   
          	               	90        	99B1      	GND                 
          	               	91        	99B4      	M_A_CPU1_SB_CB<5>   
          	               	92        	99B1      	GND                 
          	               	93        	99B2      	M_A_CPU1_SB_DQS_DP<9>
          	               	94        	99B2      	M_A_CPU1_SB_DQS_DN<9>
          	               	95        	99B1      	GND                 
          	               	96        	99B4      	M_A_CPU1_SB_CB<0>   
          	               	97        	99B1      	GND                 
          	               	98        	99B4      	M_A_CPU1_SB_CB<1>   
          	               	99        	99B1      	GND                 
          	               	100       	99B4      	M_A_CPU1_SB_DQ<0>   
          	               	101       	99B1      	GND                 
          	               	102       	99B4      	M_A_CPU1_SB_DQ<1>   
          	               	103       	99B1      	GND                 
          	               	104       	99B2      	M_A_CPU1_SB_DQS_DP<0>
          	               	105       	99B2      	M_A_CPU1_SB_DQS_DN<0>
          	               	106       	99B1      	GND                 
          	               	107       	99B4      	M_A_CPU1_SB_DQ<4>   
          	               	108       	99B1      	GND                 
          	               	109       	99B4      	M_A_CPU1_SB_DQ<5>   
          	               	110       	99B1      	GND                 
          	               	111       	99B4      	M_A_CPU1_SB_DQ<8>   
          	               	112       	99B1      	GND                 
          	               	113       	99B4      	M_A_CPU1_SB_DQ<9>   
          	               	114       	99B1      	GND                 
          	               	115       	99B2      	M_A_CPU1_SB_DQS_DP<1>
          	               	116       	99B2      	M_A_CPU1_SB_DQS_DN<1>
          	               	117       	99B1      	GND                 
          	               	118       	99B4      	M_A_CPU1_SB_DQ<12>  
          	               	119       	99B1      	GND                 
          	               	120       	99B4      	M_A_CPU1_SB_DQ<13>  
          	               	121       	99B1      	GND                 
          	               	122       	99B4      	M_A_CPU1_SB_DQ<16>  
          	               	123       	99B1      	GND                 
          	               	124       	99B4      	M_A_CPU1_SB_DQ<17>  
          	               	125       	99B1      	GND                 
          	               	126       	99B2      	M_A_CPU1_SB_DQS_DP<2>
          	               	127       	99B2      	M_A_CPU1_SB_DQS_DN<2>
          	               	128       	99B1      	GND                 
          	               	129       	99B4      	M_A_CPU1_SB_DQ<20>  
          	               	130       	99B1      	GND                 
          	               	131       	99B4      	M_A_CPU1_SB_DQ<21>  
          	               	132       	99B1      	GND                 
          	               	133       	99B4      	M_A_CPU1_SB_DQ<24>  
          	               	134       	99B1      	GND                 
          	               	135       	99B4      	M_A_CPU1_SB_DQ<25>  
          	               	136       	99B1      	GND                 
          	               	137       	99B2      	M_A_CPU1_SB_DQS_DP<3>
          	               	138       	99B2      	M_A_CPU1_SB_DQS_DN<3>
          	               	139       	99B1      	GND                 
          	               	140       	99B4      	M_A_CPU1_SB_DQ<28>  
          	               	141       	99B1      	GND                 
          	               	142       	99B4      	M_A_CPU1_SB_DQ<29>  
          	               	143       	99B1      	GND                 
          	               	144       	99B4      	TP_CHA_CPU1_DIMM2_FRU_1
          	               	145       	99B1      	P12V_S3_AUX_CPU1_NVDIMM
          	               	146       	99B1      	P12V_S3_AUX_CPU1_NVDIMM
          	               	147       	99B4      	PWRGD_CHA_CPU1_DIMM2
          	               	148       	99B4      	PD_CHA_CPU1_DIMM2_SAA
          	               	149       	99B4      	TP_CHA_CPU1_DIMM2_FRU_2
          	               	150       	99B4      	TP_CHA_CPU1_DIMM2_FRU_3
          	               	151       	99B1      	GND                 
          	               	152       	99B4      	M_A_CPU1_SA_DQ<2>   
          	               	153       	99B1      	GND                 
          	               	154       	99B4      	M_A_CPU1_SA_DQ<3>   
          	               	155       	99B1      	GND                 
          	               	156       	99B2      	M_A_CPU1_SA_DQS_DN<5>
          	               	157       	99B2      	M_A_CPU1_SA_DQS_DP<5>
          	               	158       	99B1      	GND                 
          	               	159       	99B4      	M_A_CPU1_SA_DQ<6>   
          	               	160       	99B1      	GND                 
          	               	161       	99B4      	M_A_CPU1_SA_DQ<7>   
          	               	162       	99B1      	GND                 
          	               	163       	99B4      	M_A_CPU1_SA_DQ<10>  
          	               	164       	99B1      	GND                 
          	               	165       	99B4      	M_A_CPU1_SA_DQ<11>  
          	               	166       	99B1      	GND                 
          	               	167       	99B2      	M_A_CPU1_SA_DQS_DN<6>
          	               	168       	99B2      	M_A_CPU1_SA_DQS_DP<6>
          	               	169       	99B1      	GND                 
          	               	170       	99B4      	M_A_CPU1_SA_DQ<14>  
          	               	171       	99B1      	GND                 
          	               	172       	99B4      	M_A_CPU1_SA_DQ<15>  
          	               	173       	99B1      	GND                 
          	               	174       	99B4      	M_A_CPU1_SA_DQ<18>  
          	               	175       	99B1      	GND                 
          	               	176       	99B4      	M_A_CPU1_SA_DQ<19>  
          	               	177       	99B1      	GND                 
          	               	178       	99B2      	M_A_CPU1_SA_DQS_DN<7>
          	               	179       	99B2      	M_A_CPU1_SA_DQS_DP<7>
          	               	180       	99B1      	GND                 
          	               	181       	99B4      	M_A_CPU1_SA_DQ<22>  
          	               	182       	99B1      	GND                 
          	               	183       	99B4      	M_A_CPU1_SA_DQ<23>  
          	               	184       	99B1      	GND                 
          	               	185       	99B4      	M_A_CPU1_SA_DQ<26>  
          	               	186       	99B1      	GND                 
          	               	187       	99B4      	M_A_CPU1_SA_DQ<27>  
          	               	188       	99B1      	GND                 
          	               	189       	99B2      	M_A_CPU1_SA_DQS_DN<8>
          	               	190       	99B2      	M_A_CPU1_SA_DQS_DP<8>
          	               	191       	99B1      	GND                 
          	               	192       	99B4      	M_A_CPU1_SA_DQ<30>  
          	               	193       	99B1      	GND                 
          	               	194       	99B4      	M_A_CPU1_SA_DQ<31>  
          	               	195       	99B1      	GND                 
          	               	196       	99B4      	M_A_CPU1_SA_CB<2>   
          	               	197       	99B1      	GND                 
          	               	198       	99B4      	M_A_CPU1_SA_CB<3>   
          	               	199       	99B1      	GND                 
          	               	200       	99B2      	M_A_CPU1_SA_DQS_DN<9>
          	               	201       	99B2      	M_A_CPU1_SA_DQS_DP<9>
          	               	202       	99B1      	GND                 
          	               	203       	99B4      	M_A_CPU1_SA_CB<6>   
          	               	204       	99B1      	GND                 
          	               	205       	99B4      	M_A_CPU1_SA_CB<7>   
          	               	206       	99B1      	GND                 
          	               	207       	99B4      	RST_M_AB_CPU1_FPGA_N
          	               	208       	99B1      	GND                 
          	               	209       	99B4      	M_A_CPU1_SA_CS_N<3> 
          	               	210       	99B1      	GND                 
          	               	211       	99B4      	M_A_CPU1_SA_CA<1>   
          	               	212       	99B1      	GND                 
          	               	213       	99B4      	M_A_CPU1_SA_CA<3>   
          	               	214       	99B1      	GND                 
          	               	215       	99B4      	M_A_CPU1_SA_CA<5>   
          	               	216       	99B1      	GND                 
          	               	217       	99B4      	M_A_CPU1_CLK_DP<1>  
          	               	218       	99B4      	M_A_CPU1_CLK_DN<1>  
          	               	219       	99B1      	GND                 
          	               	220       	99B4      	TP_CHA_CPU1_DIMM2_FRU_4
          	               	221       	99B4      	M_A_CPU1_SB_CA<1>   
          	               	222       	99B1      	GND                 
          	               	223       	99B4      	M_A_CPU1_SB_CA<3>   
          	               	224       	99B1      	GND                 
          	               	225       	99B4      	M_A_CPU1_SB_CA<5>   
          	               	226       	99B1      	GND                 
          	               	227       	99B4      	M_A_CPU1_SB_PAR     
          	               	228       	99B1      	GND                 
          	               	229       	99B4      	M_A_CPU1_SB_CS_N<3> 
          	               	230       	99B1      	GND                 
          	               	231       	99B4      	TP_CHA_CPU1_DIMM2_FRU_5
          	               	232       	99B4      	TP_CHA_CPU1_DIMM2_FRU_6
          	               	233       	99B1      	GND                 
          	               	234       	99B4      	M_A_CPU1_SB_CB<6>   
          	               	235       	99B1      	GND                 
          	               	236       	99B4      	M_A_CPU1_SB_CB<7>   
          	               	237       	99B1      	GND                 
          	               	238       	99B2      	M_A_CPU1_SB_DQS_DN<4>
          	               	239       	99B2      	M_A_CPU1_SB_DQS_DP<4>
          	               	240       	99B1      	GND                 
          	               	241       	99B4      	M_A_CPU1_SB_CB<2>   
          	               	242       	99B1      	GND                 
          	               	243       	99B4      	M_A_CPU1_SB_CB<3>   
          	               	244       	99B1      	GND                 
          	               	245       	99B4      	M_A_CPU1_SB_DQ<2>   
          	               	246       	99B1      	GND                 
          	               	247       	99B4      	M_A_CPU1_SB_DQ<3>   
          	               	248       	99B1      	GND                 
          	               	249       	99B2      	M_A_CPU1_SB_DQS_DN<5>
          	               	250       	99B2      	M_A_CPU1_SB_DQS_DP<5>
          	               	251       	99B1      	GND                 
          	               	252       	99B4      	M_A_CPU1_SB_DQ<6>   
          	               	253       	99B1      	GND                 
          	               	254       	99B4      	M_A_CPU1_SB_DQ<7>   
          	               	255       	99B1      	GND                 
          	               	256       	99B4      	M_A_CPU1_SB_DQ<10>  
          	               	257       	99B1      	GND                 
          	               	258       	99B4      	M_A_CPU1_SB_DQ<11>  
          	               	259       	99B1      	GND                 
          	               	260       	99B2      	M_A_CPU1_SB_DQS_DN<6>
          	               	261       	99B2      	M_A_CPU1_SB_DQS_DP<6>
          	               	262       	99B1      	GND                 
          	               	263       	99B4      	M_A_CPU1_SB_DQ<14>  
          	               	264       	99B1      	GND                 
          	               	265       	99B4      	M_A_CPU1_SB_DQ<15>  
          	               	266       	99B1      	GND                 
          	               	267       	99B4      	M_A_CPU1_SB_DQ<18>  
          	               	268       	99B1      	GND                 
          	               	269       	99B4      	M_A_CPU1_SB_DQ<19>  
          	               	270       	99B1      	GND                 
          	               	271       	99B2      	M_A_CPU1_SB_DQS_DN<7>
          	               	272       	99B2      	M_A_CPU1_SB_DQS_DP<7>
          	               	273       	99B1      	GND                 
          	               	274       	99B4      	M_A_CPU1_SB_DQ<22>  
          	               	275       	99B1      	GND                 
          	               	276       	99B4      	M_A_CPU1_SB_DQ<23>  
          	               	277       	99B1      	GND                 
          	               	278       	99B4      	M_A_CPU1_SB_DQ<26>  
          	               	279       	99B1      	GND                 
          	               	280       	99B4      	M_A_CPU1_SB_DQ<27>  
          	               	281       	99B1      	GND                 
          	               	282       	99B2      	M_A_CPU1_SB_DQS_DN<8>
          	               	283       	99B2      	M_A_CPU1_SB_DQS_DP<8>
          	               	284       	99B1      	GND                 
          	               	285       	99B4      	M_A_CPU1_SB_DQ<30>  
          	               	286       	99B1      	GND                 
          	               	287       	99B4      	M_A_CPU1_SB_DQ<31>  
          	               	288       	99B1      	GND                 
          	               	G1        	99B1      	GND                 
          	               	G2        	99A1      	GND                 
          	               	G3        	99A1      	GND                 

J19       	SCONN288_ADR50017P130CC	          	          	                    
          	               	1         	100B1     	P12V_S3_AUX_CPU1_NVDIMM
          	               	2         	100B4     	TP_CHB_CPU1_DIMM1_FRU_0
          	               	3         	100B4     	P3V3_AUX            
          	               	4         	100B4     	I3C_SPD_DDRABCD_CPU1_LVC1_SCL_2
          	               	5         	100B4     	I3C_SPD_DDRABCD_CPU1_LVC1_SDA
          	               	6         	100B1     	GND                 
          	               	7         	100B4     	M_B_CPU1_SA_DQ<0>   
          	               	8         	100B1     	GND                 
          	               	9         	100B4     	M_B_CPU1_SA_DQ<1>   
          	               	10        	100B1     	GND                 
          	               	11        	100B2     	M_B_CPU1_SA_DQS_DP<0>
          	               	12        	100B2     	M_B_CPU1_SA_DQS_DN<0>
          	               	13        	100B1     	GND                 
          	               	14        	100B4     	M_B_CPU1_SA_DQ<4>   
          	               	15        	100B1     	GND                 
          	               	16        	100B4     	M_B_CPU1_SA_DQ<5>   
          	               	17        	100B1     	GND                 
          	               	18        	100B4     	M_B_CPU1_SA_DQ<8>   
          	               	19        	100B1     	GND                 
          	               	20        	100B4     	M_B_CPU1_SA_DQ<9>   
          	               	21        	100B1     	GND                 
          	               	22        	100B2     	M_B_CPU1_SA_DQS_DP<1>
          	               	23        	100B2     	M_B_CPU1_SA_DQS_DN<1>
          	               	24        	100B1     	GND                 
          	               	25        	100B4     	M_B_CPU1_SA_DQ<12>  
          	               	26        	100B1     	GND                 
          	               	27        	100B4     	M_B_CPU1_SA_DQ<13>  
          	               	28        	100B1     	GND                 
          	               	29        	100B4     	M_B_CPU1_SA_DQ<16>  
          	               	30        	100B1     	GND                 
          	               	31        	100B4     	M_B_CPU1_SA_DQ<17>  
          	               	32        	100B1     	GND                 
          	               	33        	100B2     	M_B_CPU1_SA_DQS_DP<2>
          	               	34        	100B2     	M_B_CPU1_SA_DQS_DN<2>
          	               	35        	100B1     	GND                 
          	               	36        	100B4     	M_B_CPU1_SA_DQ<20>  
          	               	37        	100B1     	GND                 
          	               	38        	100B4     	M_B_CPU1_SA_DQ<21>  
          	               	39        	100B1     	GND                 
          	               	40        	100B4     	M_B_CPU1_SA_DQ<24>  
          	               	41        	100B1     	GND                 
          	               	42        	100B4     	M_B_CPU1_SA_DQ<25>  
          	               	43        	100B1     	GND                 
          	               	44        	100B2     	M_B_CPU1_SA_DQS_DP<3>
          	               	45        	100B2     	M_B_CPU1_SA_DQS_DN<3>
          	               	46        	100B1     	GND                 
          	               	47        	100B4     	M_B_CPU1_SA_DQ<28>  
          	               	48        	100B1     	GND                 
          	               	49        	100B4     	M_B_CPU1_SA_DQ<29>  
          	               	50        	100B1     	GND                 
          	               	51        	100B4     	M_B_CPU1_SA_CB<0>   
          	               	52        	100B1     	GND                 
          	               	53        	100B4     	M_B_CPU1_SA_CB<1>   
          	               	54        	100B1     	GND                 
          	               	55        	100B2     	M_B_CPU1_SA_DQS_DP<4>
          	               	56        	100B2     	M_B_CPU1_SA_DQS_DN<4>
          	               	57        	100B1     	GND                 
          	               	58        	100B4     	M_B_CPU1_SA_CB<4>   
          	               	59        	100B1     	GND                 
          	               	60        	100B4     	M_B_CPU1_SA_CB<5>   
          	               	61        	100B1     	GND                 
          	               	62        	100B4     	M_B_CPU1_ALERT_N    
          	               	63        	100B1     	GND                 
          	               	64        	100B4     	M_B_CPU1_SA_CS_N<0> 
          	               	65        	100B1     	GND                 
          	               	66        	100B4     	M_B_CPU1_SA_CA<0>   
          	               	67        	100B1     	GND                 
          	               	68        	100B4     	M_B_CPU1_SA_CA<2>   
          	               	69        	100B1     	GND                 
          	               	70        	100B4     	M_B_CPU1_SA_CA<4>   
          	               	71        	100B1     	GND                 
          	               	72        	100B4     	M_B_CPU1_SA_CA<6>   
          	               	73        	100B1     	GND                 
          	               	74        	100B4     	M_B_CPU1_SA_PAR     
          	               	75        	100B1     	GND                 
          	               	76        	100B4     	M_B_CPU1_SB_CA<0>   
          	               	77        	100B1     	GND                 
          	               	78        	100B4     	M_B_CPU1_SB_CA<2>   
          	               	79        	100B1     	GND                 
          	               	80        	100B4     	M_B_CPU1_SB_CA<4>   
          	               	81        	100B1     	GND                 
          	               	82        	100B4     	M_B_CPU1_SB_CA<6>   
          	               	83        	100B1     	GND                 
          	               	84        	100B4     	M_B_CPU1_SB_CS_N<0> 
          	               	85        	100B1     	GND                 
          	               	86        	100A4     	M_B_CPU1_SA_RSP<0>  
          	               	87        	100A4     	M_B_CPU1_SB_RSP<0>  
          	               	88        	100B1     	GND                 
          	               	89        	100B4     	M_B_CPU1_SB_CB<4>   
          	               	90        	100B1     	GND                 
          	               	91        	100B4     	M_B_CPU1_SB_CB<5>   
          	               	92        	100B1     	GND                 
          	               	93        	100B2     	M_B_CPU1_SB_DQS_DP<9>
          	               	94        	100B2     	M_B_CPU1_SB_DQS_DN<9>
          	               	95        	100B1     	GND                 
          	               	96        	100B4     	M_B_CPU1_SB_CB<0>   
          	               	97        	100B1     	GND                 
          	               	98        	100B4     	M_B_CPU1_SB_CB<1>   
          	               	99        	100B1     	GND                 
          	               	100       	100B4     	M_B_CPU1_SB_DQ<0>   
          	               	101       	100B1     	GND                 
          	               	102       	100B4     	M_B_CPU1_SB_DQ<1>   
          	               	103       	100B1     	GND                 
          	               	104       	100B2     	M_B_CPU1_SB_DQS_DP<0>
          	               	105       	100B2     	M_B_CPU1_SB_DQS_DN<0>
          	               	106       	100B1     	GND                 
          	               	107       	100B4     	M_B_CPU1_SB_DQ<4>   
          	               	108       	100B1     	GND                 
          	               	109       	100B4     	M_B_CPU1_SB_DQ<5>   
          	               	110       	100B1     	GND                 
          	               	111       	100B4     	M_B_CPU1_SB_DQ<8>   
          	               	112       	100B1     	GND                 
          	               	113       	100B4     	M_B_CPU1_SB_DQ<9>   
          	               	114       	100B1     	GND                 
          	               	115       	100B2     	M_B_CPU1_SB_DQS_DP<1>
          	               	116       	100B2     	M_B_CPU1_SB_DQS_DN<1>
          	               	117       	100B1     	GND                 
          	               	118       	100B4     	M_B_CPU1_SB_DQ<12>  
          	               	119       	100B1     	GND                 
          	               	120       	100B4     	M_B_CPU1_SB_DQ<13>  
          	               	121       	100B1     	GND                 
          	               	122       	100B4     	M_B_CPU1_SB_DQ<16>  
          	               	123       	100B1     	GND                 
          	               	124       	100B4     	M_B_CPU1_SB_DQ<17>  
          	               	125       	100B1     	GND                 
          	               	126       	100B2     	M_B_CPU1_SB_DQS_DP<2>
          	               	127       	100B2     	M_B_CPU1_SB_DQS_DN<2>
          	               	128       	100B1     	GND                 
          	               	129       	100B4     	M_B_CPU1_SB_DQ<20>  
          	               	130       	100B1     	GND                 
          	               	131       	100B4     	M_B_CPU1_SB_DQ<21>  
          	               	132       	100B1     	GND                 
          	               	133       	100B4     	M_B_CPU1_SB_DQ<24>  
          	               	134       	100B1     	GND                 
          	               	135       	100B4     	M_B_CPU1_SB_DQ<25>  
          	               	136       	100B1     	GND                 
          	               	137       	100B2     	M_B_CPU1_SB_DQS_DP<3>
          	               	138       	100B2     	M_B_CPU1_SB_DQS_DN<3>
          	               	139       	100B1     	GND                 
          	               	140       	100B4     	M_B_CPU1_SB_DQ<28>  
          	               	141       	100B1     	GND                 
          	               	142       	100B4     	M_B_CPU1_SB_DQ<29>  
          	               	143       	100B1     	GND                 
          	               	144       	100B4     	TP_CHB_CPU1_DIMM1_FRU_1
          	               	145       	100B1     	P12V_S3_AUX_CPU1_NVDIMM
          	               	146       	100B1     	P12V_S3_AUX_CPU1_NVDIMM
          	               	147       	100B4     	PWRGD_CHB_CPU1_DIMM1
          	               	148       	100B4     	PD_CHB_CPU1_DIMM1_SAA
          	               	149       	100B4     	TP_CHB_CPU1_DIMM1_FRU_2
          	               	150       	100B4     	TP_CHB_CPU1_DIMM1_FRU_3
          	               	151       	100B1     	GND                 
          	               	152       	100B4     	M_B_CPU1_SA_DQ<2>   
          	               	153       	100B1     	GND                 
          	               	154       	100B4     	M_B_CPU1_SA_DQ<3>   
          	               	155       	100B1     	GND                 
          	               	156       	100B2     	M_B_CPU1_SA_DQS_DN<5>
          	               	157       	100B2     	M_B_CPU1_SA_DQS_DP<5>
          	               	158       	100B1     	GND                 
          	               	159       	100B4     	M_B_CPU1_SA_DQ<6>   
          	               	160       	100B1     	GND                 
          	               	161       	100B4     	M_B_CPU1_SA_DQ<7>   
          	               	162       	100B1     	GND                 
          	               	163       	100B4     	M_B_CPU1_SA_DQ<10>  
          	               	164       	100B1     	GND                 
          	               	165       	100B4     	M_B_CPU1_SA_DQ<11>  
          	               	166       	100B1     	GND                 
          	               	167       	100B2     	M_B_CPU1_SA_DQS_DN<6>
          	               	168       	100B2     	M_B_CPU1_SA_DQS_DP<6>
          	               	169       	100B1     	GND                 
          	               	170       	100B4     	M_B_CPU1_SA_DQ<14>  
          	               	171       	100B1     	GND                 
          	               	172       	100B4     	M_B_CPU1_SA_DQ<15>  
          	               	173       	100B1     	GND                 
          	               	174       	100B4     	M_B_CPU1_SA_DQ<18>  
          	               	175       	100B1     	GND                 
          	               	176       	100B4     	M_B_CPU1_SA_DQ<19>  
          	               	177       	100B1     	GND                 
          	               	178       	100B2     	M_B_CPU1_SA_DQS_DN<7>
          	               	179       	100B2     	M_B_CPU1_SA_DQS_DP<7>
          	               	180       	100B1     	GND                 
          	               	181       	100B4     	M_B_CPU1_SA_DQ<22>  
          	               	182       	100B1     	GND                 
          	               	183       	100B4     	M_B_CPU1_SA_DQ<23>  
          	               	184       	100B1     	GND                 
          	               	185       	100B4     	M_B_CPU1_SA_DQ<26>  
          	               	186       	100B1     	GND                 
          	               	187       	100B4     	M_B_CPU1_SA_DQ<27>  
          	               	188       	100B1     	GND                 
          	               	189       	100B2     	M_B_CPU1_SA_DQS_DN<8>
          	               	190       	100B2     	M_B_CPU1_SA_DQS_DP<8>
          	               	191       	100B1     	GND                 
          	               	192       	100B4     	M_B_CPU1_SA_DQ<30>  
          	               	193       	100B1     	GND                 
          	               	194       	100B4     	M_B_CPU1_SA_DQ<31>  
          	               	195       	100B1     	GND                 
          	               	196       	100B4     	M_B_CPU1_SA_CB<2>   
          	               	197       	100B1     	GND                 
          	               	198       	100B4     	M_B_CPU1_SA_CB<3>   
          	               	199       	100B1     	GND                 
          	               	200       	100B2     	M_B_CPU1_SA_DQS_DN<9>
          	               	201       	100B2     	M_B_CPU1_SA_DQS_DP<9>
          	               	202       	100B1     	GND                 
          	               	203       	100B4     	M_B_CPU1_SA_CB<6>   
          	               	204       	100B1     	GND                 
          	               	205       	100B4     	M_B_CPU1_SA_CB<7>   
          	               	206       	100B1     	GND                 
          	               	207       	100B4     	RST_M_AB_CPU1_FPGA_N
          	               	208       	100B1     	GND                 
          	               	209       	100B4     	M_B_CPU1_SA_CS_N<1> 
          	               	210       	100B1     	GND                 
          	               	211       	100B4     	M_B_CPU1_SA_CA<1>   
          	               	212       	100B1     	GND                 
          	               	213       	100B4     	M_B_CPU1_SA_CA<3>   
          	               	214       	100B1     	GND                 
          	               	215       	100B4     	M_B_CPU1_SA_CA<5>   
          	               	216       	100B1     	GND                 
          	               	217       	100B4     	M_B_CPU1_CLK_DP<0>  
          	               	218       	100B4     	M_B_CPU1_CLK_DN<0>  
          	               	219       	100B1     	GND                 
          	               	220       	100B4     	TP_CHB_CPU1_DIMM1_FRU_4
          	               	221       	100B4     	M_B_CPU1_SB_CA<1>   
          	               	222       	100B1     	GND                 
          	               	223       	100B4     	M_B_CPU1_SB_CA<3>   
          	               	224       	100B1     	GND                 
          	               	225       	100B4     	M_B_CPU1_SB_CA<5>   
          	               	226       	100B1     	GND                 
          	               	227       	100B4     	M_B_CPU1_SB_PAR     
          	               	228       	100B1     	GND                 
          	               	229       	100B4     	M_B_CPU1_SB_CS_N<1> 
          	               	230       	100B1     	GND                 
          	               	231       	100B4     	TP_CHB_CPU1_DIMM1_FRU_5
          	               	232       	100B4     	TP_CHB_CPU1_DIMM1_FRU_6
          	               	233       	100B1     	GND                 
          	               	234       	100B4     	M_B_CPU1_SB_CB<6>   
          	               	235       	100B1     	GND                 
          	               	236       	100B4     	M_B_CPU1_SB_CB<7>   
          	               	237       	100B1     	GND                 
          	               	238       	100B2     	M_B_CPU1_SB_DQS_DN<4>
          	               	239       	100B2     	M_B_CPU1_SB_DQS_DP<4>
          	               	240       	100B1     	GND                 
          	               	241       	100B4     	M_B_CPU1_SB_CB<2>   
          	               	242       	100B1     	GND                 
          	               	243       	100B4     	M_B_CPU1_SB_CB<3>   
          	               	244       	100B1     	GND                 
          	               	245       	100B4     	M_B_CPU1_SB_DQ<2>   
          	               	246       	100B1     	GND                 
          	               	247       	100B4     	M_B_CPU1_SB_DQ<3>   
          	               	248       	100B1     	GND                 
          	               	249       	100B2     	M_B_CPU1_SB_DQS_DN<5>
          	               	250       	100B2     	M_B_CPU1_SB_DQS_DP<5>
          	               	251       	100B1     	GND                 
          	               	252       	100B4     	M_B_CPU1_SB_DQ<6>   
          	               	253       	100B1     	GND                 
          	               	254       	100B4     	M_B_CPU1_SB_DQ<7>   
          	               	255       	100B1     	GND                 
          	               	256       	100B4     	M_B_CPU1_SB_DQ<10>  
          	               	257       	100B1     	GND                 
          	               	258       	100B4     	M_B_CPU1_SB_DQ<11>  
          	               	259       	100B1     	GND                 
          	               	260       	100B2     	M_B_CPU1_SB_DQS_DN<6>
          	               	261       	100B2     	M_B_CPU1_SB_DQS_DP<6>
          	               	262       	100B1     	GND                 
          	               	263       	100B4     	M_B_CPU1_SB_DQ<14>  
          	               	264       	100B1     	GND                 
          	               	265       	100B4     	M_B_CPU1_SB_DQ<15>  
          	               	266       	100B1     	GND                 
          	               	267       	100B4     	M_B_CPU1_SB_DQ<18>  
          	               	268       	100B1     	GND                 
          	               	269       	100B4     	M_B_CPU1_SB_DQ<19>  
          	               	270       	100B1     	GND                 
          	               	271       	100B2     	M_B_CPU1_SB_DQS_DN<7>
          	               	272       	100B2     	M_B_CPU1_SB_DQS_DP<7>
          	               	273       	100B1     	GND                 
          	               	274       	100B4     	M_B_CPU1_SB_DQ<22>  
          	               	275       	100B1     	GND                 
          	               	276       	100B4     	M_B_CPU1_SB_DQ<23>  
          	               	277       	100B1     	GND                 
          	               	278       	100B4     	M_B_CPU1_SB_DQ<26>  
          	               	279       	100B1     	GND                 
          	               	280       	100B4     	M_B_CPU1_SB_DQ<27>  
          	               	281       	100B1     	GND                 
          	               	282       	100B2     	M_B_CPU1_SB_DQS_DN<8>
          	               	283       	100B2     	M_B_CPU1_SB_DQS_DP<8>
          	               	284       	100B1     	GND                 
          	               	285       	100B4     	M_B_CPU1_SB_DQ<30>  
          	               	286       	100B1     	GND                 
          	               	287       	100B4     	M_B_CPU1_SB_DQ<31>  
          	               	288       	100B1     	GND                 
          	               	G1        	100B1     	GND                 
          	               	G2        	100A1     	GND                 
          	               	G3        	100A1     	GND                 

J20       	SCONN288_ADR50017P087CC	          	          	                    
          	               	1         	101B1     	P12V_S3_AUX_CPU1_NVDIMM
          	               	2         	101B4     	TP_CHB_CPU1_DIMM2_FRU_0
          	               	3         	101B4     	P3V3_AUX            
          	               	4         	101B4     	I3C_SPD_DDRABCD_CPU1_LVC1_SCL_3
          	               	5         	101B4     	I3C_SPD_DDRABCD_CPU1_LVC1_SDA
          	               	6         	101B1     	GND                 
          	               	7         	101B4     	M_B_CPU1_SA_DQ<0>   
          	               	8         	101B1     	GND                 
          	               	9         	101B4     	M_B_CPU1_SA_DQ<1>   
          	               	10        	101B1     	GND                 
          	               	11        	101B2     	M_B_CPU1_SA_DQS_DP<0>
          	               	12        	101B2     	M_B_CPU1_SA_DQS_DN<0>
          	               	13        	101B1     	GND                 
          	               	14        	101B4     	M_B_CPU1_SA_DQ<4>   
          	               	15        	101B1     	GND                 
          	               	16        	101B4     	M_B_CPU1_SA_DQ<5>   
          	               	17        	101B1     	GND                 
          	               	18        	101B4     	M_B_CPU1_SA_DQ<8>   
          	               	19        	101B1     	GND                 
          	               	20        	101B4     	M_B_CPU1_SA_DQ<9>   
          	               	21        	101B1     	GND                 
          	               	22        	101B2     	M_B_CPU1_SA_DQS_DP<1>
          	               	23        	101B2     	M_B_CPU1_SA_DQS_DN<1>
          	               	24        	101B1     	GND                 
          	               	25        	101B4     	M_B_CPU1_SA_DQ<12>  
          	               	26        	101B1     	GND                 
          	               	27        	101B4     	M_B_CPU1_SA_DQ<13>  
          	               	28        	101B1     	GND                 
          	               	29        	101B4     	M_B_CPU1_SA_DQ<16>  
          	               	30        	101B1     	GND                 
          	               	31        	101B4     	M_B_CPU1_SA_DQ<17>  
          	               	32        	101B1     	GND                 
          	               	33        	101B2     	M_B_CPU1_SA_DQS_DP<2>
          	               	34        	101B2     	M_B_CPU1_SA_DQS_DN<2>
          	               	35        	101B1     	GND                 
          	               	36        	101B4     	M_B_CPU1_SA_DQ<20>  
          	               	37        	101B1     	GND                 
          	               	38        	101B4     	M_B_CPU1_SA_DQ<21>  
          	               	39        	101B1     	GND                 
          	               	40        	101B4     	M_B_CPU1_SA_DQ<24>  
          	               	41        	101B1     	GND                 
          	               	42        	101B4     	M_B_CPU1_SA_DQ<25>  
          	               	43        	101B1     	GND                 
          	               	44        	101B2     	M_B_CPU1_SA_DQS_DP<3>
          	               	45        	101B2     	M_B_CPU1_SA_DQS_DN<3>
          	               	46        	101B1     	GND                 
          	               	47        	101B4     	M_B_CPU1_SA_DQ<28>  
          	               	48        	101B1     	GND                 
          	               	49        	101B4     	M_B_CPU1_SA_DQ<29>  
          	               	50        	101B1     	GND                 
          	               	51        	101B4     	M_B_CPU1_SA_CB<0>   
          	               	52        	101B1     	GND                 
          	               	53        	101B4     	M_B_CPU1_SA_CB<1>   
          	               	54        	101B1     	GND                 
          	               	55        	101B2     	M_B_CPU1_SA_DQS_DP<4>
          	               	56        	101B2     	M_B_CPU1_SA_DQS_DN<4>
          	               	57        	101B1     	GND                 
          	               	58        	101B4     	M_B_CPU1_SA_CB<4>   
          	               	59        	101B1     	GND                 
          	               	60        	101B4     	M_B_CPU1_SA_CB<5>   
          	               	61        	101B1     	GND                 
          	               	62        	101B4     	M_B_CPU1_ALERT_N    
          	               	63        	101B1     	GND                 
          	               	64        	101B4     	M_B_CPU1_SA_CS_N<2> 
          	               	65        	101B1     	GND                 
          	               	66        	101B4     	M_B_CPU1_SA_CA<0>   
          	               	67        	101B1     	GND                 
          	               	68        	101B4     	M_B_CPU1_SA_CA<2>   
          	               	69        	101B1     	GND                 
          	               	70        	101B4     	M_B_CPU1_SA_CA<4>   
          	               	71        	101B1     	GND                 
          	               	72        	101B4     	M_B_CPU1_SA_CA<6>   
          	               	73        	101B1     	GND                 
          	               	74        	101B4     	M_B_CPU1_SA_PAR     
          	               	75        	101B1     	GND                 
          	               	76        	101B4     	M_B_CPU1_SB_CA<0>   
          	               	77        	101B1     	GND                 
          	               	78        	101B4     	M_B_CPU1_SB_CA<2>   
          	               	79        	101B1     	GND                 
          	               	80        	101B4     	M_B_CPU1_SB_CA<4>   
          	               	81        	101B1     	GND                 
          	               	82        	101B4     	M_B_CPU1_SB_CA<6>   
          	               	83        	101B1     	GND                 
          	               	84        	101B4     	M_B_CPU1_SB_CS_N<2> 
          	               	85        	101B1     	GND                 
          	               	86        	101A4     	M_B_CPU1_SA_RSP<1>  
          	               	87        	101A4     	M_B_CPU1_SB_RSP<1>  
          	               	88        	101B1     	GND                 
          	               	89        	101B4     	M_B_CPU1_SB_CB<4>   
          	               	90        	101B1     	GND                 
          	               	91        	101B4     	M_B_CPU1_SB_CB<5>   
          	               	92        	101B1     	GND                 
          	               	93        	101B2     	M_B_CPU1_SB_DQS_DP<9>
          	               	94        	101B2     	M_B_CPU1_SB_DQS_DN<9>
          	               	95        	101B1     	GND                 
          	               	96        	101B4     	M_B_CPU1_SB_CB<0>   
          	               	97        	101B1     	GND                 
          	               	98        	101B4     	M_B_CPU1_SB_CB<1>   
          	               	99        	101B1     	GND                 
          	               	100       	101B4     	M_B_CPU1_SB_DQ<0>   
          	               	101       	101B1     	GND                 
          	               	102       	101B4     	M_B_CPU1_SB_DQ<1>   
          	               	103       	101B1     	GND                 
          	               	104       	101B2     	M_B_CPU1_SB_DQS_DP<0>
          	               	105       	101B2     	M_B_CPU1_SB_DQS_DN<0>
          	               	106       	101B1     	GND                 
          	               	107       	101B4     	M_B_CPU1_SB_DQ<4>   
          	               	108       	101B1     	GND                 
          	               	109       	101B4     	M_B_CPU1_SB_DQ<5>   
          	               	110       	101B1     	GND                 
          	               	111       	101B4     	M_B_CPU1_SB_DQ<8>   
          	               	112       	101B1     	GND                 
          	               	113       	101B4     	M_B_CPU1_SB_DQ<9>   
          	               	114       	101B1     	GND                 
          	               	115       	101B2     	M_B_CPU1_SB_DQS_DP<1>
          	               	116       	101B2     	M_B_CPU1_SB_DQS_DN<1>
          	               	117       	101B1     	GND                 
          	               	118       	101B4     	M_B_CPU1_SB_DQ<12>  
          	               	119       	101B1     	GND                 
          	               	120       	101B4     	M_B_CPU1_SB_DQ<13>  
          	               	121       	101B1     	GND                 
          	               	122       	101B4     	M_B_CPU1_SB_DQ<16>  
          	               	123       	101B1     	GND                 
          	               	124       	101B4     	M_B_CPU1_SB_DQ<17>  
          	               	125       	101B1     	GND                 
          	               	126       	101B2     	M_B_CPU1_SB_DQS_DP<2>
          	               	127       	101B2     	M_B_CPU1_SB_DQS_DN<2>
          	               	128       	101B1     	GND                 
          	               	129       	101B4     	M_B_CPU1_SB_DQ<20>  
          	               	130       	101B1     	GND                 
          	               	131       	101B4     	M_B_CPU1_SB_DQ<21>  
          	               	132       	101B1     	GND                 
          	               	133       	101B4     	M_B_CPU1_SB_DQ<24>  
          	               	134       	101B1     	GND                 
          	               	135       	101B4     	M_B_CPU1_SB_DQ<25>  
          	               	136       	101B1     	GND                 
          	               	137       	101B2     	M_B_CPU1_SB_DQS_DP<3>
          	               	138       	101B2     	M_B_CPU1_SB_DQS_DN<3>
          	               	139       	101B1     	GND                 
          	               	140       	101B4     	M_B_CPU1_SB_DQ<28>  
          	               	141       	101B1     	GND                 
          	               	142       	101B4     	M_B_CPU1_SB_DQ<29>  
          	               	143       	101B1     	GND                 
          	               	144       	101B4     	TP_CHB_CPU1_DIMM2_FRU_1
          	               	145       	101B1     	P12V_S3_AUX_CPU1_NVDIMM
          	               	146       	101B1     	P12V_S3_AUX_CPU1_NVDIMM
          	               	147       	101B4     	PWRGD_CHB_CPU1_DIMM2
          	               	148       	101B4     	PD_CHB_CPU1_DIMM2_SAA
          	               	149       	101B4     	TP_CHB_CPU1_DIMM2_FRU_2
          	               	150       	101B4     	TP_CHB_CPU1_DIMM2_FRU_3
          	               	151       	101B1     	GND                 
          	               	152       	101B4     	M_B_CPU1_SA_DQ<2>   
          	               	153       	101B1     	GND                 
          	               	154       	101B4     	M_B_CPU1_SA_DQ<3>   
          	               	155       	101B1     	GND                 
          	               	156       	101B2     	M_B_CPU1_SA_DQS_DN<5>
          	               	157       	101B2     	M_B_CPU1_SA_DQS_DP<5>
          	               	158       	101B1     	GND                 
          	               	159       	101B4     	M_B_CPU1_SA_DQ<6>   
          	               	160       	101B1     	GND                 
          	               	161       	101B4     	M_B_CPU1_SA_DQ<7>   
          	               	162       	101B1     	GND                 
          	               	163       	101B4     	M_B_CPU1_SA_DQ<10>  
          	               	164       	101B1     	GND                 
          	               	165       	101B4     	M_B_CPU1_SA_DQ<11>  
          	               	166       	101B1     	GND                 
          	               	167       	101B2     	M_B_CPU1_SA_DQS_DN<6>
          	               	168       	101B2     	M_B_CPU1_SA_DQS_DP<6>
          	               	169       	101B1     	GND                 
          	               	170       	101B4     	M_B_CPU1_SA_DQ<14>  
          	               	171       	101B1     	GND                 
          	               	172       	101B4     	M_B_CPU1_SA_DQ<15>  
          	               	173       	101B1     	GND                 
          	               	174       	101B4     	M_B_CPU1_SA_DQ<18>  
          	               	175       	101B1     	GND                 
          	               	176       	101B4     	M_B_CPU1_SA_DQ<19>  
          	               	177       	101B1     	GND                 
          	               	178       	101B2     	M_B_CPU1_SA_DQS_DN<7>
          	               	179       	101B2     	M_B_CPU1_SA_DQS_DP<7>
          	               	180       	101B1     	GND                 
          	               	181       	101B4     	M_B_CPU1_SA_DQ<22>  
          	               	182       	101B1     	GND                 
          	               	183       	101B4     	M_B_CPU1_SA_DQ<23>  
          	               	184       	101B1     	GND                 
          	               	185       	101B4     	M_B_CPU1_SA_DQ<26>  
          	               	186       	101B1     	GND                 
          	               	187       	101B4     	M_B_CPU1_SA_DQ<27>  
          	               	188       	101B1     	GND                 
          	               	189       	101B2     	M_B_CPU1_SA_DQS_DN<8>
          	               	190       	101B2     	M_B_CPU1_SA_DQS_DP<8>
          	               	191       	101B1     	GND                 
          	               	192       	101B4     	M_B_CPU1_SA_DQ<30>  
          	               	193       	101B1     	GND                 
          	               	194       	101B4     	M_B_CPU1_SA_DQ<31>  
          	               	195       	101B1     	GND                 
          	               	196       	101B4     	M_B_CPU1_SA_CB<2>   
          	               	197       	101B1     	GND                 
          	               	198       	101B4     	M_B_CPU1_SA_CB<3>   
          	               	199       	101B1     	GND                 
          	               	200       	101B2     	M_B_CPU1_SA_DQS_DN<9>
          	               	201       	101B2     	M_B_CPU1_SA_DQS_DP<9>
          	               	202       	101B1     	GND                 
          	               	203       	101B4     	M_B_CPU1_SA_CB<6>   
          	               	204       	101B1     	GND                 
          	               	205       	101B4     	M_B_CPU1_SA_CB<7>   
          	               	206       	101B1     	GND                 
          	               	207       	101B4     	RST_M_AB_CPU1_FPGA_N
          	               	208       	101B1     	GND                 
          	               	209       	101B4     	M_B_CPU1_SA_CS_N<3> 
          	               	210       	101B1     	GND                 
          	               	211       	101B4     	M_B_CPU1_SA_CA<1>   
          	               	212       	101B1     	GND                 
          	               	213       	101B4     	M_B_CPU1_SA_CA<3>   
          	               	214       	101B1     	GND                 
          	               	215       	101B4     	M_B_CPU1_SA_CA<5>   
          	               	216       	101B1     	GND                 
          	               	217       	101B4     	M_B_CPU1_CLK_DP<1>  
          	               	218       	101B4     	M_B_CPU1_CLK_DN<1>  
          	               	219       	101B1     	GND                 
          	               	220       	101B4     	TP_CHB_CPU1_DIMM2_FRU_4
          	               	221       	101B4     	M_B_CPU1_SB_CA<1>   
          	               	222       	101B1     	GND                 
          	               	223       	101B4     	M_B_CPU1_SB_CA<3>   
          	               	224       	101B1     	GND                 
          	               	225       	101B4     	M_B_CPU1_SB_CA<5>   
          	               	226       	101B1     	GND                 
          	               	227       	101B4     	M_B_CPU1_SB_PAR     
          	               	228       	101B1     	GND                 
          	               	229       	101B4     	M_B_CPU1_SB_CS_N<3> 
          	               	230       	101B1     	GND                 
          	               	231       	101B4     	TP_CHB_CPU1_DIMM2_FRU_5
          	               	232       	101B4     	TP_CHB_CPU1_DIMM2_FRU_6
          	               	233       	101B1     	GND                 
          	               	234       	101B4     	M_B_CPU1_SB_CB<6>   
          	               	235       	101B1     	GND                 
          	               	236       	101B4     	M_B_CPU1_SB_CB<7>   
          	               	237       	101B1     	GND                 
          	               	238       	101B2     	M_B_CPU1_SB_DQS_DN<4>
          	               	239       	101B2     	M_B_CPU1_SB_DQS_DP<4>
          	               	240       	101B1     	GND                 
          	               	241       	101B4     	M_B_CPU1_SB_CB<2>   
          	               	242       	101B1     	GND                 
          	               	243       	101B4     	M_B_CPU1_SB_CB<3>   
          	               	244       	101B1     	GND                 
          	               	245       	101B4     	M_B_CPU1_SB_DQ<2>   
          	               	246       	101B1     	GND                 
          	               	247       	101B4     	M_B_CPU1_SB_DQ<3>   
          	               	248       	101B1     	GND                 
          	               	249       	101B2     	M_B_CPU1_SB_DQS_DN<5>
          	               	250       	101B2     	M_B_CPU1_SB_DQS_DP<5>
          	               	251       	101B1     	GND                 
          	               	252       	101B4     	M_B_CPU1_SB_DQ<6>   
          	               	253       	101B1     	GND                 
          	               	254       	101B4     	M_B_CPU1_SB_DQ<7>   
          	               	255       	101B1     	GND                 
          	               	256       	101B4     	M_B_CPU1_SB_DQ<10>  
          	               	257       	101B1     	GND                 
          	               	258       	101B4     	M_B_CPU1_SB_DQ<11>  
          	               	259       	101B1     	GND                 
          	               	260       	101B2     	M_B_CPU1_SB_DQS_DN<6>
          	               	261       	101B2     	M_B_CPU1_SB_DQS_DP<6>
          	               	262       	101B1     	GND                 
          	               	263       	101B4     	M_B_CPU1_SB_DQ<14>  
          	               	264       	101B1     	GND                 
          	               	265       	101B4     	M_B_CPU1_SB_DQ<15>  
          	               	266       	101B1     	GND                 
          	               	267       	101B4     	M_B_CPU1_SB_DQ<18>  
          	               	268       	101B1     	GND                 
          	               	269       	101B4     	M_B_CPU1_SB_DQ<19>  
          	               	270       	101B1     	GND                 
          	               	271       	101B2     	M_B_CPU1_SB_DQS_DN<7>
          	               	272       	101B2     	M_B_CPU1_SB_DQS_DP<7>
          	               	273       	101B1     	GND                 
          	               	274       	101B4     	M_B_CPU1_SB_DQ<22>  
          	               	275       	101B1     	GND                 
          	               	276       	101B4     	M_B_CPU1_SB_DQ<23>  
          	               	277       	101B1     	GND                 
          	               	278       	101B4     	M_B_CPU1_SB_DQ<26>  
          	               	279       	101B1     	GND                 
          	               	280       	101B4     	M_B_CPU1_SB_DQ<27>  
          	               	281       	101B1     	GND                 
          	               	282       	101B2     	M_B_CPU1_SB_DQS_DN<8>
          	               	283       	101B2     	M_B_CPU1_SB_DQS_DP<8>
          	               	284       	101B1     	GND                 
          	               	285       	101B4     	M_B_CPU1_SB_DQ<30>  
          	               	286       	101B1     	GND                 
          	               	287       	101B4     	M_B_CPU1_SB_DQ<31>  
          	               	288       	101B1     	GND                 
          	               	G1        	101B1     	GND                 
          	               	G2        	101A1     	GND                 
          	               	G3        	101A1     	GND                 

J21       	SCONN288_ADR50017P130CC	          	          	                    
          	               	1         	102B1     	P12V_S3_AUX_CPU1_NVDIMM
          	               	2         	102B4     	TP_CHC_CPU1_DIMM1_FRU_0
          	               	3         	102B4     	P3V3_AUX            
          	               	4         	102B4     	I3C_SPD_DDRABCD_CPU1_LVC1_SCL_4
          	               	5         	102B4     	I3C_SPD_DDRABCD_CPU1_LVC1_SDA
          	               	6         	102B1     	GND                 
          	               	7         	102B4     	M_C_CPU1_SA_DQ<0>   
          	               	8         	102B1     	GND                 
          	               	9         	102B4     	M_C_CPU1_SA_DQ<1>   
          	               	10        	102B1     	GND                 
          	               	11        	102B2     	M_C_CPU1_SA_DQS_DP<0>
          	               	12        	102B2     	M_C_CPU1_SA_DQS_DN<0>
          	               	13        	102B1     	GND                 
          	               	14        	102B4     	M_C_CPU1_SA_DQ<4>   
          	               	15        	102B1     	GND                 
          	               	16        	102B4     	M_C_CPU1_SA_DQ<5>   
          	               	17        	102B1     	GND                 
          	               	18        	102B4     	M_C_CPU1_SA_DQ<8>   
          	               	19        	102B1     	GND                 
          	               	20        	102B4     	M_C_CPU1_SA_DQ<9>   
          	               	21        	102B1     	GND                 
          	               	22        	102B2     	M_C_CPU1_SA_DQS_DP<1>
          	               	23        	102B2     	M_C_CPU1_SA_DQS_DN<1>
          	               	24        	102B1     	GND                 
          	               	25        	102B4     	M_C_CPU1_SA_DQ<12>  
          	               	26        	102B1     	GND                 
          	               	27        	102B4     	M_C_CPU1_SA_DQ<13>  
          	               	28        	102B1     	GND                 
          	               	29        	102B4     	M_C_CPU1_SA_DQ<16>  
          	               	30        	102B1     	GND                 
          	               	31        	102B4     	M_C_CPU1_SA_DQ<17>  
          	               	32        	102B1     	GND                 
          	               	33        	102B2     	M_C_CPU1_SA_DQS_DP<2>
          	               	34        	102B2     	M_C_CPU1_SA_DQS_DN<2>
          	               	35        	102B1     	GND                 
          	               	36        	102B4     	M_C_CPU1_SA_DQ<20>  
          	               	37        	102B1     	GND                 
          	               	38        	102B4     	M_C_CPU1_SA_DQ<21>  
          	               	39        	102B1     	GND                 
          	               	40        	102B4     	M_C_CPU1_SA_DQ<24>  
          	               	41        	102B1     	GND                 
          	               	42        	102B4     	M_C_CPU1_SA_DQ<25>  
          	               	43        	102B1     	GND                 
          	               	44        	102B2     	M_C_CPU1_SA_DQS_DP<3>
          	               	45        	102B2     	M_C_CPU1_SA_DQS_DN<3>
          	               	46        	102B1     	GND                 
          	               	47        	102B4     	M_C_CPU1_SA_DQ<28>  
          	               	48        	102B1     	GND                 
          	               	49        	102B4     	M_C_CPU1_SA_DQ<29>  
          	               	50        	102B1     	GND                 
          	               	51        	102B4     	M_C_CPU1_SA_CB<0>   
          	               	52        	102B1     	GND                 
          	               	53        	102B4     	M_C_CPU1_SA_CB<1>   
          	               	54        	102B1     	GND                 
          	               	55        	102B2     	M_C_CPU1_SA_DQS_DP<4>
          	               	56        	102B2     	M_C_CPU1_SA_DQS_DN<4>
          	               	57        	102B1     	GND                 
          	               	58        	102B4     	M_C_CPU1_SA_CB<4>   
          	               	59        	102B1     	GND                 
          	               	60        	102B4     	M_C_CPU1_SA_CB<5>   
          	               	61        	102B1     	GND                 
          	               	62        	102B4     	M_C_CPU1_ALERT_N    
          	               	63        	102B1     	GND                 
          	               	64        	102B4     	M_C_CPU1_SA_CS_N<0> 
          	               	65        	102B1     	GND                 
          	               	66        	102B4     	M_C_CPU1_SA_CA<0>   
          	               	67        	102B1     	GND                 
          	               	68        	102B4     	M_C_CPU1_SA_CA<2>   
          	               	69        	102B1     	GND                 
          	               	70        	102B4     	M_C_CPU1_SA_CA<4>   
          	               	71        	102B1     	GND                 
          	               	72        	102B4     	M_C_CPU1_SA_CA<6>   
          	               	73        	102B1     	GND                 
          	               	74        	102B4     	M_C_CPU1_SA_PAR     
          	               	75        	102B1     	GND                 
          	               	76        	102B4     	M_C_CPU1_SB_CA<0>   
          	               	77        	102B1     	GND                 
          	               	78        	102B4     	M_C_CPU1_SB_CA<2>   
          	               	79        	102B1     	GND                 
          	               	80        	102B4     	M_C_CPU1_SB_CA<4>   
          	               	81        	102B1     	GND                 
          	               	82        	102B4     	M_C_CPU1_SB_CA<6>   
          	               	83        	102B1     	GND                 
          	               	84        	102B4     	M_C_CPU1_SB_CS_N<0> 
          	               	85        	102B1     	GND                 
          	               	86        	102A4     	M_C_CPU1_SA_RSP<0>  
          	               	87        	102A4     	M_C_CPU1_SB_RSP<0>  
          	               	88        	102B1     	GND                 
          	               	89        	102B4     	M_C_CPU1_SB_CB<4>   
          	               	90        	102B1     	GND                 
          	               	91        	102B4     	M_C_CPU1_SB_CB<5>   
          	               	92        	102B1     	GND                 
          	               	93        	102B2     	M_C_CPU1_SB_DQS_DP<9>
          	               	94        	102B2     	M_C_CPU1_SB_DQS_DN<9>
          	               	95        	102B1     	GND                 
          	               	96        	102B4     	M_C_CPU1_SB_CB<0>   
          	               	97        	102B1     	GND                 
          	               	98        	102B4     	M_C_CPU1_SB_CB<1>   
          	               	99        	102B1     	GND                 
          	               	100       	102B4     	M_C_CPU1_SB_DQ<0>   
          	               	101       	102B1     	GND                 
          	               	102       	102B4     	M_C_CPU1_SB_DQ<1>   
          	               	103       	102B1     	GND                 
          	               	104       	102B2     	M_C_CPU1_SB_DQS_DP<0>
          	               	105       	102B2     	M_C_CPU1_SB_DQS_DN<0>
          	               	106       	102B1     	GND                 
          	               	107       	102B4     	M_C_CPU1_SB_DQ<4>   
          	               	108       	102B1     	GND                 
          	               	109       	102B4     	M_C_CPU1_SB_DQ<5>   
          	               	110       	102B1     	GND                 
          	               	111       	102B4     	M_C_CPU1_SB_DQ<8>   
          	               	112       	102B1     	GND                 
          	               	113       	102B4     	M_C_CPU1_SB_DQ<9>   
          	               	114       	102B1     	GND                 
          	               	115       	102B2     	M_C_CPU1_SB_DQS_DP<1>
          	               	116       	102B2     	M_C_CPU1_SB_DQS_DN<1>
          	               	117       	102B1     	GND                 
          	               	118       	102B4     	M_C_CPU1_SB_DQ<12>  
          	               	119       	102B1     	GND                 
          	               	120       	102B4     	M_C_CPU1_SB_DQ<13>  
          	               	121       	102B1     	GND                 
          	               	122       	102B4     	M_C_CPU1_SB_DQ<16>  
          	               	123       	102B1     	GND                 
          	               	124       	102B4     	M_C_CPU1_SB_DQ<17>  
          	               	125       	102B1     	GND                 
          	               	126       	102B2     	M_C_CPU1_SB_DQS_DP<2>
          	               	127       	102B2     	M_C_CPU1_SB_DQS_DN<2>
          	               	128       	102B1     	GND                 
          	               	129       	102B4     	M_C_CPU1_SB_DQ<20>  
          	               	130       	102B1     	GND                 
          	               	131       	102B4     	M_C_CPU1_SB_DQ<21>  
          	               	132       	102B1     	GND                 
          	               	133       	102B4     	M_C_CPU1_SB_DQ<24>  
          	               	134       	102B1     	GND                 
          	               	135       	102B4     	M_C_CPU1_SB_DQ<25>  
          	               	136       	102B1     	GND                 
          	               	137       	102B2     	M_C_CPU1_SB_DQS_DP<3>
          	               	138       	102B2     	M_C_CPU1_SB_DQS_DN<3>
          	               	139       	102B1     	GND                 
          	               	140       	102B4     	M_C_CPU1_SB_DQ<28>  
          	               	141       	102B1     	GND                 
          	               	142       	102B4     	M_C_CPU1_SB_DQ<29>  
          	               	143       	102B1     	GND                 
          	               	144       	102B4     	TP_CHC_CPU1_DIMM1_FRU_1
          	               	145       	102B1     	P12V_S3_AUX_CPU1_NVDIMM
          	               	146       	102B1     	P12V_S3_AUX_CPU1_NVDIMM
          	               	147       	102B4     	PWRGD_CHC_CPU1_DIMM1
          	               	148       	102B4     	PD_CHC_CPU1_DIMM1_SAA
          	               	149       	102B4     	TP_CHC_CPU1_DIMM1_FRU_2
          	               	150       	102B4     	TP_CHC_CPU1_DIMM1_FRU_3
          	               	151       	102B1     	GND                 
          	               	152       	102B4     	M_C_CPU1_SA_DQ<2>   
          	               	153       	102B1     	GND                 
          	               	154       	102B4     	M_C_CPU1_SA_DQ<3>   
          	               	155       	102B1     	GND                 
          	               	156       	102B2     	M_C_CPU1_SA_DQS_DN<5>
          	               	157       	102B2     	M_C_CPU1_SA_DQS_DP<5>
          	               	158       	102B1     	GND                 
          	               	159       	102B4     	M_C_CPU1_SA_DQ<6>   
          	               	160       	102B1     	GND                 
          	               	161       	102B4     	M_C_CPU1_SA_DQ<7>   
          	               	162       	102B1     	GND                 
          	               	163       	102B4     	M_C_CPU1_SA_DQ<10>  
          	               	164       	102B1     	GND                 
          	               	165       	102B4     	M_C_CPU1_SA_DQ<11>  
          	               	166       	102B1     	GND                 
          	               	167       	102B2     	M_C_CPU1_SA_DQS_DN<6>
          	               	168       	102B2     	M_C_CPU1_SA_DQS_DP<6>
          	               	169       	102B1     	GND                 
          	               	170       	102B4     	M_C_CPU1_SA_DQ<14>  
          	               	171       	102B1     	GND                 
          	               	172       	102B4     	M_C_CPU1_SA_DQ<15>  
          	               	173       	102B1     	GND                 
          	               	174       	102B4     	M_C_CPU1_SA_DQ<18>  
          	               	175       	102B1     	GND                 
          	               	176       	102B4     	M_C_CPU1_SA_DQ<19>  
          	               	177       	102B1     	GND                 
          	               	178       	102B2     	M_C_CPU1_SA_DQS_DN<7>
          	               	179       	102B2     	M_C_CPU1_SA_DQS_DP<7>
          	               	180       	102B1     	GND                 
          	               	181       	102B4     	M_C_CPU1_SA_DQ<22>  
          	               	182       	102B1     	GND                 
          	               	183       	102B4     	M_C_CPU1_SA_DQ<23>  
          	               	184       	102B1     	GND                 
          	               	185       	102B4     	M_C_CPU1_SA_DQ<26>  
          	               	186       	102B1     	GND                 
          	               	187       	102B4     	M_C_CPU1_SA_DQ<27>  
          	               	188       	102B1     	GND                 
          	               	189       	102B2     	M_C_CPU1_SA_DQS_DN<8>
          	               	190       	102B2     	M_C_CPU1_SA_DQS_DP<8>
          	               	191       	102B1     	GND                 
          	               	192       	102B4     	M_C_CPU1_SA_DQ<30>  
          	               	193       	102B1     	GND                 
          	               	194       	102B4     	M_C_CPU1_SA_DQ<31>  
          	               	195       	102B1     	GND                 
          	               	196       	102B4     	M_C_CPU1_SA_CB<2>   
          	               	197       	102B1     	GND                 
          	               	198       	102B4     	M_C_CPU1_SA_CB<3>   
          	               	199       	102B1     	GND                 
          	               	200       	102B2     	M_C_CPU1_SA_DQS_DN<9>
          	               	201       	102B2     	M_C_CPU1_SA_DQS_DP<9>
          	               	202       	102B1     	GND                 
          	               	203       	102B4     	M_C_CPU1_SA_CB<6>   
          	               	204       	102B1     	GND                 
          	               	205       	102B4     	M_C_CPU1_SA_CB<7>   
          	               	206       	102B1     	GND                 
          	               	207       	102B4     	RST_M_CD_CPU1_FPGA_N
          	               	208       	102B1     	GND                 
          	               	209       	102B4     	M_C_CPU1_SA_CS_N<1> 
          	               	210       	102B1     	GND                 
          	               	211       	102B4     	M_C_CPU1_SA_CA<1>   
          	               	212       	102B1     	GND                 
          	               	213       	102B4     	M_C_CPU1_SA_CA<3>   
          	               	214       	102B1     	GND                 
          	               	215       	102B4     	M_C_CPU1_SA_CA<5>   
          	               	216       	102B1     	GND                 
          	               	217       	102B4     	M_C_CPU1_CLK_DP<0>  
          	               	218       	102B4     	M_C_CPU1_CLK_DN<0>  
          	               	219       	102B1     	GND                 
          	               	220       	102B4     	TP_CHC_CPU1_DIMM1_FRU_4
          	               	221       	102B4     	M_C_CPU1_SB_CA<1>   
          	               	222       	102B1     	GND                 
          	               	223       	102B4     	M_C_CPU1_SB_CA<3>   
          	               	224       	102B1     	GND                 
          	               	225       	102B4     	M_C_CPU1_SB_CA<5>   
          	               	226       	102B1     	GND                 
          	               	227       	102B4     	M_C_CPU1_SB_PAR     
          	               	228       	102B1     	GND                 
          	               	229       	102B4     	M_C_CPU1_SB_CS_N<1> 
          	               	230       	102B1     	GND                 
          	               	231       	102B4     	TP_CHC_CPU1_DIMM1_FRU_5
          	               	232       	102B4     	TP_CHC_CPU1_DIMM1_FRU_6
          	               	233       	102B1     	GND                 
          	               	234       	102B4     	M_C_CPU1_SB_CB<6>   
          	               	235       	102B1     	GND                 
          	               	236       	102B4     	M_C_CPU1_SB_CB<7>   
          	               	237       	102B1     	GND                 
          	               	238       	102B2     	M_C_CPU1_SB_DQS_DN<4>
          	               	239       	102B2     	M_C_CPU1_SB_DQS_DP<4>
          	               	240       	102B1     	GND                 
          	               	241       	102B4     	M_C_CPU1_SB_CB<2>   
          	               	242       	102B1     	GND                 
          	               	243       	102B4     	M_C_CPU1_SB_CB<3>   
          	               	244       	102B1     	GND                 
          	               	245       	102B4     	M_C_CPU1_SB_DQ<2>   
          	               	246       	102B1     	GND                 
          	               	247       	102B4     	M_C_CPU1_SB_DQ<3>   
          	               	248       	102B1     	GND                 
          	               	249       	102B2     	M_C_CPU1_SB_DQS_DN<5>
          	               	250       	102B2     	M_C_CPU1_SB_DQS_DP<5>
          	               	251       	102B1     	GND                 
          	               	252       	102B4     	M_C_CPU1_SB_DQ<6>   
          	               	253       	102B1     	GND                 
          	               	254       	102B4     	M_C_CPU1_SB_DQ<7>   
          	               	255       	102B1     	GND                 
          	               	256       	102B4     	M_C_CPU1_SB_DQ<10>  
          	               	257       	102B1     	GND                 
          	               	258       	102B4     	M_C_CPU1_SB_DQ<11>  
          	               	259       	102B1     	GND                 
          	               	260       	102B2     	M_C_CPU1_SB_DQS_DN<6>
          	               	261       	102B2     	M_C_CPU1_SB_DQS_DP<6>
          	               	262       	102B1     	GND                 
          	               	263       	102B4     	M_C_CPU1_SB_DQ<14>  
          	               	264       	102B1     	GND                 
          	               	265       	102B4     	M_C_CPU1_SB_DQ<15>  
          	               	266       	102B1     	GND                 
          	               	267       	102B4     	M_C_CPU1_SB_DQ<18>  
          	               	268       	102B1     	GND                 
          	               	269       	102B4     	M_C_CPU1_SB_DQ<19>  
          	               	270       	102B1     	GND                 
          	               	271       	102B2     	M_C_CPU1_SB_DQS_DN<7>
          	               	272       	102B2     	M_C_CPU1_SB_DQS_DP<7>
          	               	273       	102B1     	GND                 
          	               	274       	102B4     	M_C_CPU1_SB_DQ<22>  
          	               	275       	102B1     	GND                 
          	               	276       	102B4     	M_C_CPU1_SB_DQ<23>  
          	               	277       	102B1     	GND                 
          	               	278       	102B4     	M_C_CPU1_SB_DQ<26>  
          	               	279       	102B1     	GND                 
          	               	280       	102B4     	M_C_CPU1_SB_DQ<27>  
          	               	281       	102B1     	GND                 
          	               	282       	102B2     	M_C_CPU1_SB_DQS_DN<8>
          	               	283       	102B2     	M_C_CPU1_SB_DQS_DP<8>
          	               	284       	102B1     	GND                 
          	               	285       	102B4     	M_C_CPU1_SB_DQ<30>  
          	               	286       	102B1     	GND                 
          	               	287       	102B4     	M_C_CPU1_SB_DQ<31>  
          	               	288       	102B1     	GND                 
          	               	G1        	102B1     	GND                 
          	               	G2        	102A1     	GND                 
          	               	G3        	102A1     	GND                 

J22       	SCONN288_ADR50017P087CC	          	          	                    
          	               	1         	103B1     	P12V_S3_AUX_CPU1_NVDIMM
          	               	2         	103B4     	TP_CHC_CPU1_DIMM2_FRU_0
          	               	3         	103B4     	P3V3_AUX            
          	               	4         	103B4     	I3C_SPD_DDRABCD_CPU1_LVC1_SCL_5
          	               	5         	103B4     	I3C_SPD_DDRABCD_CPU1_LVC1_SDA
          	               	6         	103B1     	GND                 
          	               	7         	103B4     	M_C_CPU1_SA_DQ<0>   
          	               	8         	103B1     	GND                 
          	               	9         	103B4     	M_C_CPU1_SA_DQ<1>   
          	               	10        	103B1     	GND                 
          	               	11        	103B2     	M_C_CPU1_SA_DQS_DP<0>
          	               	12        	103B2     	M_C_CPU1_SA_DQS_DN<0>
          	               	13        	103B1     	GND                 
          	               	14        	103B4     	M_C_CPU1_SA_DQ<4>   
          	               	15        	103B1     	GND                 
          	               	16        	103B4     	M_C_CPU1_SA_DQ<5>   
          	               	17        	103B1     	GND                 
          	               	18        	103B4     	M_C_CPU1_SA_DQ<8>   
          	               	19        	103B1     	GND                 
          	               	20        	103B4     	M_C_CPU1_SA_DQ<9>   
          	               	21        	103B1     	GND                 
          	               	22        	103B2     	M_C_CPU1_SA_DQS_DP<1>
          	               	23        	103B2     	M_C_CPU1_SA_DQS_DN<1>
          	               	24        	103B1     	GND                 
          	               	25        	103B4     	M_C_CPU1_SA_DQ<12>  
          	               	26        	103B1     	GND                 
          	               	27        	103B4     	M_C_CPU1_SA_DQ<13>  
          	               	28        	103B1     	GND                 
          	               	29        	103B4     	M_C_CPU1_SA_DQ<16>  
          	               	30        	103B1     	GND                 
          	               	31        	103B4     	M_C_CPU1_SA_DQ<17>  
          	               	32        	103B1     	GND                 
          	               	33        	103B2     	M_C_CPU1_SA_DQS_DP<2>
          	               	34        	103B2     	M_C_CPU1_SA_DQS_DN<2>
          	               	35        	103B1     	GND                 
          	               	36        	103B4     	M_C_CPU1_SA_DQ<20>  
          	               	37        	103B1     	GND                 
          	               	38        	103B4     	M_C_CPU1_SA_DQ<21>  
          	               	39        	103B1     	GND                 
          	               	40        	103B4     	M_C_CPU1_SA_DQ<24>  
          	               	41        	103B1     	GND                 
          	               	42        	103B4     	M_C_CPU1_SA_DQ<25>  
          	               	43        	103B1     	GND                 
          	               	44        	103B2     	M_C_CPU1_SA_DQS_DP<3>
          	               	45        	103B2     	M_C_CPU1_SA_DQS_DN<3>
          	               	46        	103B1     	GND                 
          	               	47        	103B4     	M_C_CPU1_SA_DQ<28>  
          	               	48        	103B1     	GND                 
          	               	49        	103B4     	M_C_CPU1_SA_DQ<29>  
          	               	50        	103B1     	GND                 
          	               	51        	103B4     	M_C_CPU1_SA_CB<0>   
          	               	52        	103B1     	GND                 
          	               	53        	103B4     	M_C_CPU1_SA_CB<1>   
          	               	54        	103B1     	GND                 
          	               	55        	103B2     	M_C_CPU1_SA_DQS_DP<4>
          	               	56        	103B2     	M_C_CPU1_SA_DQS_DN<4>
          	               	57        	103B1     	GND                 
          	               	58        	103B4     	M_C_CPU1_SA_CB<4>   
          	               	59        	103B1     	GND                 
          	               	60        	103B4     	M_C_CPU1_SA_CB<5>   
          	               	61        	103B1     	GND                 
          	               	62        	103B4     	M_C_CPU1_ALERT_N    
          	               	63        	103B1     	GND                 
          	               	64        	103B4     	M_C_CPU1_SA_CS_N<2> 
          	               	65        	103B1     	GND                 
          	               	66        	103B4     	M_C_CPU1_SA_CA<0>   
          	               	67        	103B1     	GND                 
          	               	68        	103B4     	M_C_CPU1_SA_CA<2>   
          	               	69        	103B1     	GND                 
          	               	70        	103B4     	M_C_CPU1_SA_CA<4>   
          	               	71        	103B1     	GND                 
          	               	72        	103B4     	M_C_CPU1_SA_CA<6>   
          	               	73        	103B1     	GND                 
          	               	74        	103B4     	M_C_CPU1_SA_PAR     
          	               	75        	103B1     	GND                 
          	               	76        	103B4     	M_C_CPU1_SB_CA<0>   
          	               	77        	103B1     	GND                 
          	               	78        	103B4     	M_C_CPU1_SB_CA<2>   
          	               	79        	103B1     	GND                 
          	               	80        	103B4     	M_C_CPU1_SB_CA<4>   
          	               	81        	103B1     	GND                 
          	               	82        	103B4     	M_C_CPU1_SB_CA<6>   
          	               	83        	103B1     	GND                 
          	               	84        	103B4     	M_C_CPU1_SB_CS_N<2> 
          	               	85        	103B1     	GND                 
          	               	86        	103A4     	M_C_CPU1_SA_RSP<1>  
          	               	87        	103A4     	M_C_CPU1_SB_RSP<1>  
          	               	88        	103B1     	GND                 
          	               	89        	103B4     	M_C_CPU1_SB_CB<4>   
          	               	90        	103B1     	GND                 
          	               	91        	103B4     	M_C_CPU1_SB_CB<5>   
          	               	92        	103B1     	GND                 
          	               	93        	103B2     	M_C_CPU1_SB_DQS_DP<9>
          	               	94        	103B2     	M_C_CPU1_SB_DQS_DN<9>
          	               	95        	103B1     	GND                 
          	               	96        	103B4     	M_C_CPU1_SB_CB<0>   
          	               	97        	103B1     	GND                 
          	               	98        	103B4     	M_C_CPU1_SB_CB<1>   
          	               	99        	103B1     	GND                 
          	               	100       	103B4     	M_C_CPU1_SB_DQ<0>   
          	               	101       	103B1     	GND                 
          	               	102       	103B4     	M_C_CPU1_SB_DQ<1>   
          	               	103       	103B1     	GND                 
          	               	104       	103B2     	M_C_CPU1_SB_DQS_DP<0>
          	               	105       	103B2     	M_C_CPU1_SB_DQS_DN<0>
          	               	106       	103B1     	GND                 
          	               	107       	103B4     	M_C_CPU1_SB_DQ<4>   
          	               	108       	103B1     	GND                 
          	               	109       	103B4     	M_C_CPU1_SB_DQ<5>   
          	               	110       	103B1     	GND                 
          	               	111       	103B4     	M_C_CPU1_SB_DQ<8>   
          	               	112       	103B1     	GND                 
          	               	113       	103B4     	M_C_CPU1_SB_DQ<9>   
          	               	114       	103B1     	GND                 
          	               	115       	103B2     	M_C_CPU1_SB_DQS_DP<1>
          	               	116       	103B2     	M_C_CPU1_SB_DQS_DN<1>
          	               	117       	103B1     	GND                 
          	               	118       	103B4     	M_C_CPU1_SB_DQ<12>  
          	               	119       	103B1     	GND                 
          	               	120       	103B4     	M_C_CPU1_SB_DQ<13>  
          	               	121       	103B1     	GND                 
          	               	122       	103B4     	M_C_CPU1_SB_DQ<16>  
          	               	123       	103B1     	GND                 
          	               	124       	103B4     	M_C_CPU1_SB_DQ<17>  
          	               	125       	103B1     	GND                 
          	               	126       	103B2     	M_C_CPU1_SB_DQS_DP<2>
          	               	127       	103B2     	M_C_CPU1_SB_DQS_DN<2>
          	               	128       	103B1     	GND                 
          	               	129       	103B4     	M_C_CPU1_SB_DQ<20>  
          	               	130       	103B1     	GND                 
          	               	131       	103B4     	M_C_CPU1_SB_DQ<21>  
          	               	132       	103B1     	GND                 
          	               	133       	103B4     	M_C_CPU1_SB_DQ<24>  
          	               	134       	103B1     	GND                 
          	               	135       	103B4     	M_C_CPU1_SB_DQ<25>  
          	               	136       	103B1     	GND                 
          	               	137       	103B2     	M_C_CPU1_SB_DQS_DP<3>
          	               	138       	103B2     	M_C_CPU1_SB_DQS_DN<3>
          	               	139       	103B1     	GND                 
          	               	140       	103B4     	M_C_CPU1_SB_DQ<28>  
          	               	141       	103B1     	GND                 
          	               	142       	103B4     	M_C_CPU1_SB_DQ<29>  
          	               	143       	103B1     	GND                 
          	               	144       	103B4     	TP_CHC_CPU1_DIMM2_FRU_1
          	               	145       	103B1     	P12V_S3_AUX_CPU1_NVDIMM
          	               	146       	103B1     	P12V_S3_AUX_CPU1_NVDIMM
          	               	147       	103B4     	PWRGD_CHC_CPU1_DIMM2
          	               	148       	103B4     	PD_CHC_CPU1_DIMM2_SAA
          	               	149       	103B4     	TP_CHC_CPU1_DIMM2_FRU_2
          	               	150       	103B4     	TP_CHC_CPU1_DIMM2_FRU_3
          	               	151       	103B1     	GND                 
          	               	152       	103B4     	M_C_CPU1_SA_DQ<2>   
          	               	153       	103B1     	GND                 
          	               	154       	103B4     	M_C_CPU1_SA_DQ<3>   
          	               	155       	103B1     	GND                 
          	               	156       	103B2     	M_C_CPU1_SA_DQS_DN<5>
          	               	157       	103B2     	M_C_CPU1_SA_DQS_DP<5>
          	               	158       	103B1     	GND                 
          	               	159       	103B4     	M_C_CPU1_SA_DQ<6>   
          	               	160       	103B1     	GND                 
          	               	161       	103B4     	M_C_CPU1_SA_DQ<7>   
          	               	162       	103B1     	GND                 
          	               	163       	103B4     	M_C_CPU1_SA_DQ<10>  
          	               	164       	103B1     	GND                 
          	               	165       	103B4     	M_C_CPU1_SA_DQ<11>  
          	               	166       	103B1     	GND                 
          	               	167       	103B2     	M_C_CPU1_SA_DQS_DN<6>
          	               	168       	103B2     	M_C_CPU1_SA_DQS_DP<6>
          	               	169       	103B1     	GND                 
          	               	170       	103B4     	M_C_CPU1_SA_DQ<14>  
          	               	171       	103B1     	GND                 
          	               	172       	103B4     	M_C_CPU1_SA_DQ<15>  
          	               	173       	103B1     	GND                 
          	               	174       	103B4     	M_C_CPU1_SA_DQ<18>  
          	               	175       	103B1     	GND                 
          	               	176       	103B4     	M_C_CPU1_SA_DQ<19>  
          	               	177       	103B1     	GND                 
          	               	178       	103B2     	M_C_CPU1_SA_DQS_DN<7>
          	               	179       	103B2     	M_C_CPU1_SA_DQS_DP<7>
          	               	180       	103B1     	GND                 
          	               	181       	103B4     	M_C_CPU1_SA_DQ<22>  
          	               	182       	103B1     	GND                 
          	               	183       	103B4     	M_C_CPU1_SA_DQ<23>  
          	               	184       	103B1     	GND                 
          	               	185       	103B4     	M_C_CPU1_SA_DQ<26>  
          	               	186       	103B1     	GND                 
          	               	187       	103B4     	M_C_CPU1_SA_DQ<27>  
          	               	188       	103B1     	GND                 
          	               	189       	103B2     	M_C_CPU1_SA_DQS_DN<8>
          	               	190       	103B2     	M_C_CPU1_SA_DQS_DP<8>
          	               	191       	103B1     	GND                 
          	               	192       	103B4     	M_C_CPU1_SA_DQ<30>  
          	               	193       	103B1     	GND                 
          	               	194       	103B4     	M_C_CPU1_SA_DQ<31>  
          	               	195       	103B1     	GND                 
          	               	196       	103B4     	M_C_CPU1_SA_CB<2>   
          	               	197       	103B1     	GND                 
          	               	198       	103B4     	M_C_CPU1_SA_CB<3>   
          	               	199       	103B1     	GND                 
          	               	200       	103B2     	M_C_CPU1_SA_DQS_DN<9>
          	               	201       	103B2     	M_C_CPU1_SA_DQS_DP<9>
          	               	202       	103B1     	GND                 
          	               	203       	103B4     	M_C_CPU1_SA_CB<6>   
          	               	204       	103B1     	GND                 
          	               	205       	103B4     	M_C_CPU1_SA_CB<7>   
          	               	206       	103B1     	GND                 
          	               	207       	103B4     	RST_M_CD_CPU1_FPGA_N
          	               	208       	103B1     	GND                 
          	               	209       	103B4     	M_C_CPU1_SA_CS_N<3> 
          	               	210       	103B1     	GND                 
          	               	211       	103B4     	M_C_CPU1_SA_CA<1>   
          	               	212       	103B1     	GND                 
          	               	213       	103B4     	M_C_CPU1_SA_CA<3>   
          	               	214       	103B1     	GND                 
          	               	215       	103B4     	M_C_CPU1_SA_CA<5>   
          	               	216       	103B1     	GND                 
          	               	217       	103B4     	M_C_CPU1_CLK_DP<1>  
          	               	218       	103B4     	M_C_CPU1_CLK_DN<1>  
          	               	219       	103B1     	GND                 
          	               	220       	103B4     	TP_CHC_CPU1_DIMM2_FRU_4
          	               	221       	103B4     	M_C_CPU1_SB_CA<1>   
          	               	222       	103B1     	GND                 
          	               	223       	103B4     	M_C_CPU1_SB_CA<3>   
          	               	224       	103B1     	GND                 
          	               	225       	103B4     	M_C_CPU1_SB_CA<5>   
          	               	226       	103B1     	GND                 
          	               	227       	103B4     	M_C_CPU1_SB_PAR     
          	               	228       	103B1     	GND                 
          	               	229       	103B4     	M_C_CPU1_SB_CS_N<3> 
          	               	230       	103B1     	GND                 
          	               	231       	103B4     	TP_CHC_CPU1_DIMM2_FRU_5
          	               	232       	103B4     	TP_CHC_CPU1_DIMM2_FRU_6
          	               	233       	103B1     	GND                 
          	               	234       	103B4     	M_C_CPU1_SB_CB<6>   
          	               	235       	103B1     	GND                 
          	               	236       	103B4     	M_C_CPU1_SB_CB<7>   
          	               	237       	103B1     	GND                 
          	               	238       	103B2     	M_C_CPU1_SB_DQS_DN<4>
          	               	239       	103B2     	M_C_CPU1_SB_DQS_DP<4>
          	               	240       	103B1     	GND                 
          	               	241       	103B4     	M_C_CPU1_SB_CB<2>   
          	               	242       	103B1     	GND                 
          	               	243       	103B4     	M_C_CPU1_SB_CB<3>   
          	               	244       	103B1     	GND                 
          	               	245       	103B4     	M_C_CPU1_SB_DQ<2>   
          	               	246       	103B1     	GND                 
          	               	247       	103B4     	M_C_CPU1_SB_DQ<3>   
          	               	248       	103B1     	GND                 
          	               	249       	103B2     	M_C_CPU1_SB_DQS_DN<5>
          	               	250       	103B2     	M_C_CPU1_SB_DQS_DP<5>
          	               	251       	103B1     	GND                 
          	               	252       	103B4     	M_C_CPU1_SB_DQ<6>   
          	               	253       	103B1     	GND                 
          	               	254       	103B4     	M_C_CPU1_SB_DQ<7>   
          	               	255       	103B1     	GND                 
          	               	256       	103B4     	M_C_CPU1_SB_DQ<10>  
          	               	257       	103B1     	GND                 
          	               	258       	103B4     	M_C_CPU1_SB_DQ<11>  
          	               	259       	103B1     	GND                 
          	               	260       	103B2     	M_C_CPU1_SB_DQS_DN<6>
          	               	261       	103B2     	M_C_CPU1_SB_DQS_DP<6>
          	               	262       	103B1     	GND                 
          	               	263       	103B4     	M_C_CPU1_SB_DQ<14>  
          	               	264       	103B1     	GND                 
          	               	265       	103B4     	M_C_CPU1_SB_DQ<15>  
          	               	266       	103B1     	GND                 
          	               	267       	103B4     	M_C_CPU1_SB_DQ<18>  
          	               	268       	103B1     	GND                 
          	               	269       	103B4     	M_C_CPU1_SB_DQ<19>  
          	               	270       	103B1     	GND                 
          	               	271       	103B2     	M_C_CPU1_SB_DQS_DN<7>
          	               	272       	103B2     	M_C_CPU1_SB_DQS_DP<7>
          	               	273       	103B1     	GND                 
          	               	274       	103B4     	M_C_CPU1_SB_DQ<22>  
          	               	275       	103B1     	GND                 
          	               	276       	103B4     	M_C_CPU1_SB_DQ<23>  
          	               	277       	103B1     	GND                 
          	               	278       	103B4     	M_C_CPU1_SB_DQ<26>  
          	               	279       	103B1     	GND                 
          	               	280       	103B4     	M_C_CPU1_SB_DQ<27>  
          	               	281       	103B1     	GND                 
          	               	282       	103B2     	M_C_CPU1_SB_DQS_DN<8>
          	               	283       	103B2     	M_C_CPU1_SB_DQS_DP<8>
          	               	284       	103B1     	GND                 
          	               	285       	103B4     	M_C_CPU1_SB_DQ<30>  
          	               	286       	103B1     	GND                 
          	               	287       	103B4     	M_C_CPU1_SB_DQ<31>  
          	               	288       	103B1     	GND                 
          	               	G1        	103B1     	GND                 
          	               	G2        	103A1     	GND                 
          	               	G3        	103A1     	GND                 

J23       	SCONN288_ADR50017P130CC	          	          	                    
          	               	1         	104B1     	P12V_S3_AUX_CPU1_NVDIMM
          	               	2         	104B4     	TP_CHD_CPU1_DIMM1_FRU_0
          	               	3         	104B4     	P3V3_AUX            
          	               	4         	104B4     	I3C_SPD_DDRABCD_CPU1_LVC1_SCL_6
          	               	5         	104B4     	I3C_SPD_DDRABCD_CPU1_LVC1_SDA
          	               	6         	104B1     	GND                 
          	               	7         	104B4     	M_D_CPU1_SA_DQ<0>   
          	               	8         	104B1     	GND                 
          	               	9         	104B4     	M_D_CPU1_SA_DQ<1>   
          	               	10        	104B1     	GND                 
          	               	11        	104B2     	M_D_CPU1_SA_DQS_DP<0>
          	               	12        	104B2     	M_D_CPU1_SA_DQS_DN<0>
          	               	13        	104B1     	GND                 
          	               	14        	104B4     	M_D_CPU1_SA_DQ<4>   
          	               	15        	104B1     	GND                 
          	               	16        	104B4     	M_D_CPU1_SA_DQ<5>   
          	               	17        	104B1     	GND                 
          	               	18        	104B4     	M_D_CPU1_SA_DQ<8>   
          	               	19        	104B1     	GND                 
          	               	20        	104B4     	M_D_CPU1_SA_DQ<9>   
          	               	21        	104B1     	GND                 
          	               	22        	104B2     	M_D_CPU1_SA_DQS_DP<1>
          	               	23        	104B2     	M_D_CPU1_SA_DQS_DN<1>
          	               	24        	104B1     	GND                 
          	               	25        	104B4     	M_D_CPU1_SA_DQ<12>  
          	               	26        	104B1     	GND                 
          	               	27        	104B4     	M_D_CPU1_SA_DQ<13>  
          	               	28        	104B1     	GND                 
          	               	29        	104B4     	M_D_CPU1_SA_DQ<16>  
          	               	30        	104B1     	GND                 
          	               	31        	104B4     	M_D_CPU1_SA_DQ<17>  
          	               	32        	104B1     	GND                 
          	               	33        	104B2     	M_D_CPU1_SA_DQS_DP<2>
          	               	34        	104B2     	M_D_CPU1_SA_DQS_DN<2>
          	               	35        	104B1     	GND                 
          	               	36        	104B4     	M_D_CPU1_SA_DQ<20>  
          	               	37        	104B1     	GND                 
          	               	38        	104B4     	M_D_CPU1_SA_DQ<21>  
          	               	39        	104B1     	GND                 
          	               	40        	104B4     	M_D_CPU1_SA_DQ<24>  
          	               	41        	104B1     	GND                 
          	               	42        	104B4     	M_D_CPU1_SA_DQ<25>  
          	               	43        	104B1     	GND                 
          	               	44        	104B2     	M_D_CPU1_SA_DQS_DP<3>
          	               	45        	104B2     	M_D_CPU1_SA_DQS_DN<3>
          	               	46        	104B1     	GND                 
          	               	47        	104B4     	M_D_CPU1_SA_DQ<28>  
          	               	48        	104B1     	GND                 
          	               	49        	104B4     	M_D_CPU1_SA_DQ<29>  
          	               	50        	104B1     	GND                 
          	               	51        	104B4     	M_D_CPU1_SA_CB<0>   
          	               	52        	104B1     	GND                 
          	               	53        	104B4     	M_D_CPU1_SA_CB<1>   
          	               	54        	104B1     	GND                 
          	               	55        	104B2     	M_D_CPU1_SA_DQS_DP<4>
          	               	56        	104B2     	M_D_CPU1_SA_DQS_DN<4>
          	               	57        	104B1     	GND                 
          	               	58        	104B4     	M_D_CPU1_SA_CB<4>   
          	               	59        	104B1     	GND                 
          	               	60        	104B4     	M_D_CPU1_SA_CB<5>   
          	               	61        	104B1     	GND                 
          	               	62        	104B4     	M_D_CPU1_ALERT_N    
          	               	63        	104B1     	GND                 
          	               	64        	104B4     	M_D_CPU1_SA_CS_N<0> 
          	               	65        	104B1     	GND                 
          	               	66        	104B4     	M_D_CPU1_SA_CA<0>   
          	               	67        	104B1     	GND                 
          	               	68        	104B4     	M_D_CPU1_SA_CA<2>   
          	               	69        	104B1     	GND                 
          	               	70        	104B4     	M_D_CPU1_SA_CA<4>   
          	               	71        	104B1     	GND                 
          	               	72        	104B4     	M_D_CPU1_SA_CA<6>   
          	               	73        	104B1     	GND                 
          	               	74        	104B4     	M_D_CPU1_SA_PAR     
          	               	75        	104B1     	GND                 
          	               	76        	104B4     	M_D_CPU1_SB_CA<0>   
          	               	77        	104B1     	GND                 
          	               	78        	104B4     	M_D_CPU1_SB_CA<2>   
          	               	79        	104B1     	GND                 
          	               	80        	104B4     	M_D_CPU1_SB_CA<4>   
          	               	81        	104B1     	GND                 
          	               	82        	104B4     	M_D_CPU1_SB_CA<6>   
          	               	83        	104B1     	GND                 
          	               	84        	104B4     	M_D_CPU1_SB_CS_N<0> 
          	               	85        	104B1     	GND                 
          	               	86        	104A4     	M_D_CPU1_SA_RSP<0>  
          	               	87        	104A4     	M_D_CPU1_SB_RSP<0>  
          	               	88        	104B1     	GND                 
          	               	89        	104B4     	M_D_CPU1_SB_CB<4>   
          	               	90        	104B1     	GND                 
          	               	91        	104B4     	M_D_CPU1_SB_CB<5>   
          	               	92        	104B1     	GND                 
          	               	93        	104B2     	M_D_CPU1_SB_DQS_DP<9>
          	               	94        	104B2     	M_D_CPU1_SB_DQS_DN<9>
          	               	95        	104B1     	GND                 
          	               	96        	104B4     	M_D_CPU1_SB_CB<0>   
          	               	97        	104B1     	GND                 
          	               	98        	104B4     	M_D_CPU1_SB_CB<1>   
          	               	99        	104B1     	GND                 
          	               	100       	104B4     	M_D_CPU1_SB_DQ<0>   
          	               	101       	104B1     	GND                 
          	               	102       	104B4     	M_D_CPU1_SB_DQ<1>   
          	               	103       	104B1     	GND                 
          	               	104       	104B2     	M_D_CPU1_SB_DQS_DP<0>
          	               	105       	104B2     	M_D_CPU1_SB_DQS_DN<0>
          	               	106       	104B1     	GND                 
          	               	107       	104B4     	M_D_CPU1_SB_DQ<4>   
          	               	108       	104B1     	GND                 
          	               	109       	104B4     	M_D_CPU1_SB_DQ<5>   
          	               	110       	104B1     	GND                 
          	               	111       	104B4     	M_D_CPU1_SB_DQ<8>   
          	               	112       	104B1     	GND                 
          	               	113       	104B4     	M_D_CPU1_SB_DQ<9>   
          	               	114       	104B1     	GND                 
          	               	115       	104B2     	M_D_CPU1_SB_DQS_DP<1>
          	               	116       	104B2     	M_D_CPU1_SB_DQS_DN<1>
          	               	117       	104B1     	GND                 
          	               	118       	104B4     	M_D_CPU1_SB_DQ<12>  
          	               	119       	104B1     	GND                 
          	               	120       	104B4     	M_D_CPU1_SB_DQ<13>  
          	               	121       	104B1     	GND                 
          	               	122       	104B4     	M_D_CPU1_SB_DQ<16>  
          	               	123       	104B1     	GND                 
          	               	124       	104B4     	M_D_CPU1_SB_DQ<17>  
          	               	125       	104B1     	GND                 
          	               	126       	104B2     	M_D_CPU1_SB_DQS_DP<2>
          	               	127       	104B2     	M_D_CPU1_SB_DQS_DN<2>
          	               	128       	104B1     	GND                 
          	               	129       	104B4     	M_D_CPU1_SB_DQ<20>  
          	               	130       	104B1     	GND                 
          	               	131       	104B4     	M_D_CPU1_SB_DQ<21>  
          	               	132       	104B1     	GND                 
          	               	133       	104B4     	M_D_CPU1_SB_DQ<24>  
          	               	134       	104B1     	GND                 
          	               	135       	104B4     	M_D_CPU1_SB_DQ<25>  
          	               	136       	104B1     	GND                 
          	               	137       	104B2     	M_D_CPU1_SB_DQS_DP<3>
          	               	138       	104B2     	M_D_CPU1_SB_DQS_DN<3>
          	               	139       	104B1     	GND                 
          	               	140       	104B4     	M_D_CPU1_SB_DQ<28>  
          	               	141       	104B1     	GND                 
          	               	142       	104B4     	M_D_CPU1_SB_DQ<29>  
          	               	143       	104B1     	GND                 
          	               	144       	104B4     	TP_CHD_CPU1_DIMM1_FRU_1
          	               	145       	104B1     	P12V_S3_AUX_CPU1_NVDIMM
          	               	146       	104B1     	P12V_S3_AUX_CPU1_NVDIMM
          	               	147       	104B4     	PWRGD_CHD_CPU1_DIMM1
          	               	148       	104B4     	PD_CHD_CPU1_DIMM1_SAA
          	               	149       	104B4     	TP_CHD_CPU1_DIMM1_FRU_2
          	               	150       	104B4     	TP_CHD_CPU1_DIMM1_FRU_3
          	               	151       	104B1     	GND                 
          	               	152       	104B4     	M_D_CPU1_SA_DQ<2>   
          	               	153       	104B1     	GND                 
          	               	154       	104B4     	M_D_CPU1_SA_DQ<3>   
          	               	155       	104B1     	GND                 
          	               	156       	104B2     	M_D_CPU1_SA_DQS_DN<5>
          	               	157       	104B2     	M_D_CPU1_SA_DQS_DP<5>
          	               	158       	104B1     	GND                 
          	               	159       	104B4     	M_D_CPU1_SA_DQ<6>   
          	               	160       	104B1     	GND                 
          	               	161       	104B4     	M_D_CPU1_SA_DQ<7>   
          	               	162       	104B1     	GND                 
          	               	163       	104B4     	M_D_CPU1_SA_DQ<10>  
          	               	164       	104B1     	GND                 
          	               	165       	104B4     	M_D_CPU1_SA_DQ<11>  
          	               	166       	104B1     	GND                 
          	               	167       	104B2     	M_D_CPU1_SA_DQS_DN<6>
          	               	168       	104B2     	M_D_CPU1_SA_DQS_DP<6>
          	               	169       	104B1     	GND                 
          	               	170       	104B4     	M_D_CPU1_SA_DQ<14>  
          	               	171       	104B1     	GND                 
          	               	172       	104B4     	M_D_CPU1_SA_DQ<15>  
          	               	173       	104B1     	GND                 
          	               	174       	104B4     	M_D_CPU1_SA_DQ<18>  
          	               	175       	104B1     	GND                 
          	               	176       	104B4     	M_D_CPU1_SA_DQ<19>  
          	               	177       	104B1     	GND                 
          	               	178       	104B2     	M_D_CPU1_SA_DQS_DN<7>
          	               	179       	104B2     	M_D_CPU1_SA_DQS_DP<7>
          	               	180       	104B1     	GND                 
          	               	181       	104B4     	M_D_CPU1_SA_DQ<22>  
          	               	182       	104B1     	GND                 
          	               	183       	104B4     	M_D_CPU1_SA_DQ<23>  
          	               	184       	104B1     	GND                 
          	               	185       	104B4     	M_D_CPU1_SA_DQ<26>  
          	               	186       	104B1     	GND                 
          	               	187       	104B4     	M_D_CPU1_SA_DQ<27>  
          	               	188       	104B1     	GND                 
          	               	189       	104B2     	M_D_CPU1_SA_DQS_DN<8>
          	               	190       	104B2     	M_D_CPU1_SA_DQS_DP<8>
          	               	191       	104B1     	GND                 
          	               	192       	104B4     	M_D_CPU1_SA_DQ<30>  
          	               	193       	104B1     	GND                 
          	               	194       	104B4     	M_D_CPU1_SA_DQ<31>  
          	               	195       	104B1     	GND                 
          	               	196       	104B4     	M_D_CPU1_SA_CB<2>   
          	               	197       	104B1     	GND                 
          	               	198       	104B4     	M_D_CPU1_SA_CB<3>   
          	               	199       	104B1     	GND                 
          	               	200       	104B2     	M_D_CPU1_SA_DQS_DN<9>
          	               	201       	104B2     	M_D_CPU1_SA_DQS_DP<9>
          	               	202       	104B1     	GND                 
          	               	203       	104B4     	M_D_CPU1_SA_CB<6>   
          	               	204       	104B1     	GND                 
          	               	205       	104B4     	M_D_CPU1_SA_CB<7>   
          	               	206       	104B1     	GND                 
          	               	207       	104B4     	RST_M_CD_CPU1_FPGA_N
          	               	208       	104B1     	GND                 
          	               	209       	104B4     	M_D_CPU1_SA_CS_N<1> 
          	               	210       	104B1     	GND                 
          	               	211       	104B4     	M_D_CPU1_SA_CA<1>   
          	               	212       	104B1     	GND                 
          	               	213       	104B4     	M_D_CPU1_SA_CA<3>   
          	               	214       	104B1     	GND                 
          	               	215       	104B4     	M_D_CPU1_SA_CA<5>   
          	               	216       	104B1     	GND                 
          	               	217       	104B4     	M_D_CPU1_CLK_DP<0>  
          	               	218       	104B4     	M_D_CPU1_CLK_DN<0>  
          	               	219       	104B1     	GND                 
          	               	220       	104B4     	TP_CHD_CPU1_DIMM1_FRU_4
          	               	221       	104B4     	M_D_CPU1_SB_CA<1>   
          	               	222       	104B1     	GND                 
          	               	223       	104B4     	M_D_CPU1_SB_CA<3>   
          	               	224       	104B1     	GND                 
          	               	225       	104B4     	M_D_CPU1_SB_CA<5>   
          	               	226       	104B1     	GND                 
          	               	227       	104B4     	M_D_CPU1_SB_PAR     
          	               	228       	104B1     	GND                 
          	               	229       	104B4     	M_D_CPU1_SB_CS_N<1> 
          	               	230       	104B1     	GND                 
          	               	231       	104B4     	TP_CHD_CPU1_DIMM1_FRU_5
          	               	232       	104B4     	TP_CHD_CPU1_DIMM1_FRU_6
          	               	233       	104B1     	GND                 
          	               	234       	104B4     	M_D_CPU1_SB_CB<6>   
          	               	235       	104B1     	GND                 
          	               	236       	104B4     	M_D_CPU1_SB_CB<7>   
          	               	237       	104B1     	GND                 
          	               	238       	104B2     	M_D_CPU1_SB_DQS_DN<4>
          	               	239       	104B2     	M_D_CPU1_SB_DQS_DP<4>
          	               	240       	104B1     	GND                 
          	               	241       	104B4     	M_D_CPU1_SB_CB<2>   
          	               	242       	104B1     	GND                 
          	               	243       	104B4     	M_D_CPU1_SB_CB<3>   
          	               	244       	104B1     	GND                 
          	               	245       	104B4     	M_D_CPU1_SB_DQ<2>   
          	               	246       	104B1     	GND                 
          	               	247       	104B4     	M_D_CPU1_SB_DQ<3>   
          	               	248       	104B1     	GND                 
          	               	249       	104B2     	M_D_CPU1_SB_DQS_DN<5>
          	               	250       	104B2     	M_D_CPU1_SB_DQS_DP<5>
          	               	251       	104B1     	GND                 
          	               	252       	104B4     	M_D_CPU1_SB_DQ<6>   
          	               	253       	104B1     	GND                 
          	               	254       	104B4     	M_D_CPU1_SB_DQ<7>   
          	               	255       	104B1     	GND                 
          	               	256       	104B4     	M_D_CPU1_SB_DQ<10>  
          	               	257       	104B1     	GND                 
          	               	258       	104B4     	M_D_CPU1_SB_DQ<11>  
          	               	259       	104B1     	GND                 
          	               	260       	104B2     	M_D_CPU1_SB_DQS_DN<6>
          	               	261       	104B2     	M_D_CPU1_SB_DQS_DP<6>
          	               	262       	104B1     	GND                 
          	               	263       	104B4     	M_D_CPU1_SB_DQ<14>  
          	               	264       	104B1     	GND                 
          	               	265       	104B4     	M_D_CPU1_SB_DQ<15>  
          	               	266       	104B1     	GND                 
          	               	267       	104B4     	M_D_CPU1_SB_DQ<18>  
          	               	268       	104B1     	GND                 
          	               	269       	104B4     	M_D_CPU1_SB_DQ<19>  
          	               	270       	104B1     	GND                 
          	               	271       	104B2     	M_D_CPU1_SB_DQS_DN<7>
          	               	272       	104B2     	M_D_CPU1_SB_DQS_DP<7>
          	               	273       	104B1     	GND                 
          	               	274       	104B4     	M_D_CPU1_SB_DQ<22>  
          	               	275       	104B1     	GND                 
          	               	276       	104B4     	M_D_CPU1_SB_DQ<23>  
          	               	277       	104B1     	GND                 
          	               	278       	104B4     	M_D_CPU1_SB_DQ<26>  
          	               	279       	104B1     	GND                 
          	               	280       	104B4     	M_D_CPU1_SB_DQ<27>  
          	               	281       	104B1     	GND                 
          	               	282       	104B2     	M_D_CPU1_SB_DQS_DN<8>
          	               	283       	104B2     	M_D_CPU1_SB_DQS_DP<8>
          	               	284       	104B1     	GND                 
          	               	285       	104B4     	M_D_CPU1_SB_DQ<30>  
          	               	286       	104B1     	GND                 
          	               	287       	104B4     	M_D_CPU1_SB_DQ<31>  
          	               	288       	104B1     	GND                 
          	               	G1        	104B1     	GND                 
          	               	G2        	104A1     	GND                 
          	               	G3        	104A1     	GND                 

J24       	SCONN288_ADR50017P087CC	          	          	                    
          	               	1         	105B1     	P12V_S3_AUX_CPU1_NVDIMM
          	               	2         	105B4     	TP_CHD_CPU1_DIMM2_FRU_0
          	               	3         	105B4     	P3V3_AUX            
          	               	4         	105B4     	I3C_SPD_DDRABCD_CPU1_LVC1_SCL_7
          	               	5         	105B4     	I3C_SPD_DDRABCD_CPU1_LVC1_SDA
          	               	6         	105B1     	GND                 
          	               	7         	105B4     	M_D_CPU1_SA_DQ<0>   
          	               	8         	105B1     	GND                 
          	               	9         	105B4     	M_D_CPU1_SA_DQ<1>   
          	               	10        	105B1     	GND                 
          	               	11        	105B2     	M_D_CPU1_SA_DQS_DP<0>
          	               	12        	105B2     	M_D_CPU1_SA_DQS_DN<0>
          	               	13        	105B1     	GND                 
          	               	14        	105B4     	M_D_CPU1_SA_DQ<4>   
          	               	15        	105B1     	GND                 
          	               	16        	105B4     	M_D_CPU1_SA_DQ<5>   
          	               	17        	105B1     	GND                 
          	               	18        	105B4     	M_D_CPU1_SA_DQ<8>   
          	               	19        	105B1     	GND                 
          	               	20        	105B4     	M_D_CPU1_SA_DQ<9>   
          	               	21        	105B1     	GND                 
          	               	22        	105B2     	M_D_CPU1_SA_DQS_DP<1>
          	               	23        	105B2     	M_D_CPU1_SA_DQS_DN<1>
          	               	24        	105B1     	GND                 
          	               	25        	105B4     	M_D_CPU1_SA_DQ<12>  
          	               	26        	105B1     	GND                 
          	               	27        	105B4     	M_D_CPU1_SA_DQ<13>  
          	               	28        	105B1     	GND                 
          	               	29        	105B4     	M_D_CPU1_SA_DQ<16>  
          	               	30        	105B1     	GND                 
          	               	31        	105B4     	M_D_CPU1_SA_DQ<17>  
          	               	32        	105B1     	GND                 
          	               	33        	105B2     	M_D_CPU1_SA_DQS_DP<2>
          	               	34        	105B2     	M_D_CPU1_SA_DQS_DN<2>
          	               	35        	105B1     	GND                 
          	               	36        	105B4     	M_D_CPU1_SA_DQ<20>  
          	               	37        	105B1     	GND                 
          	               	38        	105B4     	M_D_CPU1_SA_DQ<21>  
          	               	39        	105B1     	GND                 
          	               	40        	105B4     	M_D_CPU1_SA_DQ<24>  
          	               	41        	105B1     	GND                 
          	               	42        	105B4     	M_D_CPU1_SA_DQ<25>  
          	               	43        	105B1     	GND                 
          	               	44        	105B2     	M_D_CPU1_SA_DQS_DP<3>
          	               	45        	105B2     	M_D_CPU1_SA_DQS_DN<3>
          	               	46        	105B1     	GND                 
          	               	47        	105B4     	M_D_CPU1_SA_DQ<28>  
          	               	48        	105B1     	GND                 
          	               	49        	105B4     	M_D_CPU1_SA_DQ<29>  
          	               	50        	105B1     	GND                 
          	               	51        	105B4     	M_D_CPU1_SA_CB<0>   
          	               	52        	105B1     	GND                 
          	               	53        	105B4     	M_D_CPU1_SA_CB<1>   
          	               	54        	105B1     	GND                 
          	               	55        	105B2     	M_D_CPU1_SA_DQS_DP<4>
          	               	56        	105B2     	M_D_CPU1_SA_DQS_DN<4>
          	               	57        	105B1     	GND                 
          	               	58        	105B4     	M_D_CPU1_SA_CB<4>   
          	               	59        	105B1     	GND                 
          	               	60        	105B4     	M_D_CPU1_SA_CB<5>   
          	               	61        	105B1     	GND                 
          	               	62        	105B4     	M_D_CPU1_ALERT_N    
          	               	63        	105B1     	GND                 
          	               	64        	105B4     	M_D_CPU1_SA_CS_N<2> 
          	               	65        	105B1     	GND                 
          	               	66        	105B4     	M_D_CPU1_SA_CA<0>   
          	               	67        	105B1     	GND                 
          	               	68        	105B4     	M_D_CPU1_SA_CA<2>   
          	               	69        	105B1     	GND                 
          	               	70        	105B4     	M_D_CPU1_SA_CA<4>   
          	               	71        	105B1     	GND                 
          	               	72        	105B4     	M_D_CPU1_SA_CA<6>   
          	               	73        	105B1     	GND                 
          	               	74        	105B4     	M_D_CPU1_SA_PAR     
          	               	75        	105B1     	GND                 
          	               	76        	105B4     	M_D_CPU1_SB_CA<0>   
          	               	77        	105B1     	GND                 
          	               	78        	105B4     	M_D_CPU1_SB_CA<2>   
          	               	79        	105B1     	GND                 
          	               	80        	105B4     	M_D_CPU1_SB_CA<4>   
          	               	81        	105B1     	GND                 
          	               	82        	105B4     	M_D_CPU1_SB_CA<6>   
          	               	83        	105B1     	GND                 
          	               	84        	105B4     	M_D_CPU1_SB_CS_N<2> 
          	               	85        	105B1     	GND                 
          	               	86        	105A4     	M_D_CPU1_SA_RSP<1>  
          	               	87        	105A4     	M_D_CPU1_SB_RSP<1>  
          	               	88        	105B1     	GND                 
          	               	89        	105B4     	M_D_CPU1_SB_CB<4>   
          	               	90        	105B1     	GND                 
          	               	91        	105B4     	M_D_CPU1_SB_CB<5>   
          	               	92        	105B1     	GND                 
          	               	93        	105B2     	M_D_CPU1_SB_DQS_DP<9>
          	               	94        	105B2     	M_D_CPU1_SB_DQS_DN<9>
          	               	95        	105B1     	GND                 
          	               	96        	105B4     	M_D_CPU1_SB_CB<0>   
          	               	97        	105B1     	GND                 
          	               	98        	105B4     	M_D_CPU1_SB_CB<1>   
          	               	99        	105B1     	GND                 
          	               	100       	105B4     	M_D_CPU1_SB_DQ<0>   
          	               	101       	105B1     	GND                 
          	               	102       	105B4     	M_D_CPU1_SB_DQ<1>   
          	               	103       	105B1     	GND                 
          	               	104       	105B2     	M_D_CPU1_SB_DQS_DP<0>
          	               	105       	105B2     	M_D_CPU1_SB_DQS_DN<0>
          	               	106       	105B1     	GND                 
          	               	107       	105B4     	M_D_CPU1_SB_DQ<4>   
          	               	108       	105B1     	GND                 
          	               	109       	105B4     	M_D_CPU1_SB_DQ<5>   
          	               	110       	105B1     	GND                 
          	               	111       	105B4     	M_D_CPU1_SB_DQ<8>   
          	               	112       	105B1     	GND                 
          	               	113       	105B4     	M_D_CPU1_SB_DQ<9>   
          	               	114       	105B1     	GND                 
          	               	115       	105B2     	M_D_CPU1_SB_DQS_DP<1>
          	               	116       	105B2     	M_D_CPU1_SB_DQS_DN<1>
          	               	117       	105B1     	GND                 
          	               	118       	105B4     	M_D_CPU1_SB_DQ<12>  
          	               	119       	105B1     	GND                 
          	               	120       	105B4     	M_D_CPU1_SB_DQ<13>  
          	               	121       	105B1     	GND                 
          	               	122       	105B4     	M_D_CPU1_SB_DQ<16>  
          	               	123       	105B1     	GND                 
          	               	124       	105B4     	M_D_CPU1_SB_DQ<17>  
          	               	125       	105B1     	GND                 
          	               	126       	105B2     	M_D_CPU1_SB_DQS_DP<2>
          	               	127       	105B2     	M_D_CPU1_SB_DQS_DN<2>
          	               	128       	105B1     	GND                 
          	               	129       	105B4     	M_D_CPU1_SB_DQ<20>  
          	               	130       	105B1     	GND                 
          	               	131       	105B4     	M_D_CPU1_SB_DQ<21>  
          	               	132       	105B1     	GND                 
          	               	133       	105B4     	M_D_CPU1_SB_DQ<24>  
          	               	134       	105B1     	GND                 
          	               	135       	105B4     	M_D_CPU1_SB_DQ<25>  
          	               	136       	105B1     	GND                 
          	               	137       	105B2     	M_D_CPU1_SB_DQS_DP<3>
          	               	138       	105B2     	M_D_CPU1_SB_DQS_DN<3>
          	               	139       	105B1     	GND                 
          	               	140       	105B4     	M_D_CPU1_SB_DQ<28>  
          	               	141       	105B1     	GND                 
          	               	142       	105B4     	M_D_CPU1_SB_DQ<29>  
          	               	143       	105B1     	GND                 
          	               	144       	105B4     	TP_CHD_CPU1_DIMM2_FRU_1
          	               	145       	105B1     	P12V_S3_AUX_CPU1_NVDIMM
          	               	146       	105B1     	P12V_S3_AUX_CPU1_NVDIMM
          	               	147       	105B4     	PWRGD_CHD_CPU1_DIMM2
          	               	148       	105B4     	PD_CHD_CPU1_DIMM2_SAA
          	               	149       	105B4     	TP_CHD_CPU1_DIMM2_FRU_2
          	               	150       	105B4     	TP_CHD_CPU1_DIMM2_FRU_3
          	               	151       	105B1     	GND                 
          	               	152       	105B4     	M_D_CPU1_SA_DQ<2>   
          	               	153       	105B1     	GND                 
          	               	154       	105B4     	M_D_CPU1_SA_DQ<3>   
          	               	155       	105B1     	GND                 
          	               	156       	105B2     	M_D_CPU1_SA_DQS_DN<5>
          	               	157       	105B2     	M_D_CPU1_SA_DQS_DP<5>
          	               	158       	105B1     	GND                 
          	               	159       	105B4     	M_D_CPU1_SA_DQ<6>   
          	               	160       	105B1     	GND                 
          	               	161       	105B4     	M_D_CPU1_SA_DQ<7>   
          	               	162       	105B1     	GND                 
          	               	163       	105B4     	M_D_CPU1_SA_DQ<10>  
          	               	164       	105B1     	GND                 
          	               	165       	105B4     	M_D_CPU1_SA_DQ<11>  
          	               	166       	105B1     	GND                 
          	               	167       	105B2     	M_D_CPU1_SA_DQS_DN<6>
          	               	168       	105B2     	M_D_CPU1_SA_DQS_DP<6>
          	               	169       	105B1     	GND                 
          	               	170       	105B4     	M_D_CPU1_SA_DQ<14>  
          	               	171       	105B1     	GND                 
          	               	172       	105B4     	M_D_CPU1_SA_DQ<15>  
          	               	173       	105B1     	GND                 
          	               	174       	105B4     	M_D_CPU1_SA_DQ<18>  
          	               	175       	105B1     	GND                 
          	               	176       	105B4     	M_D_CPU1_SA_DQ<19>  
          	               	177       	105B1     	GND                 
          	               	178       	105B2     	M_D_CPU1_SA_DQS_DN<7>
          	               	179       	105B2     	M_D_CPU1_SA_DQS_DP<7>
          	               	180       	105B1     	GND                 
          	               	181       	105B4     	M_D_CPU1_SA_DQ<22>  
          	               	182       	105B1     	GND                 
          	               	183       	105B4     	M_D_CPU1_SA_DQ<23>  
          	               	184       	105B1     	GND                 
          	               	185       	105B4     	M_D_CPU1_SA_DQ<26>  
          	               	186       	105B1     	GND                 
          	               	187       	105B4     	M_D_CPU1_SA_DQ<27>  
          	               	188       	105B1     	GND                 
          	               	189       	105B2     	M_D_CPU1_SA_DQS_DN<8>
          	               	190       	105B2     	M_D_CPU1_SA_DQS_DP<8>
          	               	191       	105B1     	GND                 
          	               	192       	105B4     	M_D_CPU1_SA_DQ<30>  
          	               	193       	105B1     	GND                 
          	               	194       	105B4     	M_D_CPU1_SA_DQ<31>  
          	               	195       	105B1     	GND                 
          	               	196       	105B4     	M_D_CPU1_SA_CB<2>   
          	               	197       	105B1     	GND                 
          	               	198       	105B4     	M_D_CPU1_SA_CB<3>   
          	               	199       	105B1     	GND                 
          	               	200       	105B2     	M_D_CPU1_SA_DQS_DN<9>
          	               	201       	105B2     	M_D_CPU1_SA_DQS_DP<9>
          	               	202       	105B1     	GND                 
          	               	203       	105B4     	M_D_CPU1_SA_CB<6>   
          	               	204       	105B1     	GND                 
          	               	205       	105B4     	M_D_CPU1_SA_CB<7>   
          	               	206       	105B1     	GND                 
          	               	207       	105B4     	RST_M_CD_CPU1_FPGA_N
          	               	208       	105B1     	GND                 
          	               	209       	105B4     	M_D_CPU1_SA_CS_N<3> 
          	               	210       	105B1     	GND                 
          	               	211       	105B4     	M_D_CPU1_SA_CA<1>   
          	               	212       	105B1     	GND                 
          	               	213       	105B4     	M_D_CPU1_SA_CA<3>   
          	               	214       	105B1     	GND                 
          	               	215       	105B4     	M_D_CPU1_SA_CA<5>   
          	               	216       	105B1     	GND                 
          	               	217       	105B4     	M_D_CPU1_CLK_DP<1>  
          	               	218       	105B4     	M_D_CPU1_CLK_DN<1>  
          	               	219       	105B1     	GND                 
          	               	220       	105B4     	TP_CHD_CPU1_DIMM2_FRU_4
          	               	221       	105B4     	M_D_CPU1_SB_CA<1>   
          	               	222       	105B1     	GND                 
          	               	223       	105B4     	M_D_CPU1_SB_CA<3>   
          	               	224       	105B1     	GND                 
          	               	225       	105B4     	M_D_CPU1_SB_CA<5>   
          	               	226       	105B1     	GND                 
          	               	227       	105B4     	M_D_CPU1_SB_PAR     
          	               	228       	105B1     	GND                 
          	               	229       	105B4     	M_D_CPU1_SB_CS_N<3> 
          	               	230       	105B1     	GND                 
          	               	231       	105B4     	TP_CHD_CPU1_DIMM2_FRU_5
          	               	232       	105B4     	TP_CHD_CPU1_DIMM2_FRU_6
          	               	233       	105B1     	GND                 
          	               	234       	105B4     	M_D_CPU1_SB_CB<6>   
          	               	235       	105B1     	GND                 
          	               	236       	105B4     	M_D_CPU1_SB_CB<7>   
          	               	237       	105B1     	GND                 
          	               	238       	105B2     	M_D_CPU1_SB_DQS_DN<4>
          	               	239       	105B2     	M_D_CPU1_SB_DQS_DP<4>
          	               	240       	105B1     	GND                 
          	               	241       	105B4     	M_D_CPU1_SB_CB<2>   
          	               	242       	105B1     	GND                 
          	               	243       	105B4     	M_D_CPU1_SB_CB<3>   
          	               	244       	105B1     	GND                 
          	               	245       	105B4     	M_D_CPU1_SB_DQ<2>   
          	               	246       	105B1     	GND                 
          	               	247       	105B4     	M_D_CPU1_SB_DQ<3>   
          	               	248       	105B1     	GND                 
          	               	249       	105B2     	M_D_CPU1_SB_DQS_DN<5>
          	               	250       	105B2     	M_D_CPU1_SB_DQS_DP<5>
          	               	251       	105B1     	GND                 
          	               	252       	105B4     	M_D_CPU1_SB_DQ<6>   
          	               	253       	105B1     	GND                 
          	               	254       	105B4     	M_D_CPU1_SB_DQ<7>   
          	               	255       	105B1     	GND                 
          	               	256       	105B4     	M_D_CPU1_SB_DQ<10>  
          	               	257       	105B1     	GND                 
          	               	258       	105B4     	M_D_CPU1_SB_DQ<11>  
          	               	259       	105B1     	GND                 
          	               	260       	105B2     	M_D_CPU1_SB_DQS_DN<6>
          	               	261       	105B2     	M_D_CPU1_SB_DQS_DP<6>
          	               	262       	105B1     	GND                 
          	               	263       	105B4     	M_D_CPU1_SB_DQ<14>  
          	               	264       	105B1     	GND                 
          	               	265       	105B4     	M_D_CPU1_SB_DQ<15>  
          	               	266       	105B1     	GND                 
          	               	267       	105B4     	M_D_CPU1_SB_DQ<18>  
          	               	268       	105B1     	GND                 
          	               	269       	105B4     	M_D_CPU1_SB_DQ<19>  
          	               	270       	105B1     	GND                 
          	               	271       	105B2     	M_D_CPU1_SB_DQS_DN<7>
          	               	272       	105B2     	M_D_CPU1_SB_DQS_DP<7>
          	               	273       	105B1     	GND                 
          	               	274       	105B4     	M_D_CPU1_SB_DQ<22>  
          	               	275       	105B1     	GND                 
          	               	276       	105B4     	M_D_CPU1_SB_DQ<23>  
          	               	277       	105B1     	GND                 
          	               	278       	105B4     	M_D_CPU1_SB_DQ<26>  
          	               	279       	105B1     	GND                 
          	               	280       	105B4     	M_D_CPU1_SB_DQ<27>  
          	               	281       	105B1     	GND                 
          	               	282       	105B2     	M_D_CPU1_SB_DQS_DN<8>
          	               	283       	105B2     	M_D_CPU1_SB_DQS_DP<8>
          	               	284       	105B1     	GND                 
          	               	285       	105B4     	M_D_CPU1_SB_DQ<30>  
          	               	286       	105B1     	GND                 
          	               	287       	105B4     	M_D_CPU1_SB_DQ<31>  
          	               	288       	105B1     	GND                 
          	               	G1        	105B1     	GND                 
          	               	G2        	105A1     	GND                 
          	               	G3        	105A1     	GND                 

J25       	SCONN288_ADR50017P130CC	          	          	                    
          	               	1         	106B1     	P12V_S3_AUX_CPU1_NVDIMM
          	               	2         	106B4     	TP_CHE_CPU1_DIMM1_FRU_0
          	               	3         	106B4     	P3V3_AUX            
          	               	4         	106B4     	I3C_SPD_DDREFGH_CPU1_LVC1_SCL_R
          	               	5         	106B4     	I3C_SPD_DDREFGH_CPU1_LVC1_SDA
          	               	6         	106B1     	GND                 
          	               	7         	106B4     	M_E_CPU1_SA_DQ<0>   
          	               	8         	106B1     	GND                 
          	               	9         	106B4     	M_E_CPU1_SA_DQ<1>   
          	               	10        	106B1     	GND                 
          	               	11        	106B2     	M_E_CPU1_SA_DQS_DP<0>
          	               	12        	106B2     	M_E_CPU1_SA_DQS_DN<0>
          	               	13        	106B1     	GND                 
          	               	14        	106B4     	M_E_CPU1_SA_DQ<4>   
          	               	15        	106B1     	GND                 
          	               	16        	106B4     	M_E_CPU1_SA_DQ<5>   
          	               	17        	106B1     	GND                 
          	               	18        	106B4     	M_E_CPU1_SA_DQ<8>   
          	               	19        	106B1     	GND                 
          	               	20        	106B4     	M_E_CPU1_SA_DQ<9>   
          	               	21        	106B1     	GND                 
          	               	22        	106B2     	M_E_CPU1_SA_DQS_DP<1>
          	               	23        	106B2     	M_E_CPU1_SA_DQS_DN<1>
          	               	24        	106B1     	GND                 
          	               	25        	106B4     	M_E_CPU1_SA_DQ<12>  
          	               	26        	106B1     	GND                 
          	               	27        	106B4     	M_E_CPU1_SA_DQ<13>  
          	               	28        	106B1     	GND                 
          	               	29        	106B4     	M_E_CPU1_SA_DQ<16>  
          	               	30        	106B1     	GND                 
          	               	31        	106B4     	M_E_CPU1_SA_DQ<17>  
          	               	32        	106B1     	GND                 
          	               	33        	106B2     	M_E_CPU1_SA_DQS_DP<2>
          	               	34        	106B2     	M_E_CPU1_SA_DQS_DN<2>
          	               	35        	106B1     	GND                 
          	               	36        	106B4     	M_E_CPU1_SA_DQ<20>  
          	               	37        	106B1     	GND                 
          	               	38        	106B4     	M_E_CPU1_SA_DQ<21>  
          	               	39        	106B1     	GND                 
          	               	40        	106B4     	M_E_CPU1_SA_DQ<24>  
          	               	41        	106B1     	GND                 
          	               	42        	106B4     	M_E_CPU1_SA_DQ<25>  
          	               	43        	106B1     	GND                 
          	               	44        	106B2     	M_E_CPU1_SA_DQS_DP<3>
          	               	45        	106B2     	M_E_CPU1_SA_DQS_DN<3>
          	               	46        	106B1     	GND                 
          	               	47        	106B4     	M_E_CPU1_SA_DQ<28>  
          	               	48        	106B1     	GND                 
          	               	49        	106B4     	M_E_CPU1_SA_DQ<29>  
          	               	50        	106B1     	GND                 
          	               	51        	106B4     	M_E_CPU1_SA_CB<0>   
          	               	52        	106B1     	GND                 
          	               	53        	106B4     	M_E_CPU1_SA_CB<1>   
          	               	54        	106B1     	GND                 
          	               	55        	106B2     	M_E_CPU1_SA_DQS_DP<4>
          	               	56        	106B2     	M_E_CPU1_SA_DQS_DN<4>
          	               	57        	106B1     	GND                 
          	               	58        	106B4     	M_E_CPU1_SA_CB<4>   
          	               	59        	106B1     	GND                 
          	               	60        	106B4     	M_E_CPU1_SA_CB<5>   
          	               	61        	106B1     	GND                 
          	               	62        	106B4     	M_E_CPU1_ALERT_N    
          	               	63        	106B1     	GND                 
          	               	64        	106B4     	M_E_CPU1_SA_CS_N<0> 
          	               	65        	106B1     	GND                 
          	               	66        	106B4     	M_E_CPU1_SA_CA<0>   
          	               	67        	106B1     	GND                 
          	               	68        	106B4     	M_E_CPU1_SA_CA<2>   
          	               	69        	106B1     	GND                 
          	               	70        	106B4     	M_E_CPU1_SA_CA<4>   
          	               	71        	106B1     	GND                 
          	               	72        	106B4     	M_E_CPU1_SA_CA<6>   
          	               	73        	106B1     	GND                 
          	               	74        	106B4     	M_E_CPU1_SA_PAR     
          	               	75        	106B1     	GND                 
          	               	76        	106B4     	M_E_CPU1_SB_CA<0>   
          	               	77        	106B1     	GND                 
          	               	78        	106B4     	M_E_CPU1_SB_CA<2>   
          	               	79        	106B1     	GND                 
          	               	80        	106B4     	M_E_CPU1_SB_CA<4>   
          	               	81        	106B1     	GND                 
          	               	82        	106B4     	M_E_CPU1_SB_CA<6>   
          	               	83        	106B1     	GND                 
          	               	84        	106B4     	M_E_CPU1_SB_CS_N<0> 
          	               	85        	106B1     	GND                 
          	               	86        	106A4     	M_E_CPU1_SA_RSP<0>  
          	               	87        	106A4     	M_E_CPU1_SB_RSP<0>  
          	               	88        	106B1     	GND                 
          	               	89        	106B4     	M_E_CPU1_SB_CB<4>   
          	               	90        	106B1     	GND                 
          	               	91        	106B4     	M_E_CPU1_SB_CB<5>   
          	               	92        	106B1     	GND                 
          	               	93        	106B2     	M_E_CPU1_SB_DQS_DP<9>
          	               	94        	106B2     	M_E_CPU1_SB_DQS_DN<9>
          	               	95        	106B1     	GND                 
          	               	96        	106B4     	M_E_CPU1_SB_CB<0>   
          	               	97        	106B1     	GND                 
          	               	98        	106B4     	M_E_CPU1_SB_CB<1>   
          	               	99        	106B1     	GND                 
          	               	100       	106B4     	M_E_CPU1_SB_DQ<0>   
          	               	101       	106B1     	GND                 
          	               	102       	106B4     	M_E_CPU1_SB_DQ<1>   
          	               	103       	106B1     	GND                 
          	               	104       	106B2     	M_E_CPU1_SB_DQS_DP<0>
          	               	105       	106B2     	M_E_CPU1_SB_DQS_DN<0>
          	               	106       	106B1     	GND                 
          	               	107       	106B4     	M_E_CPU1_SB_DQ<4>   
          	               	108       	106B1     	GND                 
          	               	109       	106B4     	M_E_CPU1_SB_DQ<5>   
          	               	110       	106B1     	GND                 
          	               	111       	106B4     	M_E_CPU1_SB_DQ<8>   
          	               	112       	106B1     	GND                 
          	               	113       	106B4     	M_E_CPU1_SB_DQ<9>   
          	               	114       	106B1     	GND                 
          	               	115       	106B2     	M_E_CPU1_SB_DQS_DP<1>
          	               	116       	106B2     	M_E_CPU1_SB_DQS_DN<1>
          	               	117       	106B1     	GND                 
          	               	118       	106B4     	M_E_CPU1_SB_DQ<12>  
          	               	119       	106B1     	GND                 
          	               	120       	106B4     	M_E_CPU1_SB_DQ<13>  
          	               	121       	106B1     	GND                 
          	               	122       	106B4     	M_E_CPU1_SB_DQ<16>  
          	               	123       	106B1     	GND                 
          	               	124       	106B4     	M_E_CPU1_SB_DQ<17>  
          	               	125       	106B1     	GND                 
          	               	126       	106B2     	M_E_CPU1_SB_DQS_DP<2>
          	               	127       	106B2     	M_E_CPU1_SB_DQS_DN<2>
          	               	128       	106B1     	GND                 
          	               	129       	106B4     	M_E_CPU1_SB_DQ<20>  
          	               	130       	106B1     	GND                 
          	               	131       	106B4     	M_E_CPU1_SB_DQ<21>  
          	               	132       	106B1     	GND                 
          	               	133       	106B4     	M_E_CPU1_SB_DQ<24>  
          	               	134       	106B1     	GND                 
          	               	135       	106B4     	M_E_CPU1_SB_DQ<25>  
          	               	136       	106B1     	GND                 
          	               	137       	106B2     	M_E_CPU1_SB_DQS_DP<3>
          	               	138       	106B2     	M_E_CPU1_SB_DQS_DN<3>
          	               	139       	106B1     	GND                 
          	               	140       	106B4     	M_E_CPU1_SB_DQ<28>  
          	               	141       	106B1     	GND                 
          	               	142       	106B4     	M_E_CPU1_SB_DQ<29>  
          	               	143       	106B1     	GND                 
          	               	144       	106B4     	TP_CHE_CPU1_DIMM1_FRU_1
          	               	145       	106B1     	P12V_S3_AUX_CPU1_NVDIMM
          	               	146       	106B1     	P12V_S3_AUX_CPU1_NVDIMM
          	               	147       	106B4     	PWRGD_CHE_CPU1_DIMM1
          	               	148       	106B4     	PD_CHE_CPU1_DIMM1_SAA
          	               	149       	106B4     	TP_CHE_CPU1_DIMM1_FRU_2
          	               	150       	106B4     	TP_CHE_CPU1_DIMM1_FRU_3
          	               	151       	106B1     	GND                 
          	               	152       	106B4     	M_E_CPU1_SA_DQ<2>   
          	               	153       	106B1     	GND                 
          	               	154       	106B4     	M_E_CPU1_SA_DQ<3>   
          	               	155       	106B1     	GND                 
          	               	156       	106B2     	M_E_CPU1_SA_DQS_DN<5>
          	               	157       	106B2     	M_E_CPU1_SA_DQS_DP<5>
          	               	158       	106B1     	GND                 
          	               	159       	106B4     	M_E_CPU1_SA_DQ<6>   
          	               	160       	106B1     	GND                 
          	               	161       	106B4     	M_E_CPU1_SA_DQ<7>   
          	               	162       	106B1     	GND                 
          	               	163       	106B4     	M_E_CPU1_SA_DQ<10>  
          	               	164       	106B1     	GND                 
          	               	165       	106B4     	M_E_CPU1_SA_DQ<11>  
          	               	166       	106B1     	GND                 
          	               	167       	106B2     	M_E_CPU1_SA_DQS_DN<6>
          	               	168       	106B2     	M_E_CPU1_SA_DQS_DP<6>
          	               	169       	106B1     	GND                 
          	               	170       	106B4     	M_E_CPU1_SA_DQ<14>  
          	               	171       	106B1     	GND                 
          	               	172       	106B4     	M_E_CPU1_SA_DQ<15>  
          	               	173       	106B1     	GND                 
          	               	174       	106B4     	M_E_CPU1_SA_DQ<18>  
          	               	175       	106B1     	GND                 
          	               	176       	106B4     	M_E_CPU1_SA_DQ<19>  
          	               	177       	106B1     	GND                 
          	               	178       	106B2     	M_E_CPU1_SA_DQS_DN<7>
          	               	179       	106B2     	M_E_CPU1_SA_DQS_DP<7>
          	               	180       	106B1     	GND                 
          	               	181       	106B4     	M_E_CPU1_SA_DQ<22>  
          	               	182       	106B1     	GND                 
          	               	183       	106B4     	M_E_CPU1_SA_DQ<23>  
          	               	184       	106B1     	GND                 
          	               	185       	106B4     	M_E_CPU1_SA_DQ<26>  
          	               	186       	106B1     	GND                 
          	               	187       	106B4     	M_E_CPU1_SA_DQ<27>  
          	               	188       	106B1     	GND                 
          	               	189       	106B2     	M_E_CPU1_SA_DQS_DN<8>
          	               	190       	106B2     	M_E_CPU1_SA_DQS_DP<8>
          	               	191       	106B1     	GND                 
          	               	192       	106B4     	M_E_CPU1_SA_DQ<30>  
          	               	193       	106B1     	GND                 
          	               	194       	106B4     	M_E_CPU1_SA_DQ<31>  
          	               	195       	106B1     	GND                 
          	               	196       	106B4     	M_E_CPU1_SA_CB<2>   
          	               	197       	106B1     	GND                 
          	               	198       	106B4     	M_E_CPU1_SA_CB<3>   
          	               	199       	106B1     	GND                 
          	               	200       	106B2     	M_E_CPU1_SA_DQS_DN<9>
          	               	201       	106B2     	M_E_CPU1_SA_DQS_DP<9>
          	               	202       	106B1     	GND                 
          	               	203       	106B4     	M_E_CPU1_SA_CB<6>   
          	               	204       	106B1     	GND                 
          	               	205       	106B4     	M_E_CPU1_SA_CB<7>   
          	               	206       	106B1     	GND                 
          	               	207       	106B4     	RST_M_EF_CPU1_FPGA_N
          	               	208       	106B1     	GND                 
          	               	209       	106B4     	M_E_CPU1_SA_CS_N<1> 
          	               	210       	106B1     	GND                 
          	               	211       	106B4     	M_E_CPU1_SA_CA<1>   
          	               	212       	106B1     	GND                 
          	               	213       	106B4     	M_E_CPU1_SA_CA<3>   
          	               	214       	106B1     	GND                 
          	               	215       	106B4     	M_E_CPU1_SA_CA<5>   
          	               	216       	106B1     	GND                 
          	               	217       	106B4     	M_E_CPU1_CLK_DP<0>  
          	               	218       	106B4     	M_E_CPU1_CLK_DN<0>  
          	               	219       	106B1     	GND                 
          	               	220       	106B4     	TP_CHE_CPU1_DIMM1_FRU_4
          	               	221       	106B4     	M_E_CPU1_SB_CA<1>   
          	               	222       	106B1     	GND                 
          	               	223       	106B4     	M_E_CPU1_SB_CA<3>   
          	               	224       	106B1     	GND                 
          	               	225       	106B4     	M_E_CPU1_SB_CA<5>   
          	               	226       	106B1     	GND                 
          	               	227       	106B4     	M_E_CPU1_SB_PAR     
          	               	228       	106B1     	GND                 
          	               	229       	106B4     	M_E_CPU1_SB_CS_N<1> 
          	               	230       	106B1     	GND                 
          	               	231       	106B4     	TP_CHE_CPU1_DIMM1_FRU_5
          	               	232       	106B4     	TP_CHE_CPU1_DIMM1_FRU_6
          	               	233       	106B1     	GND                 
          	               	234       	106B4     	M_E_CPU1_SB_CB<6>   
          	               	235       	106B1     	GND                 
          	               	236       	106B4     	M_E_CPU1_SB_CB<7>   
          	               	237       	106B1     	GND                 
          	               	238       	106B2     	M_E_CPU1_SB_DQS_DN<4>
          	               	239       	106B2     	M_E_CPU1_SB_DQS_DP<4>
          	               	240       	106B1     	GND                 
          	               	241       	106B4     	M_E_CPU1_SB_CB<2>   
          	               	242       	106B1     	GND                 
          	               	243       	106B4     	M_E_CPU1_SB_CB<3>   
          	               	244       	106B1     	GND                 
          	               	245       	106B4     	M_E_CPU1_SB_DQ<2>   
          	               	246       	106B1     	GND                 
          	               	247       	106B4     	M_E_CPU1_SB_DQ<3>   
          	               	248       	106B1     	GND                 
          	               	249       	106B2     	M_E_CPU1_SB_DQS_DN<5>
          	               	250       	106B2     	M_E_CPU1_SB_DQS_DP<5>
          	               	251       	106B1     	GND                 
          	               	252       	106B4     	M_E_CPU1_SB_DQ<6>   
          	               	253       	106B1     	GND                 
          	               	254       	106B4     	M_E_CPU1_SB_DQ<7>   
          	               	255       	106B1     	GND                 
          	               	256       	106B4     	M_E_CPU1_SB_DQ<10>  
          	               	257       	106B1     	GND                 
          	               	258       	106B4     	M_E_CPU1_SB_DQ<11>  
          	               	259       	106B1     	GND                 
          	               	260       	106B2     	M_E_CPU1_SB_DQS_DN<6>
          	               	261       	106B2     	M_E_CPU1_SB_DQS_DP<6>
          	               	262       	106B1     	GND                 
          	               	263       	106B4     	M_E_CPU1_SB_DQ<14>  
          	               	264       	106B1     	GND                 
          	               	265       	106B4     	M_E_CPU1_SB_DQ<15>  
          	               	266       	106B1     	GND                 
          	               	267       	106B4     	M_E_CPU1_SB_DQ<18>  
          	               	268       	106B1     	GND                 
          	               	269       	106B4     	M_E_CPU1_SB_DQ<19>  
          	               	270       	106B1     	GND                 
          	               	271       	106B2     	M_E_CPU1_SB_DQS_DN<7>
          	               	272       	106B2     	M_E_CPU1_SB_DQS_DP<7>
          	               	273       	106B1     	GND                 
          	               	274       	106B4     	M_E_CPU1_SB_DQ<22>  
          	               	275       	106B1     	GND                 
          	               	276       	106B4     	M_E_CPU1_SB_DQ<23>  
          	               	277       	106B1     	GND                 
          	               	278       	106B4     	M_E_CPU1_SB_DQ<26>  
          	               	279       	106B1     	GND                 
          	               	280       	106B4     	M_E_CPU1_SB_DQ<27>  
          	               	281       	106B1     	GND                 
          	               	282       	106B2     	M_E_CPU1_SB_DQS_DN<8>
          	               	283       	106B2     	M_E_CPU1_SB_DQS_DP<8>
          	               	284       	106B1     	GND                 
          	               	285       	106B4     	M_E_CPU1_SB_DQ<30>  
          	               	286       	106B1     	GND                 
          	               	287       	106B4     	M_E_CPU1_SB_DQ<31>  
          	               	288       	106B1     	GND                 
          	               	G1        	106B1     	GND                 
          	               	G2        	106A1     	GND                 
          	               	G3        	106A1     	GND                 

J26       	SCONN288_ADR50017P087CC	          	          	                    
          	               	1         	107B1     	P12V_S3_AUX_CPU1_NVDIMM
          	               	2         	107B4     	TP_CHE_CPU1_DIMM2_FRU_0
          	               	3         	107B4     	P3V3_AUX            
          	               	4         	107B4     	I3C_SPD_DDREFGH_CPU1_LVC1_SCL_1
          	               	5         	107B4     	I3C_SPD_DDREFGH_CPU1_LVC1_SDA
          	               	6         	107B1     	GND                 
          	               	7         	107B4     	M_E_CPU1_SA_DQ<0>   
          	               	8         	107B1     	GND                 
          	               	9         	107B4     	M_E_CPU1_SA_DQ<1>   
          	               	10        	107B1     	GND                 
          	               	11        	107B2     	M_E_CPU1_SA_DQS_DP<0>
          	               	12        	107B2     	M_E_CPU1_SA_DQS_DN<0>
          	               	13        	107B1     	GND                 
          	               	14        	107B4     	M_E_CPU1_SA_DQ<4>   
          	               	15        	107B1     	GND                 
          	               	16        	107B4     	M_E_CPU1_SA_DQ<5>   
          	               	17        	107B1     	GND                 
          	               	18        	107B4     	M_E_CPU1_SA_DQ<8>   
          	               	19        	107B1     	GND                 
          	               	20        	107B4     	M_E_CPU1_SA_DQ<9>   
          	               	21        	107B1     	GND                 
          	               	22        	107B2     	M_E_CPU1_SA_DQS_DP<1>
          	               	23        	107B2     	M_E_CPU1_SA_DQS_DN<1>
          	               	24        	107B1     	GND                 
          	               	25        	107B4     	M_E_CPU1_SA_DQ<12>  
          	               	26        	107B1     	GND                 
          	               	27        	107B4     	M_E_CPU1_SA_DQ<13>  
          	               	28        	107B1     	GND                 
          	               	29        	107B4     	M_E_CPU1_SA_DQ<16>  
          	               	30        	107B1     	GND                 
          	               	31        	107B4     	M_E_CPU1_SA_DQ<17>  
          	               	32        	107B1     	GND                 
          	               	33        	107B2     	M_E_CPU1_SA_DQS_DP<2>
          	               	34        	107B2     	M_E_CPU1_SA_DQS_DN<2>
          	               	35        	107B1     	GND                 
          	               	36        	107B4     	M_E_CPU1_SA_DQ<20>  
          	               	37        	107B1     	GND                 
          	               	38        	107B4     	M_E_CPU1_SA_DQ<21>  
          	               	39        	107B1     	GND                 
          	               	40        	107B4     	M_E_CPU1_SA_DQ<24>  
          	               	41        	107B1     	GND                 
          	               	42        	107B4     	M_E_CPU1_SA_DQ<25>  
          	               	43        	107B1     	GND                 
          	               	44        	107B2     	M_E_CPU1_SA_DQS_DP<3>
          	               	45        	107B2     	M_E_CPU1_SA_DQS_DN<3>
          	               	46        	107B1     	GND                 
          	               	47        	107B4     	M_E_CPU1_SA_DQ<28>  
          	               	48        	107B1     	GND                 
          	               	49        	107B4     	M_E_CPU1_SA_DQ<29>  
          	               	50        	107B1     	GND                 
          	               	51        	107B4     	M_E_CPU1_SA_CB<0>   
          	               	52        	107B1     	GND                 
          	               	53        	107B4     	M_E_CPU1_SA_CB<1>   
          	               	54        	107B1     	GND                 
          	               	55        	107B2     	M_E_CPU1_SA_DQS_DP<4>
          	               	56        	107B2     	M_E_CPU1_SA_DQS_DN<4>
          	               	57        	107B1     	GND                 
          	               	58        	107B4     	M_E_CPU1_SA_CB<4>   
          	               	59        	107B1     	GND                 
          	               	60        	107B4     	M_E_CPU1_SA_CB<5>   
          	               	61        	107B1     	GND                 
          	               	62        	107B4     	M_E_CPU1_ALERT_N    
          	               	63        	107B1     	GND                 
          	               	64        	107B4     	M_E_CPU1_SA_CS_N<2> 
          	               	65        	107B1     	GND                 
          	               	66        	107B4     	M_E_CPU1_SA_CA<0>   
          	               	67        	107B1     	GND                 
          	               	68        	107B4     	M_E_CPU1_SA_CA<2>   
          	               	69        	107B1     	GND                 
          	               	70        	107B4     	M_E_CPU1_SA_CA<4>   
          	               	71        	107B1     	GND                 
          	               	72        	107B4     	M_E_CPU1_SA_CA<6>   
          	               	73        	107B1     	GND                 
          	               	74        	107B4     	M_E_CPU1_SA_PAR     
          	               	75        	107B1     	GND                 
          	               	76        	107B4     	M_E_CPU1_SB_CA<0>   
          	               	77        	107B1     	GND                 
          	               	78        	107B4     	M_E_CPU1_SB_CA<2>   
          	               	79        	107B1     	GND                 
          	               	80        	107B4     	M_E_CPU1_SB_CA<4>   
          	               	81        	107B1     	GND                 
          	               	82        	107B4     	M_E_CPU1_SB_CA<6>   
          	               	83        	107B1     	GND                 
          	               	84        	107B4     	M_E_CPU1_SB_CS_N<2> 
          	               	85        	107B1     	GND                 
          	               	86        	107A4     	M_E_CPU1_SA_RSP<1>  
          	               	87        	107A4     	M_E_CPU1_SB_RSP<1>  
          	               	88        	107B1     	GND                 
          	               	89        	107B4     	M_E_CPU1_SB_CB<4>   
          	               	90        	107B1     	GND                 
          	               	91        	107B4     	M_E_CPU1_SB_CB<5>   
          	               	92        	107B1     	GND                 
          	               	93        	107B2     	M_E_CPU1_SB_DQS_DP<9>
          	               	94        	107B2     	M_E_CPU1_SB_DQS_DN<9>
          	               	95        	107B1     	GND                 
          	               	96        	107B4     	M_E_CPU1_SB_CB<0>   
          	               	97        	107B1     	GND                 
          	               	98        	107B4     	M_E_CPU1_SB_CB<1>   
          	               	99        	107B1     	GND                 
          	               	100       	107B4     	M_E_CPU1_SB_DQ<0>   
          	               	101       	107B1     	GND                 
          	               	102       	107B4     	M_E_CPU1_SB_DQ<1>   
          	               	103       	107B1     	GND                 
          	               	104       	107B2     	M_E_CPU1_SB_DQS_DP<0>
          	               	105       	107B2     	M_E_CPU1_SB_DQS_DN<0>
          	               	106       	107B1     	GND                 
          	               	107       	107B4     	M_E_CPU1_SB_DQ<4>   
          	               	108       	107B1     	GND                 
          	               	109       	107B4     	M_E_CPU1_SB_DQ<5>   
          	               	110       	107B1     	GND                 
          	               	111       	107B4     	M_E_CPU1_SB_DQ<8>   
          	               	112       	107B1     	GND                 
          	               	113       	107B4     	M_E_CPU1_SB_DQ<9>   
          	               	114       	107B1     	GND                 
          	               	115       	107B2     	M_E_CPU1_SB_DQS_DP<1>
          	               	116       	107B2     	M_E_CPU1_SB_DQS_DN<1>
          	               	117       	107B1     	GND                 
          	               	118       	107B4     	M_E_CPU1_SB_DQ<12>  
          	               	119       	107B1     	GND                 
          	               	120       	107B4     	M_E_CPU1_SB_DQ<13>  
          	               	121       	107B1     	GND                 
          	               	122       	107B4     	M_E_CPU1_SB_DQ<16>  
          	               	123       	107B1     	GND                 
          	               	124       	107B4     	M_E_CPU1_SB_DQ<17>  
          	               	125       	107B1     	GND                 
          	               	126       	107B2     	M_E_CPU1_SB_DQS_DP<2>
          	               	127       	107B2     	M_E_CPU1_SB_DQS_DN<2>
          	               	128       	107B1     	GND                 
          	               	129       	107B4     	M_E_CPU1_SB_DQ<20>  
          	               	130       	107B1     	GND                 
          	               	131       	107B4     	M_E_CPU1_SB_DQ<21>  
          	               	132       	107B1     	GND                 
          	               	133       	107B4     	M_E_CPU1_SB_DQ<24>  
          	               	134       	107B1     	GND                 
          	               	135       	107B4     	M_E_CPU1_SB_DQ<25>  
          	               	136       	107B1     	GND                 
          	               	137       	107B2     	M_E_CPU1_SB_DQS_DP<3>
          	               	138       	107B2     	M_E_CPU1_SB_DQS_DN<3>
          	               	139       	107B1     	GND                 
          	               	140       	107B4     	M_E_CPU1_SB_DQ<28>  
          	               	141       	107B1     	GND                 
          	               	142       	107B4     	M_E_CPU1_SB_DQ<29>  
          	               	143       	107B1     	GND                 
          	               	144       	107B4     	TP_CHE_CPU1_DIMM2_FRU_1
          	               	145       	107B1     	P12V_S3_AUX_CPU1_NVDIMM
          	               	146       	107B1     	P12V_S3_AUX_CPU1_NVDIMM
          	               	147       	107B4     	PWRGD_CHE_CPU1_DIMM2
          	               	148       	107B4     	PD_CHE_CPU1_DIMM2_SAA
          	               	149       	107B4     	TP_CHE_CPU1_DIMM2_FRU_2
          	               	150       	107B4     	TP_CHE_CPU1_DIMM2_FRU_3
          	               	151       	107B1     	GND                 
          	               	152       	107B4     	M_E_CPU1_SA_DQ<2>   
          	               	153       	107B1     	GND                 
          	               	154       	107B4     	M_E_CPU1_SA_DQ<3>   
          	               	155       	107B1     	GND                 
          	               	156       	107B2     	M_E_CPU1_SA_DQS_DN<5>
          	               	157       	107B2     	M_E_CPU1_SA_DQS_DP<5>
          	               	158       	107B1     	GND                 
          	               	159       	107B4     	M_E_CPU1_SA_DQ<6>   
          	               	160       	107B1     	GND                 
          	               	161       	107B4     	M_E_CPU1_SA_DQ<7>   
          	               	162       	107B1     	GND                 
          	               	163       	107B4     	M_E_CPU1_SA_DQ<10>  
          	               	164       	107B1     	GND                 
          	               	165       	107B4     	M_E_CPU1_SA_DQ<11>  
          	               	166       	107B1     	GND                 
          	               	167       	107B2     	M_E_CPU1_SA_DQS_DN<6>
          	               	168       	107B2     	M_E_CPU1_SA_DQS_DP<6>
          	               	169       	107B1     	GND                 
          	               	170       	107B4     	M_E_CPU1_SA_DQ<14>  
          	               	171       	107B1     	GND                 
          	               	172       	107B4     	M_E_CPU1_SA_DQ<15>  
          	               	173       	107B1     	GND                 
          	               	174       	107B4     	M_E_CPU1_SA_DQ<18>  
          	               	175       	107B1     	GND                 
          	               	176       	107B4     	M_E_CPU1_SA_DQ<19>  
          	               	177       	107B1     	GND                 
          	               	178       	107B2     	M_E_CPU1_SA_DQS_DN<7>
          	               	179       	107B2     	M_E_CPU1_SA_DQS_DP<7>
          	               	180       	107B1     	GND                 
          	               	181       	107B4     	M_E_CPU1_SA_DQ<22>  
          	               	182       	107B1     	GND                 
          	               	183       	107B4     	M_E_CPU1_SA_DQ<23>  
          	               	184       	107B1     	GND                 
          	               	185       	107B4     	M_E_CPU1_SA_DQ<26>  
          	               	186       	107B1     	GND                 
          	               	187       	107B4     	M_E_CPU1_SA_DQ<27>  
          	               	188       	107B1     	GND                 
          	               	189       	107B2     	M_E_CPU1_SA_DQS_DN<8>
          	               	190       	107B2     	M_E_CPU1_SA_DQS_DP<8>
          	               	191       	107B1     	GND                 
          	               	192       	107B4     	M_E_CPU1_SA_DQ<30>  
          	               	193       	107B1     	GND                 
          	               	194       	107B4     	M_E_CPU1_SA_DQ<31>  
          	               	195       	107B1     	GND                 
          	               	196       	107B4     	M_E_CPU1_SA_CB<2>   
          	               	197       	107B1     	GND                 
          	               	198       	107B4     	M_E_CPU1_SA_CB<3>   
          	               	199       	107B1     	GND                 
          	               	200       	107B2     	M_E_CPU1_SA_DQS_DN<9>
          	               	201       	107B2     	M_E_CPU1_SA_DQS_DP<9>
          	               	202       	107B1     	GND                 
          	               	203       	107B4     	M_E_CPU1_SA_CB<6>   
          	               	204       	107B1     	GND                 
          	               	205       	107B4     	M_E_CPU1_SA_CB<7>   
          	               	206       	107B1     	GND                 
          	               	207       	107B4     	RST_M_EF_CPU1_FPGA_N
          	               	208       	107B1     	GND                 
          	               	209       	107B4     	M_E_CPU1_SA_CS_N<3> 
          	               	210       	107B1     	GND                 
          	               	211       	107B4     	M_E_CPU1_SA_CA<1>   
          	               	212       	107B1     	GND                 
          	               	213       	107B4     	M_E_CPU1_SA_CA<3>   
          	               	214       	107B1     	GND                 
          	               	215       	107B4     	M_E_CPU1_SA_CA<5>   
          	               	216       	107B1     	GND                 
          	               	217       	107B4     	M_E_CPU1_CLK_DP<1>  
          	               	218       	107B4     	M_E_CPU1_CLK_DN<1>  
          	               	219       	107B1     	GND                 
          	               	220       	107B4     	TP_CHE_CPU1_DIMM2_FRU_4
          	               	221       	107B4     	M_E_CPU1_SB_CA<1>   
          	               	222       	107B1     	GND                 
          	               	223       	107B4     	M_E_CPU1_SB_CA<3>   
          	               	224       	107B1     	GND                 
          	               	225       	107B4     	M_E_CPU1_SB_CA<5>   
          	               	226       	107B1     	GND                 
          	               	227       	107B4     	M_E_CPU1_SB_PAR     
          	               	228       	107B1     	GND                 
          	               	229       	107B4     	M_E_CPU1_SB_CS_N<3> 
          	               	230       	107B1     	GND                 
          	               	231       	107B4     	TP_CHE_CPU1_DIMM2_FRU_5
          	               	232       	107B4     	TP_CHE_CPU1_DIMM2_FRU_6
          	               	233       	107B1     	GND                 
          	               	234       	107B4     	M_E_CPU1_SB_CB<6>   
          	               	235       	107B1     	GND                 
          	               	236       	107B4     	M_E_CPU1_SB_CB<7>   
          	               	237       	107B1     	GND                 
          	               	238       	107B2     	M_E_CPU1_SB_DQS_DN<4>
          	               	239       	107B2     	M_E_CPU1_SB_DQS_DP<4>
          	               	240       	107B1     	GND                 
          	               	241       	107B4     	M_E_CPU1_SB_CB<2>   
          	               	242       	107B1     	GND                 
          	               	243       	107B4     	M_E_CPU1_SB_CB<3>   
          	               	244       	107B1     	GND                 
          	               	245       	107B4     	M_E_CPU1_SB_DQ<2>   
          	               	246       	107B1     	GND                 
          	               	247       	107B4     	M_E_CPU1_SB_DQ<3>   
          	               	248       	107B1     	GND                 
          	               	249       	107B2     	M_E_CPU1_SB_DQS_DN<5>
          	               	250       	107B2     	M_E_CPU1_SB_DQS_DP<5>
          	               	251       	107B1     	GND                 
          	               	252       	107B4     	M_E_CPU1_SB_DQ<6>   
          	               	253       	107B1     	GND                 
          	               	254       	107B4     	M_E_CPU1_SB_DQ<7>   
          	               	255       	107B1     	GND                 
          	               	256       	107B4     	M_E_CPU1_SB_DQ<10>  
          	               	257       	107B1     	GND                 
          	               	258       	107B4     	M_E_CPU1_SB_DQ<11>  
          	               	259       	107B1     	GND                 
          	               	260       	107B2     	M_E_CPU1_SB_DQS_DN<6>
          	               	261       	107B2     	M_E_CPU1_SB_DQS_DP<6>
          	               	262       	107B1     	GND                 
          	               	263       	107B4     	M_E_CPU1_SB_DQ<14>  
          	               	264       	107B1     	GND                 
          	               	265       	107B4     	M_E_CPU1_SB_DQ<15>  
          	               	266       	107B1     	GND                 
          	               	267       	107B4     	M_E_CPU1_SB_DQ<18>  
          	               	268       	107B1     	GND                 
          	               	269       	107B4     	M_E_CPU1_SB_DQ<19>  
          	               	270       	107B1     	GND                 
          	               	271       	107B2     	M_E_CPU1_SB_DQS_DN<7>
          	               	272       	107B2     	M_E_CPU1_SB_DQS_DP<7>
          	               	273       	107B1     	GND                 
          	               	274       	107B4     	M_E_CPU1_SB_DQ<22>  
          	               	275       	107B1     	GND                 
          	               	276       	107B4     	M_E_CPU1_SB_DQ<23>  
          	               	277       	107B1     	GND                 
          	               	278       	107B4     	M_E_CPU1_SB_DQ<26>  
          	               	279       	107B1     	GND                 
          	               	280       	107B4     	M_E_CPU1_SB_DQ<27>  
          	               	281       	107B1     	GND                 
          	               	282       	107B2     	M_E_CPU1_SB_DQS_DN<8>
          	               	283       	107B2     	M_E_CPU1_SB_DQS_DP<8>
          	               	284       	107B1     	GND                 
          	               	285       	107B4     	M_E_CPU1_SB_DQ<30>  
          	               	286       	107B1     	GND                 
          	               	287       	107B4     	M_E_CPU1_SB_DQ<31>  
          	               	288       	107B1     	GND                 
          	               	G1        	107B1     	GND                 
          	               	G2        	107A1     	GND                 
          	               	G3        	107A1     	GND                 

J27       	SCONN288_ADR50017P130CC	          	          	                    
          	               	1         	108B1     	P12V_S3_AUX_CPU1_NVDIMM
          	               	2         	108B4     	TP_CHF_CPU1_DIMM1_FRU_0
          	               	3         	108B4     	P3V3_AUX            
          	               	4         	108B4     	I3C_SPD_DDREFGH_CPU1_LVC1_SCL_2
          	               	5         	108B4     	I3C_SPD_DDREFGH_CPU1_LVC1_SDA
          	               	6         	108B1     	GND                 
          	               	7         	108B4     	M_F_CPU1_SA_DQ<0>   
          	               	8         	108B1     	GND                 
          	               	9         	108B4     	M_F_CPU1_SA_DQ<1>   
          	               	10        	108B1     	GND                 
          	               	11        	108B2     	M_F_CPU1_SA_DQS_DP<0>
          	               	12        	108B2     	M_F_CPU1_SA_DQS_DN<0>
          	               	13        	108B1     	GND                 
          	               	14        	108B4     	M_F_CPU1_SA_DQ<4>   
          	               	15        	108B1     	GND                 
          	               	16        	108B4     	M_F_CPU1_SA_DQ<5>   
          	               	17        	108B1     	GND                 
          	               	18        	108B4     	M_F_CPU1_SA_DQ<8>   
          	               	19        	108B1     	GND                 
          	               	20        	108B4     	M_F_CPU1_SA_DQ<9>   
          	               	21        	108B1     	GND                 
          	               	22        	108B2     	M_F_CPU1_SA_DQS_DP<1>
          	               	23        	108B2     	M_F_CPU1_SA_DQS_DN<1>
          	               	24        	108B1     	GND                 
          	               	25        	108B4     	M_F_CPU1_SA_DQ<12>  
          	               	26        	108B1     	GND                 
          	               	27        	108B4     	M_F_CPU1_SA_DQ<13>  
          	               	28        	108B1     	GND                 
          	               	29        	108B4     	M_F_CPU1_SA_DQ<16>  
          	               	30        	108B1     	GND                 
          	               	31        	108B4     	M_F_CPU1_SA_DQ<17>  
          	               	32        	108B1     	GND                 
          	               	33        	108B2     	M_F_CPU1_SA_DQS_DP<2>
          	               	34        	108B2     	M_F_CPU1_SA_DQS_DN<2>
          	               	35        	108B1     	GND                 
          	               	36        	108B4     	M_F_CPU1_SA_DQ<20>  
          	               	37        	108B1     	GND                 
          	               	38        	108B4     	M_F_CPU1_SA_DQ<21>  
          	               	39        	108B1     	GND                 
          	               	40        	108B4     	M_F_CPU1_SA_DQ<24>  
          	               	41        	108B1     	GND                 
          	               	42        	108B4     	M_F_CPU1_SA_DQ<25>  
          	               	43        	108B1     	GND                 
          	               	44        	108B2     	M_F_CPU1_SA_DQS_DP<3>
          	               	45        	108B2     	M_F_CPU1_SA_DQS_DN<3>
          	               	46        	108B1     	GND                 
          	               	47        	108B4     	M_F_CPU1_SA_DQ<28>  
          	               	48        	108B1     	GND                 
          	               	49        	108B4     	M_F_CPU1_SA_DQ<29>  
          	               	50        	108B1     	GND                 
          	               	51        	108B4     	M_F_CPU1_SA_CB<0>   
          	               	52        	108B1     	GND                 
          	               	53        	108B4     	M_F_CPU1_SA_CB<1>   
          	               	54        	108B1     	GND                 
          	               	55        	108B2     	M_F_CPU1_SA_DQS_DP<4>
          	               	56        	108B2     	M_F_CPU1_SA_DQS_DN<4>
          	               	57        	108B1     	GND                 
          	               	58        	108B4     	M_F_CPU1_SA_CB<4>   
          	               	59        	108B1     	GND                 
          	               	60        	108B4     	M_F_CPU1_SA_CB<5>   
          	               	61        	108B1     	GND                 
          	               	62        	108B4     	M_F_CPU1_ALERT_N    
          	               	63        	108B1     	GND                 
          	               	64        	108B4     	M_F_CPU1_SA_CS_N<0> 
          	               	65        	108B1     	GND                 
          	               	66        	108B4     	M_F_CPU1_SA_CA<0>   
          	               	67        	108B1     	GND                 
          	               	68        	108B4     	M_F_CPU1_SA_CA<2>   
          	               	69        	108B1     	GND                 
          	               	70        	108B4     	M_F_CPU1_SA_CA<4>   
          	               	71        	108B1     	GND                 
          	               	72        	108B4     	M_F_CPU1_SA_CA<6>   
          	               	73        	108B1     	GND                 
          	               	74        	108B4     	M_F_CPU1_SA_PAR     
          	               	75        	108B1     	GND                 
          	               	76        	108B4     	M_F_CPU1_SB_CA<0>   
          	               	77        	108B1     	GND                 
          	               	78        	108B4     	M_F_CPU1_SB_CA<2>   
          	               	79        	108B1     	GND                 
          	               	80        	108B4     	M_F_CPU1_SB_CA<4>   
          	               	81        	108B1     	GND                 
          	               	82        	108B4     	M_F_CPU1_SB_CA<6>   
          	               	83        	108B1     	GND                 
          	               	84        	108B4     	M_F_CPU1_SB_CS_N<0> 
          	               	85        	108B1     	GND                 
          	               	86        	108A4     	M_F_CPU1_SA_RSP<0>  
          	               	87        	108A4     	M_F_CPU1_SB_RSP<0>  
          	               	88        	108B1     	GND                 
          	               	89        	108B4     	M_F_CPU1_SB_CB<4>   
          	               	90        	108B1     	GND                 
          	               	91        	108B4     	M_F_CPU1_SB_CB<5>   
          	               	92        	108B1     	GND                 
          	               	93        	108B2     	M_F_CPU1_SB_DQS_DP<9>
          	               	94        	108B2     	M_F_CPU1_SB_DQS_DN<9>
          	               	95        	108B1     	GND                 
          	               	96        	108B4     	M_F_CPU1_SB_CB<0>   
          	               	97        	108B1     	GND                 
          	               	98        	108B4     	M_F_CPU1_SB_CB<1>   
          	               	99        	108B1     	GND                 
          	               	100       	108B4     	M_F_CPU1_SB_DQ<0>   
          	               	101       	108B1     	GND                 
          	               	102       	108B4     	M_F_CPU1_SB_DQ<1>   
          	               	103       	108B1     	GND                 
          	               	104       	108B2     	M_F_CPU1_SB_DQS_DP<0>
          	               	105       	108B2     	M_F_CPU1_SB_DQS_DN<0>
          	               	106       	108B1     	GND                 
          	               	107       	108B4     	M_F_CPU1_SB_DQ<4>   
          	               	108       	108B1     	GND                 
          	               	109       	108B4     	M_F_CPU1_SB_DQ<5>   
          	               	110       	108B1     	GND                 
          	               	111       	108B4     	M_F_CPU1_SB_DQ<8>   
          	               	112       	108B1     	GND                 
          	               	113       	108B4     	M_F_CPU1_SB_DQ<9>   
          	               	114       	108B1     	GND                 
          	               	115       	108B2     	M_F_CPU1_SB_DQS_DP<1>
          	               	116       	108B2     	M_F_CPU1_SB_DQS_DN<1>
          	               	117       	108B1     	GND                 
          	               	118       	108B4     	M_F_CPU1_SB_DQ<12>  
          	               	119       	108B1     	GND                 
          	               	120       	108B4     	M_F_CPU1_SB_DQ<13>  
          	               	121       	108B1     	GND                 
          	               	122       	108B4     	M_F_CPU1_SB_DQ<16>  
          	               	123       	108B1     	GND                 
          	               	124       	108B4     	M_F_CPU1_SB_DQ<17>  
          	               	125       	108B1     	GND                 
          	               	126       	108B2     	M_F_CPU1_SB_DQS_DP<2>
          	               	127       	108B2     	M_F_CPU1_SB_DQS_DN<2>
          	               	128       	108B1     	GND                 
          	               	129       	108B4     	M_F_CPU1_SB_DQ<20>  
          	               	130       	108B1     	GND                 
          	               	131       	108B4     	M_F_CPU1_SB_DQ<21>  
          	               	132       	108B1     	GND                 
          	               	133       	108B4     	M_F_CPU1_SB_DQ<24>  
          	               	134       	108B1     	GND                 
          	               	135       	108B4     	M_F_CPU1_SB_DQ<25>  
          	               	136       	108B1     	GND                 
          	               	137       	108B2     	M_F_CPU1_SB_DQS_DP<3>
          	               	138       	108B2     	M_F_CPU1_SB_DQS_DN<3>
          	               	139       	108B1     	GND                 
          	               	140       	108B4     	M_F_CPU1_SB_DQ<28>  
          	               	141       	108B1     	GND                 
          	               	142       	108B4     	M_F_CPU1_SB_DQ<29>  
          	               	143       	108B1     	GND                 
          	               	144       	108B4     	TP_CHF_CPU1_DIMM1_FRU_1
          	               	145       	108B1     	P12V_S3_AUX_CPU1_NVDIMM
          	               	146       	108B1     	P12V_S3_AUX_CPU1_NVDIMM
          	               	147       	108B4     	PWRGD_CHF_CPU1_DIMM1
          	               	148       	108B4     	PD_CHF_CPU1_DIMM1_SAA
          	               	149       	108B4     	TP_CHF_CPU1_DIMM1_FRU_2
          	               	150       	108B4     	TP_CHF_CPU1_DIMM1_FRU_3
          	               	151       	108B1     	GND                 
          	               	152       	108B4     	M_F_CPU1_SA_DQ<2>   
          	               	153       	108B1     	GND                 
          	               	154       	108B4     	M_F_CPU1_SA_DQ<3>   
          	               	155       	108B1     	GND                 
          	               	156       	108B2     	M_F_CPU1_SA_DQS_DN<5>
          	               	157       	108B2     	M_F_CPU1_SA_DQS_DP<5>
          	               	158       	108B1     	GND                 
          	               	159       	108B4     	M_F_CPU1_SA_DQ<6>   
          	               	160       	108B1     	GND                 
          	               	161       	108B4     	M_F_CPU1_SA_DQ<7>   
          	               	162       	108B1     	GND                 
          	               	163       	108B4     	M_F_CPU1_SA_DQ<10>  
          	               	164       	108B1     	GND                 
          	               	165       	108B4     	M_F_CPU1_SA_DQ<11>  
          	               	166       	108B1     	GND                 
          	               	167       	108B2     	M_F_CPU1_SA_DQS_DN<6>
          	               	168       	108B2     	M_F_CPU1_SA_DQS_DP<6>
          	               	169       	108B1     	GND                 
          	               	170       	108B4     	M_F_CPU1_SA_DQ<14>  
          	               	171       	108B1     	GND                 
          	               	172       	108B4     	M_F_CPU1_SA_DQ<15>  
          	               	173       	108B1     	GND                 
          	               	174       	108B4     	M_F_CPU1_SA_DQ<18>  
          	               	175       	108B1     	GND                 
          	               	176       	108B4     	M_F_CPU1_SA_DQ<19>  
          	               	177       	108B1     	GND                 
          	               	178       	108B2     	M_F_CPU1_SA_DQS_DN<7>
          	               	179       	108B2     	M_F_CPU1_SA_DQS_DP<7>
          	               	180       	108B1     	GND                 
          	               	181       	108B4     	M_F_CPU1_SA_DQ<22>  
          	               	182       	108B1     	GND                 
          	               	183       	108B4     	M_F_CPU1_SA_DQ<23>  
          	               	184       	108B1     	GND                 
          	               	185       	108B4     	M_F_CPU1_SA_DQ<26>  
          	               	186       	108B1     	GND                 
          	               	187       	108B4     	M_F_CPU1_SA_DQ<27>  
          	               	188       	108B1     	GND                 
          	               	189       	108B2     	M_F_CPU1_SA_DQS_DN<8>
          	               	190       	108B2     	M_F_CPU1_SA_DQS_DP<8>
          	               	191       	108B1     	GND                 
          	               	192       	108B4     	M_F_CPU1_SA_DQ<30>  
          	               	193       	108B1     	GND                 
          	               	194       	108B4     	M_F_CPU1_SA_DQ<31>  
          	               	195       	108B1     	GND                 
          	               	196       	108B4     	M_F_CPU1_SA_CB<2>   
          	               	197       	108B1     	GND                 
          	               	198       	108B4     	M_F_CPU1_SA_CB<3>   
          	               	199       	108B1     	GND                 
          	               	200       	108B2     	M_F_CPU1_SA_DQS_DN<9>
          	               	201       	108B2     	M_F_CPU1_SA_DQS_DP<9>
          	               	202       	108B1     	GND                 
          	               	203       	108B4     	M_F_CPU1_SA_CB<6>   
          	               	204       	108B1     	GND                 
          	               	205       	108B4     	M_F_CPU1_SA_CB<7>   
          	               	206       	108B1     	GND                 
          	               	207       	108B4     	RST_M_EF_CPU1_FPGA_N
          	               	208       	108B1     	GND                 
          	               	209       	108B4     	M_F_CPU1_SA_CS_N<1> 
          	               	210       	108B1     	GND                 
          	               	211       	108B4     	M_F_CPU1_SA_CA<1>   
          	               	212       	108B1     	GND                 
          	               	213       	108B4     	M_F_CPU1_SA_CA<3>   
          	               	214       	108B1     	GND                 
          	               	215       	108B4     	M_F_CPU1_SA_CA<5>   
          	               	216       	108B1     	GND                 
          	               	217       	108B4     	M_F_CPU1_CLK_DP<0>  
          	               	218       	108B4     	M_F_CPU1_CLK_DN<0>  
          	               	219       	108B1     	GND                 
          	               	220       	108B4     	TP_CHF_CPU1_DIMM1_FRU_4
          	               	221       	108B4     	M_F_CPU1_SB_CA<1>   
          	               	222       	108B1     	GND                 
          	               	223       	108B4     	M_F_CPU1_SB_CA<3>   
          	               	224       	108B1     	GND                 
          	               	225       	108B4     	M_F_CPU1_SB_CA<5>   
          	               	226       	108B1     	GND                 
          	               	227       	108B4     	M_F_CPU1_SB_PAR     
          	               	228       	108B1     	GND                 
          	               	229       	108B4     	M_F_CPU1_SB_CS_N<1> 
          	               	230       	108B1     	GND                 
          	               	231       	108B4     	TP_CHF_CPU1_DIMM1_FRU_5
          	               	232       	108B4     	TP_CHF_CPU1_DIMM1_FRU_6
          	               	233       	108B1     	GND                 
          	               	234       	108B4     	M_F_CPU1_SB_CB<6>   
          	               	235       	108B1     	GND                 
          	               	236       	108B4     	M_F_CPU1_SB_CB<7>   
          	               	237       	108B1     	GND                 
          	               	238       	108B2     	M_F_CPU1_SB_DQS_DN<4>
          	               	239       	108B2     	M_F_CPU1_SB_DQS_DP<4>
          	               	240       	108B1     	GND                 
          	               	241       	108B4     	M_F_CPU1_SB_CB<2>   
          	               	242       	108B1     	GND                 
          	               	243       	108B4     	M_F_CPU1_SB_CB<3>   
          	               	244       	108B1     	GND                 
          	               	245       	108B4     	M_F_CPU1_SB_DQ<2>   
          	               	246       	108B1     	GND                 
          	               	247       	108B4     	M_F_CPU1_SB_DQ<3>   
          	               	248       	108B1     	GND                 
          	               	249       	108B2     	M_F_CPU1_SB_DQS_DN<5>
          	               	250       	108B2     	M_F_CPU1_SB_DQS_DP<5>
          	               	251       	108B1     	GND                 
          	               	252       	108B4     	M_F_CPU1_SB_DQ<6>   
          	               	253       	108B1     	GND                 
          	               	254       	108B4     	M_F_CPU1_SB_DQ<7>   
          	               	255       	108B1     	GND                 
          	               	256       	108B4     	M_F_CPU1_SB_DQ<10>  
          	               	257       	108B1     	GND                 
          	               	258       	108B4     	M_F_CPU1_SB_DQ<11>  
          	               	259       	108B1     	GND                 
          	               	260       	108B2     	M_F_CPU1_SB_DQS_DN<6>
          	               	261       	108B2     	M_F_CPU1_SB_DQS_DP<6>
          	               	262       	108B1     	GND                 
          	               	263       	108B4     	M_F_CPU1_SB_DQ<14>  
          	               	264       	108B1     	GND                 
          	               	265       	108B4     	M_F_CPU1_SB_DQ<15>  
          	               	266       	108B1     	GND                 
          	               	267       	108B4     	M_F_CPU1_SB_DQ<18>  
          	               	268       	108B1     	GND                 
          	               	269       	108B4     	M_F_CPU1_SB_DQ<19>  
          	               	270       	108B1     	GND                 
          	               	271       	108B2     	M_F_CPU1_SB_DQS_DN<7>
          	               	272       	108B2     	M_F_CPU1_SB_DQS_DP<7>
          	               	273       	108B1     	GND                 
          	               	274       	108B4     	M_F_CPU1_SB_DQ<22>  
          	               	275       	108B1     	GND                 
          	               	276       	108B4     	M_F_CPU1_SB_DQ<23>  
          	               	277       	108B1     	GND                 
          	               	278       	108B4     	M_F_CPU1_SB_DQ<26>  
          	               	279       	108B1     	GND                 
          	               	280       	108B4     	M_F_CPU1_SB_DQ<27>  
          	               	281       	108B1     	GND                 
          	               	282       	108B2     	M_F_CPU1_SB_DQS_DN<8>
          	               	283       	108B2     	M_F_CPU1_SB_DQS_DP<8>
          	               	284       	108B1     	GND                 
          	               	285       	108B4     	M_F_CPU1_SB_DQ<30>  
          	               	286       	108B1     	GND                 
          	               	287       	108B4     	M_F_CPU1_SB_DQ<31>  
          	               	288       	108B1     	GND                 
          	               	G1        	108B1     	GND                 
          	               	G2        	108A1     	GND                 
          	               	G3        	108A1     	GND                 

J28       	SCONN288_ADR50017P087CC	          	          	                    
          	               	1         	109B1     	P12V_S3_AUX_CPU1_NVDIMM
          	               	2         	109B4     	TP_CHF_CPU1_DIMM2_FRU_0
          	               	3         	109B4     	P3V3_AUX            
          	               	4         	109B4     	I3C_SPD_DDREFGH_CPU1_LVC1_SCL_3
          	               	5         	109B4     	I3C_SPD_DDREFGH_CPU1_LVC1_SDA
          	               	6         	109B1     	GND                 
          	               	7         	109B4     	M_F_CPU1_SA_DQ<0>   
          	               	8         	109B1     	GND                 
          	               	9         	109B4     	M_F_CPU1_SA_DQ<1>   
          	               	10        	109B1     	GND                 
          	               	11        	109B2     	M_F_CPU1_SA_DQS_DP<0>
          	               	12        	109B2     	M_F_CPU1_SA_DQS_DN<0>
          	               	13        	109B1     	GND                 
          	               	14        	109B4     	M_F_CPU1_SA_DQ<4>   
          	               	15        	109B1     	GND                 
          	               	16        	109B4     	M_F_CPU1_SA_DQ<5>   
          	               	17        	109B1     	GND                 
          	               	18        	109B4     	M_F_CPU1_SA_DQ<8>   
          	               	19        	109B1     	GND                 
          	               	20        	109B4     	M_F_CPU1_SA_DQ<9>   
          	               	21        	109B1     	GND                 
          	               	22        	109B2     	M_F_CPU1_SA_DQS_DP<1>
          	               	23        	109B2     	M_F_CPU1_SA_DQS_DN<1>
          	               	24        	109B1     	GND                 
          	               	25        	109B4     	M_F_CPU1_SA_DQ<12>  
          	               	26        	109B1     	GND                 
          	               	27        	109B4     	M_F_CPU1_SA_DQ<13>  
          	               	28        	109B1     	GND                 
          	               	29        	109B4     	M_F_CPU1_SA_DQ<16>  
          	               	30        	109B1     	GND                 
          	               	31        	109B4     	M_F_CPU1_SA_DQ<17>  
          	               	32        	109B1     	GND                 
          	               	33        	109B2     	M_F_CPU1_SA_DQS_DP<2>
          	               	34        	109B2     	M_F_CPU1_SA_DQS_DN<2>
          	               	35        	109B1     	GND                 
          	               	36        	109B4     	M_F_CPU1_SA_DQ<20>  
          	               	37        	109B1     	GND                 
          	               	38        	109B4     	M_F_CPU1_SA_DQ<21>  
          	               	39        	109B1     	GND                 
          	               	40        	109B4     	M_F_CPU1_SA_DQ<24>  
          	               	41        	109B1     	GND                 
          	               	42        	109B4     	M_F_CPU1_SA_DQ<25>  
          	               	43        	109B1     	GND                 
          	               	44        	109B2     	M_F_CPU1_SA_DQS_DP<3>
          	               	45        	109B2     	M_F_CPU1_SA_DQS_DN<3>
          	               	46        	109B1     	GND                 
          	               	47        	109B4     	M_F_CPU1_SA_DQ<28>  
          	               	48        	109B1     	GND                 
          	               	49        	109B4     	M_F_CPU1_SA_DQ<29>  
          	               	50        	109B1     	GND                 
          	               	51        	109B4     	M_F_CPU1_SA_CB<0>   
          	               	52        	109B1     	GND                 
          	               	53        	109B4     	M_F_CPU1_SA_CB<1>   
          	               	54        	109B1     	GND                 
          	               	55        	109B2     	M_F_CPU1_SA_DQS_DP<4>
          	               	56        	109B2     	M_F_CPU1_SA_DQS_DN<4>
          	               	57        	109B1     	GND                 
          	               	58        	109B4     	M_F_CPU1_SA_CB<4>   
          	               	59        	109B1     	GND                 
          	               	60        	109B4     	M_F_CPU1_SA_CB<5>   
          	               	61        	109B1     	GND                 
          	               	62        	109B4     	M_F_CPU1_ALERT_N    
          	               	63        	109B1     	GND                 
          	               	64        	109B4     	M_F_CPU1_SA_CS_N<2> 
          	               	65        	109B1     	GND                 
          	               	66        	109B4     	M_F_CPU1_SA_CA<0>   
          	               	67        	109B1     	GND                 
          	               	68        	109B4     	M_F_CPU1_SA_CA<2>   
          	               	69        	109B1     	GND                 
          	               	70        	109B4     	M_F_CPU1_SA_CA<4>   
          	               	71        	109B1     	GND                 
          	               	72        	109B4     	M_F_CPU1_SA_CA<6>   
          	               	73        	109B1     	GND                 
          	               	74        	109B4     	M_F_CPU1_SA_PAR     
          	               	75        	109B1     	GND                 
          	               	76        	109B4     	M_F_CPU1_SB_CA<0>   
          	               	77        	109B1     	GND                 
          	               	78        	109B4     	M_F_CPU1_SB_CA<2>   
          	               	79        	109B1     	GND                 
          	               	80        	109B4     	M_F_CPU1_SB_CA<4>   
          	               	81        	109B1     	GND                 
          	               	82        	109B4     	M_F_CPU1_SB_CA<6>   
          	               	83        	109B1     	GND                 
          	               	84        	109B4     	M_F_CPU1_SB_CS_N<2> 
          	               	85        	109B1     	GND                 
          	               	86        	109A4     	M_F_CPU1_SA_RSP<1>  
          	               	87        	109A4     	M_F_CPU1_SB_RSP<1>  
          	               	88        	109B1     	GND                 
          	               	89        	109B4     	M_F_CPU1_SB_CB<4>   
          	               	90        	109B1     	GND                 
          	               	91        	109B4     	M_F_CPU1_SB_CB<5>   
          	               	92        	109B1     	GND                 
          	               	93        	109B2     	M_F_CPU1_SB_DQS_DP<9>
          	               	94        	109B2     	M_F_CPU1_SB_DQS_DN<9>
          	               	95        	109B1     	GND                 
          	               	96        	109B4     	M_F_CPU1_SB_CB<0>   
          	               	97        	109B1     	GND                 
          	               	98        	109B4     	M_F_CPU1_SB_CB<1>   
          	               	99        	109B1     	GND                 
          	               	100       	109B4     	M_F_CPU1_SB_DQ<0>   
          	               	101       	109B1     	GND                 
          	               	102       	109B4     	M_F_CPU1_SB_DQ<1>   
          	               	103       	109B1     	GND                 
          	               	104       	109B2     	M_F_CPU1_SB_DQS_DP<0>
          	               	105       	109B2     	M_F_CPU1_SB_DQS_DN<0>
          	               	106       	109B1     	GND                 
          	               	107       	109B4     	M_F_CPU1_SB_DQ<4>   
          	               	108       	109B1     	GND                 
          	               	109       	109B4     	M_F_CPU1_SB_DQ<5>   
          	               	110       	109B1     	GND                 
          	               	111       	109B4     	M_F_CPU1_SB_DQ<8>   
          	               	112       	109B1     	GND                 
          	               	113       	109B4     	M_F_CPU1_SB_DQ<9>   
          	               	114       	109B1     	GND                 
          	               	115       	109B2     	M_F_CPU1_SB_DQS_DP<1>
          	               	116       	109B2     	M_F_CPU1_SB_DQS_DN<1>
          	               	117       	109B1     	GND                 
          	               	118       	109B4     	M_F_CPU1_SB_DQ<12>  
          	               	119       	109B1     	GND                 
          	               	120       	109B4     	M_F_CPU1_SB_DQ<13>  
          	               	121       	109B1     	GND                 
          	               	122       	109B4     	M_F_CPU1_SB_DQ<16>  
          	               	123       	109B1     	GND                 
          	               	124       	109B4     	M_F_CPU1_SB_DQ<17>  
          	               	125       	109B1     	GND                 
          	               	126       	109B2     	M_F_CPU1_SB_DQS_DP<2>
          	               	127       	109B2     	M_F_CPU1_SB_DQS_DN<2>
          	               	128       	109B1     	GND                 
          	               	129       	109B4     	M_F_CPU1_SB_DQ<20>  
          	               	130       	109B1     	GND                 
          	               	131       	109B4     	M_F_CPU1_SB_DQ<21>  
          	               	132       	109B1     	GND                 
          	               	133       	109B4     	M_F_CPU1_SB_DQ<24>  
          	               	134       	109B1     	GND                 
          	               	135       	109B4     	M_F_CPU1_SB_DQ<25>  
          	               	136       	109B1     	GND                 
          	               	137       	109B2     	M_F_CPU1_SB_DQS_DP<3>
          	               	138       	109B2     	M_F_CPU1_SB_DQS_DN<3>
          	               	139       	109B1     	GND                 
          	               	140       	109B4     	M_F_CPU1_SB_DQ<28>  
          	               	141       	109B1     	GND                 
          	               	142       	109B4     	M_F_CPU1_SB_DQ<29>  
          	               	143       	109B1     	GND                 
          	               	144       	109B4     	TP_CHF_CPU1_DIMM2_FRU_1
          	               	145       	109B1     	P12V_S3_AUX_CPU1_NVDIMM
          	               	146       	109B1     	P12V_S3_AUX_CPU1_NVDIMM
          	               	147       	109B4     	PWRGD_CHF_CPU1_DIMM2
          	               	148       	109B4     	PD_CHF_CPU1_DIMM2_SAA
          	               	149       	109B4     	TP_CHF_CPU1_DIMM2_FRU_2
          	               	150       	109B4     	TP_CHF_CPU1_DIMM2_FRU_3
          	               	151       	109B1     	GND                 
          	               	152       	109B4     	M_F_CPU1_SA_DQ<2>   
          	               	153       	109B1     	GND                 
          	               	154       	109B4     	M_F_CPU1_SA_DQ<3>   
          	               	155       	109B1     	GND                 
          	               	156       	109B2     	M_F_CPU1_SA_DQS_DN<5>
          	               	157       	109B2     	M_F_CPU1_SA_DQS_DP<5>
          	               	158       	109B1     	GND                 
          	               	159       	109B4     	M_F_CPU1_SA_DQ<6>   
          	               	160       	109B1     	GND                 
          	               	161       	109B4     	M_F_CPU1_SA_DQ<7>   
          	               	162       	109B1     	GND                 
          	               	163       	109B4     	M_F_CPU1_SA_DQ<10>  
          	               	164       	109B1     	GND                 
          	               	165       	109B4     	M_F_CPU1_SA_DQ<11>  
          	               	166       	109B1     	GND                 
          	               	167       	109B2     	M_F_CPU1_SA_DQS_DN<6>
          	               	168       	109B2     	M_F_CPU1_SA_DQS_DP<6>
          	               	169       	109B1     	GND                 
          	               	170       	109B4     	M_F_CPU1_SA_DQ<14>  
          	               	171       	109B1     	GND                 
          	               	172       	109B4     	M_F_CPU1_SA_DQ<15>  
          	               	173       	109B1     	GND                 
          	               	174       	109B4     	M_F_CPU1_SA_DQ<18>  
          	               	175       	109B1     	GND                 
          	               	176       	109B4     	M_F_CPU1_SA_DQ<19>  
          	               	177       	109B1     	GND                 
          	               	178       	109B2     	M_F_CPU1_SA_DQS_DN<7>
          	               	179       	109B2     	M_F_CPU1_SA_DQS_DP<7>
          	               	180       	109B1     	GND                 
          	               	181       	109B4     	M_F_CPU1_SA_DQ<22>  
          	               	182       	109B1     	GND                 
          	               	183       	109B4     	M_F_CPU1_SA_DQ<23>  
          	               	184       	109B1     	GND                 
          	               	185       	109B4     	M_F_CPU1_SA_DQ<26>  
          	               	186       	109B1     	GND                 
          	               	187       	109B4     	M_F_CPU1_SA_DQ<27>  
          	               	188       	109B1     	GND                 
          	               	189       	109B2     	M_F_CPU1_SA_DQS_DN<8>
          	               	190       	109B2     	M_F_CPU1_SA_DQS_DP<8>
          	               	191       	109B1     	GND                 
          	               	192       	109B4     	M_F_CPU1_SA_DQ<30>  
          	               	193       	109B1     	GND                 
          	               	194       	109B4     	M_F_CPU1_SA_DQ<31>  
          	               	195       	109B1     	GND                 
          	               	196       	109B4     	M_F_CPU1_SA_CB<2>   
          	               	197       	109B1     	GND                 
          	               	198       	109B4     	M_F_CPU1_SA_CB<3>   
          	               	199       	109B1     	GND                 
          	               	200       	109B2     	M_F_CPU1_SA_DQS_DN<9>
          	               	201       	109B2     	M_F_CPU1_SA_DQS_DP<9>
          	               	202       	109B1     	GND                 
          	               	203       	109B4     	M_F_CPU1_SA_CB<6>   
          	               	204       	109B1     	GND                 
          	               	205       	109B4     	M_F_CPU1_SA_CB<7>   
          	               	206       	109B1     	GND                 
          	               	207       	109B4     	RST_M_EF_CPU1_FPGA_N
          	               	208       	109B1     	GND                 
          	               	209       	109B4     	M_F_CPU1_SA_CS_N<3> 
          	               	210       	109B1     	GND                 
          	               	211       	109B4     	M_F_CPU1_SA_CA<1>   
          	               	212       	109B1     	GND                 
          	               	213       	109B4     	M_F_CPU1_SA_CA<3>   
          	               	214       	109B1     	GND                 
          	               	215       	109B4     	M_F_CPU1_SA_CA<5>   
          	               	216       	109B1     	GND                 
          	               	217       	109B4     	M_F_CPU1_CLK_DP<1>  
          	               	218       	109B4     	M_F_CPU1_CLK_DN<1>  
          	               	219       	109B1     	GND                 
          	               	220       	109B4     	TP_CHF_CPU1_DIMM2_FRU_4
          	               	221       	109B4     	M_F_CPU1_SB_CA<1>   
          	               	222       	109B1     	GND                 
          	               	223       	109B4     	M_F_CPU1_SB_CA<3>   
          	               	224       	109B1     	GND                 
          	               	225       	109B4     	M_F_CPU1_SB_CA<5>   
          	               	226       	109B1     	GND                 
          	               	227       	109B4     	M_F_CPU1_SB_PAR     
          	               	228       	109B1     	GND                 
          	               	229       	109B4     	M_F_CPU1_SB_CS_N<3> 
          	               	230       	109B1     	GND                 
          	               	231       	109B4     	TP_CHF_CPU1_DIMM2_FRU_5
          	               	232       	109B4     	TP_CHF_CPU1_DIMM2_FRU_6
          	               	233       	109B1     	GND                 
          	               	234       	109B4     	M_F_CPU1_SB_CB<6>   
          	               	235       	109B1     	GND                 
          	               	236       	109B4     	M_F_CPU1_SB_CB<7>   
          	               	237       	109B1     	GND                 
          	               	238       	109B2     	M_F_CPU1_SB_DQS_DN<4>
          	               	239       	109B2     	M_F_CPU1_SB_DQS_DP<4>
          	               	240       	109B1     	GND                 
          	               	241       	109B4     	M_F_CPU1_SB_CB<2>   
          	               	242       	109B1     	GND                 
          	               	243       	109B4     	M_F_CPU1_SB_CB<3>   
          	               	244       	109B1     	GND                 
          	               	245       	109B4     	M_F_CPU1_SB_DQ<2>   
          	               	246       	109B1     	GND                 
          	               	247       	109B4     	M_F_CPU1_SB_DQ<3>   
          	               	248       	109B1     	GND                 
          	               	249       	109B2     	M_F_CPU1_SB_DQS_DN<5>
          	               	250       	109B2     	M_F_CPU1_SB_DQS_DP<5>
          	               	251       	109B1     	GND                 
          	               	252       	109B4     	M_F_CPU1_SB_DQ<6>   
          	               	253       	109B1     	GND                 
          	               	254       	109B4     	M_F_CPU1_SB_DQ<7>   
          	               	255       	109B1     	GND                 
          	               	256       	109B4     	M_F_CPU1_SB_DQ<10>  
          	               	257       	109B1     	GND                 
          	               	258       	109B4     	M_F_CPU1_SB_DQ<11>  
          	               	259       	109B1     	GND                 
          	               	260       	109B2     	M_F_CPU1_SB_DQS_DN<6>
          	               	261       	109B2     	M_F_CPU1_SB_DQS_DP<6>
          	               	262       	109B1     	GND                 
          	               	263       	109B4     	M_F_CPU1_SB_DQ<14>  
          	               	264       	109B1     	GND                 
          	               	265       	109B4     	M_F_CPU1_SB_DQ<15>  
          	               	266       	109B1     	GND                 
          	               	267       	109B4     	M_F_CPU1_SB_DQ<18>  
          	               	268       	109B1     	GND                 
          	               	269       	109B4     	M_F_CPU1_SB_DQ<19>  
          	               	270       	109B1     	GND                 
          	               	271       	109B2     	M_F_CPU1_SB_DQS_DN<7>
          	               	272       	109B2     	M_F_CPU1_SB_DQS_DP<7>
          	               	273       	109B1     	GND                 
          	               	274       	109B4     	M_F_CPU1_SB_DQ<22>  
          	               	275       	109B1     	GND                 
          	               	276       	109B4     	M_F_CPU1_SB_DQ<23>  
          	               	277       	109B1     	GND                 
          	               	278       	109B4     	M_F_CPU1_SB_DQ<26>  
          	               	279       	109B1     	GND                 
          	               	280       	109B4     	M_F_CPU1_SB_DQ<27>  
          	               	281       	109B1     	GND                 
          	               	282       	109B2     	M_F_CPU1_SB_DQS_DN<8>
          	               	283       	109B2     	M_F_CPU1_SB_DQS_DP<8>
          	               	284       	109B1     	GND                 
          	               	285       	109B4     	M_F_CPU1_SB_DQ<30>  
          	               	286       	109B1     	GND                 
          	               	287       	109B4     	M_F_CPU1_SB_DQ<31>  
          	               	288       	109B1     	GND                 
          	               	G1        	109B1     	GND                 
          	               	G2        	109A1     	GND                 
          	               	G3        	109A1     	GND                 

J29       	SCONN288_ADR50017P130CC	          	          	                    
          	               	1         	110B1     	P12V_S3_AUX_CPU1_NVDIMM
          	               	2         	110B4     	TP_CHG_CPU1_DIMM1_FRU_0
          	               	3         	110B4     	P3V3_AUX            
          	               	4         	110B4     	I3C_SPD_DDREFGH_CPU1_LVC1_SCL_4
          	               	5         	110B4     	I3C_SPD_DDREFGH_CPU1_LVC1_SDA
          	               	6         	110B1     	GND                 
          	               	7         	110B4     	M_G_CPU1_SA_DQ<0>   
          	               	8         	110B1     	GND                 
          	               	9         	110B4     	M_G_CPU1_SA_DQ<1>   
          	               	10        	110B1     	GND                 
          	               	11        	110B2     	M_G_CPU1_SA_DQS_DP<0>
          	               	12        	110B2     	M_G_CPU1_SA_DQS_DN<0>
          	               	13        	110B1     	GND                 
          	               	14        	110B4     	M_G_CPU1_SA_DQ<4>   
          	               	15        	110B1     	GND                 
          	               	16        	110B4     	M_G_CPU1_SA_DQ<5>   
          	               	17        	110B1     	GND                 
          	               	18        	110B4     	M_G_CPU1_SA_DQ<8>   
          	               	19        	110B1     	GND                 
          	               	20        	110B4     	M_G_CPU1_SA_DQ<9>   
          	               	21        	110B1     	GND                 
          	               	22        	110B2     	M_G_CPU1_SA_DQS_DP<1>
          	               	23        	110B2     	M_G_CPU1_SA_DQS_DN<1>
          	               	24        	110B1     	GND                 
          	               	25        	110B4     	M_G_CPU1_SA_DQ<12>  
          	               	26        	110B1     	GND                 
          	               	27        	110B4     	M_G_CPU1_SA_DQ<13>  
          	               	28        	110B1     	GND                 
          	               	29        	110B4     	M_G_CPU1_SA_DQ<16>  
          	               	30        	110B1     	GND                 
          	               	31        	110B4     	M_G_CPU1_SA_DQ<17>  
          	               	32        	110B1     	GND                 
          	               	33        	110B2     	M_G_CPU1_SA_DQS_DP<2>
          	               	34        	110B2     	M_G_CPU1_SA_DQS_DN<2>
          	               	35        	110B1     	GND                 
          	               	36        	110B4     	M_G_CPU1_SA_DQ<20>  
          	               	37        	110B1     	GND                 
          	               	38        	110B4     	M_G_CPU1_SA_DQ<21>  
          	               	39        	110B1     	GND                 
          	               	40        	110B4     	M_G_CPU1_SA_DQ<24>  
          	               	41        	110B1     	GND                 
          	               	42        	110B4     	M_G_CPU1_SA_DQ<25>  
          	               	43        	110B1     	GND                 
          	               	44        	110B2     	M_G_CPU1_SA_DQS_DP<3>
          	               	45        	110B2     	M_G_CPU1_SA_DQS_DN<3>
          	               	46        	110B1     	GND                 
          	               	47        	110B4     	M_G_CPU1_SA_DQ<28>  
          	               	48        	110B1     	GND                 
          	               	49        	110B4     	M_G_CPU1_SA_DQ<29>  
          	               	50        	110B1     	GND                 
          	               	51        	110B4     	M_G_CPU1_SA_CB<0>   
          	               	52        	110B1     	GND                 
          	               	53        	110B4     	M_G_CPU1_SA_CB<1>   
          	               	54        	110B1     	GND                 
          	               	55        	110B2     	M_G_CPU1_SA_DQS_DP<4>
          	               	56        	110B2     	M_G_CPU1_SA_DQS_DN<4>
          	               	57        	110B1     	GND                 
          	               	58        	110B4     	M_G_CPU1_SA_CB<4>   
          	               	59        	110B1     	GND                 
          	               	60        	110B4     	M_G_CPU1_SA_CB<5>   
          	               	61        	110B1     	GND                 
          	               	62        	110B4     	M_G_CPU1_ALERT_N    
          	               	63        	110B1     	GND                 
          	               	64        	110B4     	M_G_CPU1_SA_CS_N<0> 
          	               	65        	110B1     	GND                 
          	               	66        	110B4     	M_G_CPU1_SA_CA<0>   
          	               	67        	110B1     	GND                 
          	               	68        	110B4     	M_G_CPU1_SA_CA<2>   
          	               	69        	110B1     	GND                 
          	               	70        	110B4     	M_G_CPU1_SA_CA<4>   
          	               	71        	110B1     	GND                 
          	               	72        	110B4     	M_G_CPU1_SA_CA<6>   
          	               	73        	110B1     	GND                 
          	               	74        	110B4     	M_G_CPU1_SA_PAR     
          	               	75        	110B1     	GND                 
          	               	76        	110B4     	M_G_CPU1_SB_CA<0>   
          	               	77        	110B1     	GND                 
          	               	78        	110B4     	M_G_CPU1_SB_CA<2>   
          	               	79        	110B1     	GND                 
          	               	80        	110B4     	M_G_CPU1_SB_CA<4>   
          	               	81        	110B1     	GND                 
          	               	82        	110B4     	M_G_CPU1_SB_CA<6>   
          	               	83        	110B1     	GND                 
          	               	84        	110B4     	M_G_CPU1_SB_CS_N<0> 
          	               	85        	110B1     	GND                 
          	               	86        	110A4     	M_G_CPU1_SA_RSP<0>  
          	               	87        	110A4     	M_G_CPU1_SB_RSP<0>  
          	               	88        	110B1     	GND                 
          	               	89        	110B4     	M_G_CPU1_SB_CB<4>   
          	               	90        	110B1     	GND                 
          	               	91        	110B4     	M_G_CPU1_SB_CB<5>   
          	               	92        	110B1     	GND                 
          	               	93        	110B2     	M_G_CPU1_SB_DQS_DP<9>
          	               	94        	110B2     	M_G_CPU1_SB_DQS_DN<9>
          	               	95        	110B1     	GND                 
          	               	96        	110B4     	M_G_CPU1_SB_CB<0>   
          	               	97        	110B1     	GND                 
          	               	98        	110B4     	M_G_CPU1_SB_CB<1>   
          	               	99        	110B1     	GND                 
          	               	100       	110B4     	M_G_CPU1_SB_DQ<0>   
          	               	101       	110B1     	GND                 
          	               	102       	110B4     	M_G_CPU1_SB_DQ<1>   
          	               	103       	110B1     	GND                 
          	               	104       	110B2     	M_G_CPU1_SB_DQS_DP<0>
          	               	105       	110B2     	M_G_CPU1_SB_DQS_DN<0>
          	               	106       	110B1     	GND                 
          	               	107       	110B4     	M_G_CPU1_SB_DQ<4>   
          	               	108       	110B1     	GND                 
          	               	109       	110B4     	M_G_CPU1_SB_DQ<5>   
          	               	110       	110B1     	GND                 
          	               	111       	110B4     	M_G_CPU1_SB_DQ<8>   
          	               	112       	110B1     	GND                 
          	               	113       	110B4     	M_G_CPU1_SB_DQ<9>   
          	               	114       	110B1     	GND                 
          	               	115       	110B2     	M_G_CPU1_SB_DQS_DP<1>
          	               	116       	110B2     	M_G_CPU1_SB_DQS_DN<1>
          	               	117       	110B1     	GND                 
          	               	118       	110B4     	M_G_CPU1_SB_DQ<12>  
          	               	119       	110B1     	GND                 
          	               	120       	110B4     	M_G_CPU1_SB_DQ<13>  
          	               	121       	110B1     	GND                 
          	               	122       	110B4     	M_G_CPU1_SB_DQ<16>  
          	               	123       	110B1     	GND                 
          	               	124       	110B4     	M_G_CPU1_SB_DQ<17>  
          	               	125       	110B1     	GND                 
          	               	126       	110B2     	M_G_CPU1_SB_DQS_DP<2>
          	               	127       	110B2     	M_G_CPU1_SB_DQS_DN<2>
          	               	128       	110B1     	GND                 
          	               	129       	110B4     	M_G_CPU1_SB_DQ<20>  
          	               	130       	110B1     	GND                 
          	               	131       	110B4     	M_G_CPU1_SB_DQ<21>  
          	               	132       	110B1     	GND                 
          	               	133       	110B4     	M_G_CPU1_SB_DQ<24>  
          	               	134       	110B1     	GND                 
          	               	135       	110B4     	M_G_CPU1_SB_DQ<25>  
          	               	136       	110B1     	GND                 
          	               	137       	110B2     	M_G_CPU1_SB_DQS_DP<3>
          	               	138       	110B2     	M_G_CPU1_SB_DQS_DN<3>
          	               	139       	110B1     	GND                 
          	               	140       	110B4     	M_G_CPU1_SB_DQ<28>  
          	               	141       	110B1     	GND                 
          	               	142       	110B4     	M_G_CPU1_SB_DQ<29>  
          	               	143       	110B1     	GND                 
          	               	144       	110B4     	TP_CHG_CPU1_DIMM1_FRU_1
          	               	145       	110B1     	P12V_S3_AUX_CPU1_NVDIMM
          	               	146       	110B1     	P12V_S3_AUX_CPU1_NVDIMM
          	               	147       	110B4     	PWRGD_CHG_CPU1_DIMM1
          	               	148       	110B4     	PD_CHG_CPU1_DIMM1_SAA
          	               	149       	110B4     	TP_CHG_CPU1_DIMM1_FRU_2
          	               	150       	110B4     	TP_CHG_CPU1_DIMM1_FRU_3
          	               	151       	110B1     	GND                 
          	               	152       	110B4     	M_G_CPU1_SA_DQ<2>   
          	               	153       	110B1     	GND                 
          	               	154       	110B4     	M_G_CPU1_SA_DQ<3>   
          	               	155       	110B1     	GND                 
          	               	156       	110B2     	M_G_CPU1_SA_DQS_DN<5>
          	               	157       	110B2     	M_G_CPU1_SA_DQS_DP<5>
          	               	158       	110B1     	GND                 
          	               	159       	110B4     	M_G_CPU1_SA_DQ<6>   
          	               	160       	110B1     	GND                 
          	               	161       	110B4     	M_G_CPU1_SA_DQ<7>   
          	               	162       	110B1     	GND                 
          	               	163       	110B4     	M_G_CPU1_SA_DQ<10>  
          	               	164       	110B1     	GND                 
          	               	165       	110B4     	M_G_CPU1_SA_DQ<11>  
          	               	166       	110B1     	GND                 
          	               	167       	110B2     	M_G_CPU1_SA_DQS_DN<6>
          	               	168       	110B2     	M_G_CPU1_SA_DQS_DP<6>
          	               	169       	110B1     	GND                 
          	               	170       	110B4     	M_G_CPU1_SA_DQ<14>  
          	               	171       	110B1     	GND                 
          	               	172       	110B4     	M_G_CPU1_SA_DQ<15>  
          	               	173       	110B1     	GND                 
          	               	174       	110B4     	M_G_CPU1_SA_DQ<18>  
          	               	175       	110B1     	GND                 
          	               	176       	110B4     	M_G_CPU1_SA_DQ<19>  
          	               	177       	110B1     	GND                 
          	               	178       	110B2     	M_G_CPU1_SA_DQS_DN<7>
          	               	179       	110B2     	M_G_CPU1_SA_DQS_DP<7>
          	               	180       	110B1     	GND                 
          	               	181       	110B4     	M_G_CPU1_SA_DQ<22>  
          	               	182       	110B1     	GND                 
          	               	183       	110B4     	M_G_CPU1_SA_DQ<23>  
          	               	184       	110B1     	GND                 
          	               	185       	110B4     	M_G_CPU1_SA_DQ<26>  
          	               	186       	110B1     	GND                 
          	               	187       	110B4     	M_G_CPU1_SA_DQ<27>  
          	               	188       	110B1     	GND                 
          	               	189       	110B2     	M_G_CPU1_SA_DQS_DN<8>
          	               	190       	110B2     	M_G_CPU1_SA_DQS_DP<8>
          	               	191       	110B1     	GND                 
          	               	192       	110B4     	M_G_CPU1_SA_DQ<30>  
          	               	193       	110B1     	GND                 
          	               	194       	110B4     	M_G_CPU1_SA_DQ<31>  
          	               	195       	110B1     	GND                 
          	               	196       	110B4     	M_G_CPU1_SA_CB<2>   
          	               	197       	110B1     	GND                 
          	               	198       	110B4     	M_G_CPU1_SA_CB<3>   
          	               	199       	110B1     	GND                 
          	               	200       	110B2     	M_G_CPU1_SA_DQS_DN<9>
          	               	201       	110B2     	M_G_CPU1_SA_DQS_DP<9>
          	               	202       	110B1     	GND                 
          	               	203       	110B4     	M_G_CPU1_SA_CB<6>   
          	               	204       	110B1     	GND                 
          	               	205       	110B4     	M_G_CPU1_SA_CB<7>   
          	               	206       	110B1     	GND                 
          	               	207       	110B4     	RST_M_GH_CPU1_FPGA_N
          	               	208       	110B1     	GND                 
          	               	209       	110B4     	M_G_CPU1_SA_CS_N<1> 
          	               	210       	110B1     	GND                 
          	               	211       	110B4     	M_G_CPU1_SA_CA<1>   
          	               	212       	110B1     	GND                 
          	               	213       	110B4     	M_G_CPU1_SA_CA<3>   
          	               	214       	110B1     	GND                 
          	               	215       	110B4     	M_G_CPU1_SA_CA<5>   
          	               	216       	110B1     	GND                 
          	               	217       	110B4     	M_G_CPU1_CLK_DP<0>  
          	               	218       	110B4     	M_G_CPU1_CLK_DN<0>  
          	               	219       	110B1     	GND                 
          	               	220       	110B4     	TP_CHG_CPU1_DIMM1_FRU_4
          	               	221       	110B4     	M_G_CPU1_SB_CA<1>   
          	               	222       	110B1     	GND                 
          	               	223       	110B4     	M_G_CPU1_SB_CA<3>   
          	               	224       	110B1     	GND                 
          	               	225       	110B4     	M_G_CPU1_SB_CA<5>   
          	               	226       	110B1     	GND                 
          	               	227       	110B4     	M_G_CPU1_SB_PAR     
          	               	228       	110B1     	GND                 
          	               	229       	110B4     	M_G_CPU1_SB_CS_N<1> 
          	               	230       	110B1     	GND                 
          	               	231       	110B4     	TP_CHG_CPU1_DIMM1_FRU_5
          	               	232       	110B4     	TP_CHG_CPU1_DIMM1_FRU_6
          	               	233       	110B1     	GND                 
          	               	234       	110B4     	M_G_CPU1_SB_CB<6>   
          	               	235       	110B1     	GND                 
          	               	236       	110B4     	M_G_CPU1_SB_CB<7>   
          	               	237       	110B1     	GND                 
          	               	238       	110B2     	M_G_CPU1_SB_DQS_DN<4>
          	               	239       	110B2     	M_G_CPU1_SB_DQS_DP<4>
          	               	240       	110B1     	GND                 
          	               	241       	110B4     	M_G_CPU1_SB_CB<2>   
          	               	242       	110B1     	GND                 
          	               	243       	110B4     	M_G_CPU1_SB_CB<3>   
          	               	244       	110B1     	GND                 
          	               	245       	110B4     	M_G_CPU1_SB_DQ<2>   
          	               	246       	110B1     	GND                 
          	               	247       	110B4     	M_G_CPU1_SB_DQ<3>   
          	               	248       	110B1     	GND                 
          	               	249       	110B2     	M_G_CPU1_SB_DQS_DN<5>
          	               	250       	110B2     	M_G_CPU1_SB_DQS_DP<5>
          	               	251       	110B1     	GND                 
          	               	252       	110B4     	M_G_CPU1_SB_DQ<6>   
          	               	253       	110B1     	GND                 
          	               	254       	110B4     	M_G_CPU1_SB_DQ<7>   
          	               	255       	110B1     	GND                 
          	               	256       	110B4     	M_G_CPU1_SB_DQ<10>  
          	               	257       	110B1     	GND                 
          	               	258       	110B4     	M_G_CPU1_SB_DQ<11>  
          	               	259       	110B1     	GND                 
          	               	260       	110B2     	M_G_CPU1_SB_DQS_DN<6>
          	               	261       	110B2     	M_G_CPU1_SB_DQS_DP<6>
          	               	262       	110B1     	GND                 
          	               	263       	110B4     	M_G_CPU1_SB_DQ<14>  
          	               	264       	110B1     	GND                 
          	               	265       	110B4     	M_G_CPU1_SB_DQ<15>  
          	               	266       	110B1     	GND                 
          	               	267       	110B4     	M_G_CPU1_SB_DQ<18>  
          	               	268       	110B1     	GND                 
          	               	269       	110B4     	M_G_CPU1_SB_DQ<19>  
          	               	270       	110B1     	GND                 
          	               	271       	110B2     	M_G_CPU1_SB_DQS_DN<7>
          	               	272       	110B2     	M_G_CPU1_SB_DQS_DP<7>
          	               	273       	110B1     	GND                 
          	               	274       	110B4     	M_G_CPU1_SB_DQ<22>  
          	               	275       	110B1     	GND                 
          	               	276       	110B4     	M_G_CPU1_SB_DQ<23>  
          	               	277       	110B1     	GND                 
          	               	278       	110B4     	M_G_CPU1_SB_DQ<26>  
          	               	279       	110B1     	GND                 
          	               	280       	110B4     	M_G_CPU1_SB_DQ<27>  
          	               	281       	110B1     	GND                 
          	               	282       	110B2     	M_G_CPU1_SB_DQS_DN<8>
          	               	283       	110B2     	M_G_CPU1_SB_DQS_DP<8>
          	               	284       	110B1     	GND                 
          	               	285       	110B4     	M_G_CPU1_SB_DQ<30>  
          	               	286       	110B1     	GND                 
          	               	287       	110B4     	M_G_CPU1_SB_DQ<31>  
          	               	288       	110B1     	GND                 
          	               	G1        	110B1     	GND                 
          	               	G2        	110A1     	GND                 
          	               	G3        	110A1     	GND                 

J30       	SCONN288_ADR50017P087CC	          	          	                    
          	               	1         	111B1     	P12V_S3_AUX_CPU1_NVDIMM
          	               	2         	111B4     	TP_CHG_CPU1_DIMM2_FRU_0
          	               	3         	111B4     	P3V3_AUX            
          	               	4         	111B4     	I3C_SPD_DDREFGH_CPU1_LVC1_SCL_5
          	               	5         	111B4     	I3C_SPD_DDREFGH_CPU1_LVC1_SDA
          	               	6         	111B1     	GND                 
          	               	7         	111B4     	M_G_CPU1_SA_DQ<0>   
          	               	8         	111B1     	GND                 
          	               	9         	111B4     	M_G_CPU1_SA_DQ<1>   
          	               	10        	111B1     	GND                 
          	               	11        	111B2     	M_G_CPU1_SA_DQS_DP<0>
          	               	12        	111B2     	M_G_CPU1_SA_DQS_DN<0>
          	               	13        	111B1     	GND                 
          	               	14        	111B4     	M_G_CPU1_SA_DQ<4>   
          	               	15        	111B1     	GND                 
          	               	16        	111B4     	M_G_CPU1_SA_DQ<5>   
          	               	17        	111B1     	GND                 
          	               	18        	111B4     	M_G_CPU1_SA_DQ<8>   
          	               	19        	111B1     	GND                 
          	               	20        	111B4     	M_G_CPU1_SA_DQ<9>   
          	               	21        	111B1     	GND                 
          	               	22        	111B2     	M_G_CPU1_SA_DQS_DP<1>
          	               	23        	111B2     	M_G_CPU1_SA_DQS_DN<1>
          	               	24        	111B1     	GND                 
          	               	25        	111B4     	M_G_CPU1_SA_DQ<12>  
          	               	26        	111B1     	GND                 
          	               	27        	111B4     	M_G_CPU1_SA_DQ<13>  
          	               	28        	111B1     	GND                 
          	               	29        	111B4     	M_G_CPU1_SA_DQ<16>  
          	               	30        	111B1     	GND                 
          	               	31        	111B4     	M_G_CPU1_SA_DQ<17>  
          	               	32        	111B1     	GND                 
          	               	33        	111B2     	M_G_CPU1_SA_DQS_DP<2>
          	               	34        	111B2     	M_G_CPU1_SA_DQS_DN<2>
          	               	35        	111B1     	GND                 
          	               	36        	111B4     	M_G_CPU1_SA_DQ<20>  
          	               	37        	111B1     	GND                 
          	               	38        	111B4     	M_G_CPU1_SA_DQ<21>  
          	               	39        	111B1     	GND                 
          	               	40        	111B4     	M_G_CPU1_SA_DQ<24>  
          	               	41        	111B1     	GND                 
          	               	42        	111B4     	M_G_CPU1_SA_DQ<25>  
          	               	43        	111B1     	GND                 
          	               	44        	111B2     	M_G_CPU1_SA_DQS_DP<3>
          	               	45        	111B2     	M_G_CPU1_SA_DQS_DN<3>
          	               	46        	111B1     	GND                 
          	               	47        	111B4     	M_G_CPU1_SA_DQ<28>  
          	               	48        	111B1     	GND                 
          	               	49        	111B4     	M_G_CPU1_SA_DQ<29>  
          	               	50        	111B1     	GND                 
          	               	51        	111B4     	M_G_CPU1_SA_CB<0>   
          	               	52        	111B1     	GND                 
          	               	53        	111B4     	M_G_CPU1_SA_CB<1>   
          	               	54        	111B1     	GND                 
          	               	55        	111B2     	M_G_CPU1_SA_DQS_DP<4>
          	               	56        	111B2     	M_G_CPU1_SA_DQS_DN<4>
          	               	57        	111B1     	GND                 
          	               	58        	111B4     	M_G_CPU1_SA_CB<4>   
          	               	59        	111B1     	GND                 
          	               	60        	111B4     	M_G_CPU1_SA_CB<5>   
          	               	61        	111B1     	GND                 
          	               	62        	111B4     	M_G_CPU1_ALERT_N    
          	               	63        	111B1     	GND                 
          	               	64        	111B4     	M_G_CPU1_SA_CS_N<2> 
          	               	65        	111B1     	GND                 
          	               	66        	111B4     	M_G_CPU1_SA_CA<0>   
          	               	67        	111B1     	GND                 
          	               	68        	111B4     	M_G_CPU1_SA_CA<2>   
          	               	69        	111B1     	GND                 
          	               	70        	111B4     	M_G_CPU1_SA_CA<4>   
          	               	71        	111B1     	GND                 
          	               	72        	111B4     	M_G_CPU1_SA_CA<6>   
          	               	73        	111B1     	GND                 
          	               	74        	111B4     	M_G_CPU1_SA_PAR     
          	               	75        	111B1     	GND                 
          	               	76        	111B4     	M_G_CPU1_SB_CA<0>   
          	               	77        	111B1     	GND                 
          	               	78        	111B4     	M_G_CPU1_SB_CA<2>   
          	               	79        	111B1     	GND                 
          	               	80        	111B4     	M_G_CPU1_SB_CA<4>   
          	               	81        	111B1     	GND                 
          	               	82        	111B4     	M_G_CPU1_SB_CA<6>   
          	               	83        	111B1     	GND                 
          	               	84        	111B4     	M_G_CPU1_SB_CS_N<2> 
          	               	85        	111B1     	GND                 
          	               	86        	111A4     	M_G_CPU1_SA_RSP<1>  
          	               	87        	111A4     	M_G_CPU1_SB_RSP<1>  
          	               	88        	111B1     	GND                 
          	               	89        	111B4     	M_G_CPU1_SB_CB<4>   
          	               	90        	111B1     	GND                 
          	               	91        	111B4     	M_G_CPU1_SB_CB<5>   
          	               	92        	111B1     	GND                 
          	               	93        	111B2     	M_G_CPU1_SB_DQS_DP<9>
          	               	94        	111B2     	M_G_CPU1_SB_DQS_DN<9>
          	               	95        	111B1     	GND                 
          	               	96        	111B4     	M_G_CPU1_SB_CB<0>   
          	               	97        	111B1     	GND                 
          	               	98        	111B4     	M_G_CPU1_SB_CB<1>   
          	               	99        	111B1     	GND                 
          	               	100       	111B4     	M_G_CPU1_SB_DQ<0>   
          	               	101       	111B1     	GND                 
          	               	102       	111B4     	M_G_CPU1_SB_DQ<1>   
          	               	103       	111B1     	GND                 
          	               	104       	111B2     	M_G_CPU1_SB_DQS_DP<0>
          	               	105       	111B2     	M_G_CPU1_SB_DQS_DN<0>
          	               	106       	111B1     	GND                 
          	               	107       	111B4     	M_G_CPU1_SB_DQ<4>   
          	               	108       	111B1     	GND                 
          	               	109       	111B4     	M_G_CPU1_SB_DQ<5>   
          	               	110       	111B1     	GND                 
          	               	111       	111B4     	M_G_CPU1_SB_DQ<8>   
          	               	112       	111B1     	GND                 
          	               	113       	111B4     	M_G_CPU1_SB_DQ<9>   
          	               	114       	111B1     	GND                 
          	               	115       	111B2     	M_G_CPU1_SB_DQS_DP<1>
          	               	116       	111B2     	M_G_CPU1_SB_DQS_DN<1>
          	               	117       	111B1     	GND                 
          	               	118       	111B4     	M_G_CPU1_SB_DQ<12>  
          	               	119       	111B1     	GND                 
          	               	120       	111B4     	M_G_CPU1_SB_DQ<13>  
          	               	121       	111B1     	GND                 
          	               	122       	111B4     	M_G_CPU1_SB_DQ<16>  
          	               	123       	111B1     	GND                 
          	               	124       	111B4     	M_G_CPU1_SB_DQ<17>  
          	               	125       	111B1     	GND                 
          	               	126       	111B2     	M_G_CPU1_SB_DQS_DP<2>
          	               	127       	111B2     	M_G_CPU1_SB_DQS_DN<2>
          	               	128       	111B1     	GND                 
          	               	129       	111B4     	M_G_CPU1_SB_DQ<20>  
          	               	130       	111B1     	GND                 
          	               	131       	111B4     	M_G_CPU1_SB_DQ<21>  
          	               	132       	111B1     	GND                 
          	               	133       	111B4     	M_G_CPU1_SB_DQ<24>  
          	               	134       	111B1     	GND                 
          	               	135       	111B4     	M_G_CPU1_SB_DQ<25>  
          	               	136       	111B1     	GND                 
          	               	137       	111B2     	M_G_CPU1_SB_DQS_DP<3>
          	               	138       	111B2     	M_G_CPU1_SB_DQS_DN<3>
          	               	139       	111B1     	GND                 
          	               	140       	111B4     	M_G_CPU1_SB_DQ<28>  
          	               	141       	111B1     	GND                 
          	               	142       	111B4     	M_G_CPU1_SB_DQ<29>  
          	               	143       	111B1     	GND                 
          	               	144       	111B4     	TP_CHG_CPU1_DIMM2_FRU_1
          	               	145       	111B1     	P12V_S3_AUX_CPU1_NVDIMM
          	               	146       	111B1     	P12V_S3_AUX_CPU1_NVDIMM
          	               	147       	111B4     	PWRGD_CHG_CPU1_DIMM2
          	               	148       	111B4     	PD_CHG_CPU1_DIMM2_SAA
          	               	149       	111B4     	TP_CHG_CPU1_DIMM2_FRU_2
          	               	150       	111B4     	TP_CHG_CPU1_DIMM2_FRU_3
          	               	151       	111B1     	GND                 
          	               	152       	111B4     	M_G_CPU1_SA_DQ<2>   
          	               	153       	111B1     	GND                 
          	               	154       	111B4     	M_G_CPU1_SA_DQ<3>   
          	               	155       	111B1     	GND                 
          	               	156       	111B2     	M_G_CPU1_SA_DQS_DN<5>
          	               	157       	111B2     	M_G_CPU1_SA_DQS_DP<5>
          	               	158       	111B1     	GND                 
          	               	159       	111B4     	M_G_CPU1_SA_DQ<6>   
          	               	160       	111B1     	GND                 
          	               	161       	111B4     	M_G_CPU1_SA_DQ<7>   
          	               	162       	111B1     	GND                 
          	               	163       	111B4     	M_G_CPU1_SA_DQ<10>  
          	               	164       	111B1     	GND                 
          	               	165       	111B4     	M_G_CPU1_SA_DQ<11>  
          	               	166       	111B1     	GND                 
          	               	167       	111B2     	M_G_CPU1_SA_DQS_DN<6>
          	               	168       	111B2     	M_G_CPU1_SA_DQS_DP<6>
          	               	169       	111B1     	GND                 
          	               	170       	111B4     	M_G_CPU1_SA_DQ<14>  
          	               	171       	111B1     	GND                 
          	               	172       	111B4     	M_G_CPU1_SA_DQ<15>  
          	               	173       	111B1     	GND                 
          	               	174       	111B4     	M_G_CPU1_SA_DQ<18>  
          	               	175       	111B1     	GND                 
          	               	176       	111B4     	M_G_CPU1_SA_DQ<19>  
          	               	177       	111B1     	GND                 
          	               	178       	111B2     	M_G_CPU1_SA_DQS_DN<7>
          	               	179       	111B2     	M_G_CPU1_SA_DQS_DP<7>
          	               	180       	111B1     	GND                 
          	               	181       	111B4     	M_G_CPU1_SA_DQ<22>  
          	               	182       	111B1     	GND                 
          	               	183       	111B4     	M_G_CPU1_SA_DQ<23>  
          	               	184       	111B1     	GND                 
          	               	185       	111B4     	M_G_CPU1_SA_DQ<26>  
          	               	186       	111B1     	GND                 
          	               	187       	111B4     	M_G_CPU1_SA_DQ<27>  
          	               	188       	111B1     	GND                 
          	               	189       	111B2     	M_G_CPU1_SA_DQS_DN<8>
          	               	190       	111B2     	M_G_CPU1_SA_DQS_DP<8>
          	               	191       	111B1     	GND                 
          	               	192       	111B4     	M_G_CPU1_SA_DQ<30>  
          	               	193       	111B1     	GND                 
          	               	194       	111B4     	M_G_CPU1_SA_DQ<31>  
          	               	195       	111B1     	GND                 
          	               	196       	111B4     	M_G_CPU1_SA_CB<2>   
          	               	197       	111B1     	GND                 
          	               	198       	111B4     	M_G_CPU1_SA_CB<3>   
          	               	199       	111B1     	GND                 
          	               	200       	111B2     	M_G_CPU1_SA_DQS_DN<9>
          	               	201       	111B2     	M_G_CPU1_SA_DQS_DP<9>
          	               	202       	111B1     	GND                 
          	               	203       	111B4     	M_G_CPU1_SA_CB<6>   
          	               	204       	111B1     	GND                 
          	               	205       	111B4     	M_G_CPU1_SA_CB<7>   
          	               	206       	111B1     	GND                 
          	               	207       	111B4     	RST_M_GH_CPU1_FPGA_N
          	               	208       	111B1     	GND                 
          	               	209       	111B4     	M_G_CPU1_SA_CS_N<3> 
          	               	210       	111B1     	GND                 
          	               	211       	111B4     	M_G_CPU1_SA_CA<1>   
          	               	212       	111B1     	GND                 
          	               	213       	111B4     	M_G_CPU1_SA_CA<3>   
          	               	214       	111B1     	GND                 
          	               	215       	111B4     	M_G_CPU1_SA_CA<5>   
          	               	216       	111B1     	GND                 
          	               	217       	111B4     	M_G_CPU1_CLK_DP<1>  
          	               	218       	111B4     	M_G_CPU1_CLK_DN<1>  
          	               	219       	111B1     	GND                 
          	               	220       	111B4     	TP_CHG_CPU1_DIMM2_FRU_4
          	               	221       	111B4     	M_G_CPU1_SB_CA<1>   
          	               	222       	111B1     	GND                 
          	               	223       	111B4     	M_G_CPU1_SB_CA<3>   
          	               	224       	111B1     	GND                 
          	               	225       	111B4     	M_G_CPU1_SB_CA<5>   
          	               	226       	111B1     	GND                 
          	               	227       	111B4     	M_G_CPU1_SB_PAR     
          	               	228       	111B1     	GND                 
          	               	229       	111B4     	M_G_CPU1_SB_CS_N<3> 
          	               	230       	111B1     	GND                 
          	               	231       	111B4     	TP_CHG_CPU1_DIMM2_FRU_5
          	               	232       	111B4     	TP_CHG_CPU1_DIMM2_FRU_6
          	               	233       	111B1     	GND                 
          	               	234       	111B4     	M_G_CPU1_SB_CB<6>   
          	               	235       	111B1     	GND                 
          	               	236       	111B4     	M_G_CPU1_SB_CB<7>   
          	               	237       	111B1     	GND                 
          	               	238       	111B2     	M_G_CPU1_SB_DQS_DN<4>
          	               	239       	111B2     	M_G_CPU1_SB_DQS_DP<4>
          	               	240       	111B1     	GND                 
          	               	241       	111B4     	M_G_CPU1_SB_CB<2>   
          	               	242       	111B1     	GND                 
          	               	243       	111B4     	M_G_CPU1_SB_CB<3>   
          	               	244       	111B1     	GND                 
          	               	245       	111B4     	M_G_CPU1_SB_DQ<2>   
          	               	246       	111B1     	GND                 
          	               	247       	111B4     	M_G_CPU1_SB_DQ<3>   
          	               	248       	111B1     	GND                 
          	               	249       	111B2     	M_G_CPU1_SB_DQS_DN<5>
          	               	250       	111B2     	M_G_CPU1_SB_DQS_DP<5>
          	               	251       	111B1     	GND                 
          	               	252       	111B4     	M_G_CPU1_SB_DQ<6>   
          	               	253       	111B1     	GND                 
          	               	254       	111B4     	M_G_CPU1_SB_DQ<7>   
          	               	255       	111B1     	GND                 
          	               	256       	111B4     	M_G_CPU1_SB_DQ<10>  
          	               	257       	111B1     	GND                 
          	               	258       	111B4     	M_G_CPU1_SB_DQ<11>  
          	               	259       	111B1     	GND                 
          	               	260       	111B2     	M_G_CPU1_SB_DQS_DN<6>
          	               	261       	111B2     	M_G_CPU1_SB_DQS_DP<6>
          	               	262       	111B1     	GND                 
          	               	263       	111B4     	M_G_CPU1_SB_DQ<14>  
          	               	264       	111B1     	GND                 
          	               	265       	111B4     	M_G_CPU1_SB_DQ<15>  
          	               	266       	111B1     	GND                 
          	               	267       	111B4     	M_G_CPU1_SB_DQ<18>  
          	               	268       	111B1     	GND                 
          	               	269       	111B4     	M_G_CPU1_SB_DQ<19>  
          	               	270       	111B1     	GND                 
          	               	271       	111B2     	M_G_CPU1_SB_DQS_DN<7>
          	               	272       	111B2     	M_G_CPU1_SB_DQS_DP<7>
          	               	273       	111B1     	GND                 
          	               	274       	111B4     	M_G_CPU1_SB_DQ<22>  
          	               	275       	111B1     	GND                 
          	               	276       	111B4     	M_G_CPU1_SB_DQ<23>  
          	               	277       	111B1     	GND                 
          	               	278       	111B4     	M_G_CPU1_SB_DQ<26>  
          	               	279       	111B1     	GND                 
          	               	280       	111B4     	M_G_CPU1_SB_DQ<27>  
          	               	281       	111B1     	GND                 
          	               	282       	111B2     	M_G_CPU1_SB_DQS_DN<8>
          	               	283       	111B2     	M_G_CPU1_SB_DQS_DP<8>
          	               	284       	111B1     	GND                 
          	               	285       	111B4     	M_G_CPU1_SB_DQ<30>  
          	               	286       	111B1     	GND                 
          	               	287       	111B4     	M_G_CPU1_SB_DQ<31>  
          	               	288       	111B1     	GND                 
          	               	G1        	111B1     	GND                 
          	               	G2        	111A1     	GND                 
          	               	G3        	111A1     	GND                 

J31       	SCONN288_ADR50017P130CC	          	          	                    
          	               	1         	112B1     	P12V_S3_AUX_CPU1_NVDIMM
          	               	2         	112B4     	TP_CHH_CPU1_DIMM1_FRU_0
          	               	3         	112B4     	P3V3_AUX            
          	               	4         	112B4     	I3C_SPD_DDREFGH_CPU1_LVC1_SCL_6
          	               	5         	112B4     	I3C_SPD_DDREFGH_CPU1_LVC1_SDA
          	               	6         	112B1     	GND                 
          	               	7         	112B4     	M_H_CPU1_SA_DQ<0>   
          	               	8         	112B1     	GND                 
          	               	9         	112B4     	M_H_CPU1_SA_DQ<1>   
          	               	10        	112B1     	GND                 
          	               	11        	112B2     	M_H_CPU1_SA_DQS_DP<0>
          	               	12        	112B2     	M_H_CPU1_SA_DQS_DN<0>
          	               	13        	112B1     	GND                 
          	               	14        	112B4     	M_H_CPU1_SA_DQ<4>   
          	               	15        	112B1     	GND                 
          	               	16        	112B4     	M_H_CPU1_SA_DQ<5>   
          	               	17        	112B1     	GND                 
          	               	18        	112B4     	M_H_CPU1_SA_DQ<8>   
          	               	19        	112B1     	GND                 
          	               	20        	112B4     	M_H_CPU1_SA_DQ<9>   
          	               	21        	112B1     	GND                 
          	               	22        	112B2     	M_H_CPU1_SA_DQS_DP<1>
          	               	23        	112B2     	M_H_CPU1_SA_DQS_DN<1>
          	               	24        	112B1     	GND                 
          	               	25        	112B4     	M_H_CPU1_SA_DQ<12>  
          	               	26        	112B1     	GND                 
          	               	27        	112B4     	M_H_CPU1_SA_DQ<13>  
          	               	28        	112B1     	GND                 
          	               	29        	112B4     	M_H_CPU1_SA_DQ<16>  
          	               	30        	112B1     	GND                 
          	               	31        	112B4     	M_H_CPU1_SA_DQ<17>  
          	               	32        	112B1     	GND                 
          	               	33        	112B2     	M_H_CPU1_SA_DQS_DP<2>
          	               	34        	112B2     	M_H_CPU1_SA_DQS_DN<2>
          	               	35        	112B1     	GND                 
          	               	36        	112B4     	M_H_CPU1_SA_DQ<20>  
          	               	37        	112B1     	GND                 
          	               	38        	112B4     	M_H_CPU1_SA_DQ<21>  
          	               	39        	112B1     	GND                 
          	               	40        	112B4     	M_H_CPU1_SA_DQ<24>  
          	               	41        	112B1     	GND                 
          	               	42        	112B4     	M_H_CPU1_SA_DQ<25>  
          	               	43        	112B1     	GND                 
          	               	44        	112B2     	M_H_CPU1_SA_DQS_DP<3>
          	               	45        	112B2     	M_H_CPU1_SA_DQS_DN<3>
          	               	46        	112B1     	GND                 
          	               	47        	112B4     	M_H_CPU1_SA_DQ<28>  
          	               	48        	112B1     	GND                 
          	               	49        	112B4     	M_H_CPU1_SA_DQ<29>  
          	               	50        	112B1     	GND                 
          	               	51        	112B4     	M_H_CPU1_SA_CB<0>   
          	               	52        	112B1     	GND                 
          	               	53        	112B4     	M_H_CPU1_SA_CB<1>   
          	               	54        	112B1     	GND                 
          	               	55        	112B2     	M_H_CPU1_SA_DQS_DP<4>
          	               	56        	112B2     	M_H_CPU1_SA_DQS_DN<4>
          	               	57        	112B1     	GND                 
          	               	58        	112B4     	M_H_CPU1_SA_CB<4>   
          	               	59        	112B1     	GND                 
          	               	60        	112B4     	M_H_CPU1_SA_CB<5>   
          	               	61        	112B1     	GND                 
          	               	62        	112B4     	M_H_CPU1_ALERT_N    
          	               	63        	112B1     	GND                 
          	               	64        	112B4     	M_H_CPU1_SA_CS_N<0> 
          	               	65        	112B1     	GND                 
          	               	66        	112B4     	M_H_CPU1_SA_CA<0>   
          	               	67        	112B1     	GND                 
          	               	68        	112B4     	M_H_CPU1_SA_CA<2>   
          	               	69        	112B1     	GND                 
          	               	70        	112B4     	M_H_CPU1_SA_CA<4>   
          	               	71        	112B1     	GND                 
          	               	72        	112B4     	M_H_CPU1_SA_CA<6>   
          	               	73        	112B1     	GND                 
          	               	74        	112B4     	M_H_CPU1_SA_PAR     
          	               	75        	112B1     	GND                 
          	               	76        	112B4     	M_H_CPU1_SB_CA<0>   
          	               	77        	112B1     	GND                 
          	               	78        	112B4     	M_H_CPU1_SB_CA<2>   
          	               	79        	112B1     	GND                 
          	               	80        	112B4     	M_H_CPU1_SB_CA<4>   
          	               	81        	112B1     	GND                 
          	               	82        	112B4     	M_H_CPU1_SB_CA<6>   
          	               	83        	112B1     	GND                 
          	               	84        	112B4     	M_H_CPU1_SB_CS_N<0> 
          	               	85        	112B1     	GND                 
          	               	86        	112A4     	M_H_CPU1_SA_RSP<0>  
          	               	87        	112A4     	M_H_CPU1_SB_RSP<0>  
          	               	88        	112B1     	GND                 
          	               	89        	112B4     	M_H_CPU1_SB_CB<4>   
          	               	90        	112B1     	GND                 
          	               	91        	112B4     	M_H_CPU1_SB_CB<5>   
          	               	92        	112B1     	GND                 
          	               	93        	112B2     	M_H_CPU1_SB_DQS_DP<9>
          	               	94        	112B2     	M_H_CPU1_SB_DQS_DN<9>
          	               	95        	112B1     	GND                 
          	               	96        	112B4     	M_H_CPU1_SB_CB<0>   
          	               	97        	112B1     	GND                 
          	               	98        	112B4     	M_H_CPU1_SB_CB<1>   
          	               	99        	112B1     	GND                 
          	               	100       	112B4     	M_H_CPU1_SB_DQ<0>   
          	               	101       	112B1     	GND                 
          	               	102       	112B4     	M_H_CPU1_SB_DQ<1>   
          	               	103       	112B1     	GND                 
          	               	104       	112B2     	M_H_CPU1_SB_DQS_DP<0>
          	               	105       	112B2     	M_H_CPU1_SB_DQS_DN<0>
          	               	106       	112B1     	GND                 
          	               	107       	112B4     	M_H_CPU1_SB_DQ<4>   
          	               	108       	112B1     	GND                 
          	               	109       	112B4     	M_H_CPU1_SB_DQ<5>   
          	               	110       	112B1     	GND                 
          	               	111       	112B4     	M_H_CPU1_SB_DQ<8>   
          	               	112       	112B1     	GND                 
          	               	113       	112B4     	M_H_CPU1_SB_DQ<9>   
          	               	114       	112B1     	GND                 
          	               	115       	112B2     	M_H_CPU1_SB_DQS_DP<1>
          	               	116       	112B2     	M_H_CPU1_SB_DQS_DN<1>
          	               	117       	112B1     	GND                 
          	               	118       	112B4     	M_H_CPU1_SB_DQ<12>  
          	               	119       	112B1     	GND                 
          	               	120       	112B4     	M_H_CPU1_SB_DQ<13>  
          	               	121       	112B1     	GND                 
          	               	122       	112B4     	M_H_CPU1_SB_DQ<16>  
          	               	123       	112B1     	GND                 
          	               	124       	112B4     	M_H_CPU1_SB_DQ<17>  
          	               	125       	112B1     	GND                 
          	               	126       	112B2     	M_H_CPU1_SB_DQS_DP<2>
          	               	127       	112B2     	M_H_CPU1_SB_DQS_DN<2>
          	               	128       	112B1     	GND                 
          	               	129       	112B4     	M_H_CPU1_SB_DQ<20>  
          	               	130       	112B1     	GND                 
          	               	131       	112B4     	M_H_CPU1_SB_DQ<21>  
          	               	132       	112B1     	GND                 
          	               	133       	112B4     	M_H_CPU1_SB_DQ<24>  
          	               	134       	112B1     	GND                 
          	               	135       	112B4     	M_H_CPU1_SB_DQ<25>  
          	               	136       	112B1     	GND                 
          	               	137       	112B2     	M_H_CPU1_SB_DQS_DP<3>
          	               	138       	112B2     	M_H_CPU1_SB_DQS_DN<3>
          	               	139       	112B1     	GND                 
          	               	140       	112B4     	M_H_CPU1_SB_DQ<28>  
          	               	141       	112B1     	GND                 
          	               	142       	112B4     	M_H_CPU1_SB_DQ<29>  
          	               	143       	112B1     	GND                 
          	               	144       	112B4     	TP_CHH_CPU1_DIMM1_FRU_1
          	               	145       	112B1     	P12V_S3_AUX_CPU1_NVDIMM
          	               	146       	112B1     	P12V_S3_AUX_CPU1_NVDIMM
          	               	147       	112B4     	PWRGD_CHH_CPU1_DIMM1
          	               	148       	112B4     	PD_CHH_CPU1_DIMM1_SAA
          	               	149       	112B4     	TP_CHH_CPU1_DIMM1_FRU_2
          	               	150       	112B4     	TP_CHH_CPU1_DIMM1_FRU_3
          	               	151       	112B1     	GND                 
          	               	152       	112B4     	M_H_CPU1_SA_DQ<2>   
          	               	153       	112B1     	GND                 
          	               	154       	112B4     	M_H_CPU1_SA_DQ<3>   
          	               	155       	112B1     	GND                 
          	               	156       	112B2     	M_H_CPU1_SA_DQS_DN<5>
          	               	157       	112B2     	M_H_CPU1_SA_DQS_DP<5>
          	               	158       	112B1     	GND                 
          	               	159       	112B4     	M_H_CPU1_SA_DQ<6>   
          	               	160       	112B1     	GND                 
          	               	161       	112B4     	M_H_CPU1_SA_DQ<7>   
          	               	162       	112B1     	GND                 
          	               	163       	112B4     	M_H_CPU1_SA_DQ<10>  
          	               	164       	112B1     	GND                 
          	               	165       	112B4     	M_H_CPU1_SA_DQ<11>  
          	               	166       	112B1     	GND                 
          	               	167       	112B2     	M_H_CPU1_SA_DQS_DN<6>
          	               	168       	112B2     	M_H_CPU1_SA_DQS_DP<6>
          	               	169       	112B1     	GND                 
          	               	170       	112B4     	M_H_CPU1_SA_DQ<14>  
          	               	171       	112B1     	GND                 
          	               	172       	112B4     	M_H_CPU1_SA_DQ<15>  
          	               	173       	112B1     	GND                 
          	               	174       	112B4     	M_H_CPU1_SA_DQ<18>  
          	               	175       	112B1     	GND                 
          	               	176       	112B4     	M_H_CPU1_SA_DQ<19>  
          	               	177       	112B1     	GND                 
          	               	178       	112B2     	M_H_CPU1_SA_DQS_DN<7>
          	               	179       	112B2     	M_H_CPU1_SA_DQS_DP<7>
          	               	180       	112B1     	GND                 
          	               	181       	112B4     	M_H_CPU1_SA_DQ<22>  
          	               	182       	112B1     	GND                 
          	               	183       	112B4     	M_H_CPU1_SA_DQ<23>  
          	               	184       	112B1     	GND                 
          	               	185       	112B4     	M_H_CPU1_SA_DQ<26>  
          	               	186       	112B1     	GND                 
          	               	187       	112B4     	M_H_CPU1_SA_DQ<27>  
          	               	188       	112B1     	GND                 
          	               	189       	112B2     	M_H_CPU1_SA_DQS_DN<8>
          	               	190       	112B2     	M_H_CPU1_SA_DQS_DP<8>
          	               	191       	112B1     	GND                 
          	               	192       	112B4     	M_H_CPU1_SA_DQ<30>  
          	               	193       	112B1     	GND                 
          	               	194       	112B4     	M_H_CPU1_SA_DQ<31>  
          	               	195       	112B1     	GND                 
          	               	196       	112B4     	M_H_CPU1_SA_CB<2>   
          	               	197       	112B1     	GND                 
          	               	198       	112B4     	M_H_CPU1_SA_CB<3>   
          	               	199       	112B1     	GND                 
          	               	200       	112B2     	M_H_CPU1_SA_DQS_DN<9>
          	               	201       	112B2     	M_H_CPU1_SA_DQS_DP<9>
          	               	202       	112B1     	GND                 
          	               	203       	112B4     	M_H_CPU1_SA_CB<6>   
          	               	204       	112B1     	GND                 
          	               	205       	112B4     	M_H_CPU1_SA_CB<7>   
          	               	206       	112B1     	GND                 
          	               	207       	112B4     	RST_M_GH_CPU1_FPGA_N
          	               	208       	112B1     	GND                 
          	               	209       	112B4     	M_H_CPU1_SA_CS_N<1> 
          	               	210       	112B1     	GND                 
          	               	211       	112B4     	M_H_CPU1_SA_CA<1>   
          	               	212       	112B1     	GND                 
          	               	213       	112B4     	M_H_CPU1_SA_CA<3>   
          	               	214       	112B1     	GND                 
          	               	215       	112B4     	M_H_CPU1_SA_CA<5>   
          	               	216       	112B1     	GND                 
          	               	217       	112B4     	M_H_CPU1_CLK_DP<0>  
          	               	218       	112B4     	M_H_CPU1_CLK_DN<0>  
          	               	219       	112B1     	GND                 
          	               	220       	112B4     	TP_CHH_CPU1_DIMM1_FRU_4
          	               	221       	112B4     	M_H_CPU1_SB_CA<1>   
          	               	222       	112B1     	GND                 
          	               	223       	112B4     	M_H_CPU1_SB_CA<3>   
          	               	224       	112B1     	GND                 
          	               	225       	112B4     	M_H_CPU1_SB_CA<5>   
          	               	226       	112B1     	GND                 
          	               	227       	112B4     	M_H_CPU1_SB_PAR     
          	               	228       	112B1     	GND                 
          	               	229       	112B4     	M_H_CPU1_SB_CS_N<1> 
          	               	230       	112B1     	GND                 
          	               	231       	112B4     	TP_CHH_CPU1_DIMM1_FRU_5
          	               	232       	112B4     	TP_CHH_CPU1_DIMM1_FRU_6
          	               	233       	112B1     	GND                 
          	               	234       	112B4     	M_H_CPU1_SB_CB<6>   
          	               	235       	112B1     	GND                 
          	               	236       	112B4     	M_H_CPU1_SB_CB<7>   
          	               	237       	112B1     	GND                 
          	               	238       	112B2     	M_H_CPU1_SB_DQS_DN<4>
          	               	239       	112B2     	M_H_CPU1_SB_DQS_DP<4>
          	               	240       	112B1     	GND                 
          	               	241       	112B4     	M_H_CPU1_SB_CB<2>   
          	               	242       	112B1     	GND                 
          	               	243       	112B4     	M_H_CPU1_SB_CB<3>   
          	               	244       	112B1     	GND                 
          	               	245       	112B4     	M_H_CPU1_SB_DQ<2>   
          	               	246       	112B1     	GND                 
          	               	247       	112B4     	M_H_CPU1_SB_DQ<3>   
          	               	248       	112B1     	GND                 
          	               	249       	112B2     	M_H_CPU1_SB_DQS_DN<5>
          	               	250       	112B2     	M_H_CPU1_SB_DQS_DP<5>
          	               	251       	112B1     	GND                 
          	               	252       	112B4     	M_H_CPU1_SB_DQ<6>   
          	               	253       	112B1     	GND                 
          	               	254       	112B4     	M_H_CPU1_SB_DQ<7>   
          	               	255       	112B1     	GND                 
          	               	256       	112B4     	M_H_CPU1_SB_DQ<10>  
          	               	257       	112B1     	GND                 
          	               	258       	112B4     	M_H_CPU1_SB_DQ<11>  
          	               	259       	112B1     	GND                 
          	               	260       	112B2     	M_H_CPU1_SB_DQS_DN<6>
          	               	261       	112B2     	M_H_CPU1_SB_DQS_DP<6>
          	               	262       	112B1     	GND                 
          	               	263       	112B4     	M_H_CPU1_SB_DQ<14>  
          	               	264       	112B1     	GND                 
          	               	265       	112B4     	M_H_CPU1_SB_DQ<15>  
          	               	266       	112B1     	GND                 
          	               	267       	112B4     	M_H_CPU1_SB_DQ<18>  
          	               	268       	112B1     	GND                 
          	               	269       	112B4     	M_H_CPU1_SB_DQ<19>  
          	               	270       	112B1     	GND                 
          	               	271       	112B2     	M_H_CPU1_SB_DQS_DN<7>
          	               	272       	112B2     	M_H_CPU1_SB_DQS_DP<7>
          	               	273       	112B1     	GND                 
          	               	274       	112B4     	M_H_CPU1_SB_DQ<22>  
          	               	275       	112B1     	GND                 
          	               	276       	112B4     	M_H_CPU1_SB_DQ<23>  
          	               	277       	112B1     	GND                 
          	               	278       	112B4     	M_H_CPU1_SB_DQ<26>  
          	               	279       	112B1     	GND                 
          	               	280       	112B4     	M_H_CPU1_SB_DQ<27>  
          	               	281       	112B1     	GND                 
          	               	282       	112B2     	M_H_CPU1_SB_DQS_DN<8>
          	               	283       	112B2     	M_H_CPU1_SB_DQS_DP<8>
          	               	284       	112B1     	GND                 
          	               	285       	112B4     	M_H_CPU1_SB_DQ<30>  
          	               	286       	112B1     	GND                 
          	               	287       	112B4     	M_H_CPU1_SB_DQ<31>  
          	               	288       	112B1     	GND                 
          	               	G1        	112B1     	GND                 
          	               	G2        	112A1     	GND                 
          	               	G3        	112A1     	GND                 

J32       	SCONN288_ADR50017P087CC	          	          	                    
          	               	1         	113B1     	P12V_S3_AUX_CPU1_NVDIMM
          	               	2         	113B4     	TP_CHH_CPU1_DIMM2_FRU_0
          	               	3         	113B4     	P3V3_AUX            
          	               	4         	113B4     	I3C_SPD_DDREFGH_CPU1_LVC1_SCL_7
          	               	5         	113B4     	I3C_SPD_DDREFGH_CPU1_LVC1_SDA
          	               	6         	113B1     	GND                 
          	               	7         	113B4     	M_H_CPU1_SA_DQ<0>   
          	               	8         	113B1     	GND                 
          	               	9         	113B4     	M_H_CPU1_SA_DQ<1>   
          	               	10        	113B1     	GND                 
          	               	11        	113B2     	M_H_CPU1_SA_DQS_DP<0>
          	               	12        	113B2     	M_H_CPU1_SA_DQS_DN<0>
          	               	13        	113B1     	GND                 
          	               	14        	113B4     	M_H_CPU1_SA_DQ<4>   
          	               	15        	113B1     	GND                 
          	               	16        	113B4     	M_H_CPU1_SA_DQ<5>   
          	               	17        	113B1     	GND                 
          	               	18        	113B4     	M_H_CPU1_SA_DQ<8>   
          	               	19        	113B1     	GND                 
          	               	20        	113B4     	M_H_CPU1_SA_DQ<9>   
          	               	21        	113B1     	GND                 
          	               	22        	113B2     	M_H_CPU1_SA_DQS_DP<1>
          	               	23        	113B2     	M_H_CPU1_SA_DQS_DN<1>
          	               	24        	113B1     	GND                 
          	               	25        	113B4     	M_H_CPU1_SA_DQ<12>  
          	               	26        	113B1     	GND                 
          	               	27        	113B4     	M_H_CPU1_SA_DQ<13>  
          	               	28        	113B1     	GND                 
          	               	29        	113B4     	M_H_CPU1_SA_DQ<16>  
          	               	30        	113B1     	GND                 
          	               	31        	113B4     	M_H_CPU1_SA_DQ<17>  
          	               	32        	113B1     	GND                 
          	               	33        	113B2     	M_H_CPU1_SA_DQS_DP<2>
          	               	34        	113B2     	M_H_CPU1_SA_DQS_DN<2>
          	               	35        	113B1     	GND                 
          	               	36        	113B4     	M_H_CPU1_SA_DQ<20>  
          	               	37        	113B1     	GND                 
          	               	38        	113B4     	M_H_CPU1_SA_DQ<21>  
          	               	39        	113B1     	GND                 
          	               	40        	113B4     	M_H_CPU1_SA_DQ<24>  
          	               	41        	113B1     	GND                 
          	               	42        	113B4     	M_H_CPU1_SA_DQ<25>  
          	               	43        	113B1     	GND                 
          	               	44        	113B2     	M_H_CPU1_SA_DQS_DP<3>
          	               	45        	113B2     	M_H_CPU1_SA_DQS_DN<3>
          	               	46        	113B1     	GND                 
          	               	47        	113B4     	M_H_CPU1_SA_DQ<28>  
          	               	48        	113B1     	GND                 
          	               	49        	113B4     	M_H_CPU1_SA_DQ<29>  
          	               	50        	113B1     	GND                 
          	               	51        	113B4     	M_H_CPU1_SA_CB<0>   
          	               	52        	113B1     	GND                 
          	               	53        	113B4     	M_H_CPU1_SA_CB<1>   
          	               	54        	113B1     	GND                 
          	               	55        	113B2     	M_H_CPU1_SA_DQS_DP<4>
          	               	56        	113B2     	M_H_CPU1_SA_DQS_DN<4>
          	               	57        	113B1     	GND                 
          	               	58        	113B4     	M_H_CPU1_SA_CB<4>   
          	               	59        	113B1     	GND                 
          	               	60        	113B4     	M_H_CPU1_SA_CB<5>   
          	               	61        	113B1     	GND                 
          	               	62        	113B4     	M_H_CPU1_ALERT_N    
          	               	63        	113B1     	GND                 
          	               	64        	113B4     	M_H_CPU1_SA_CS_N<2> 
          	               	65        	113B1     	GND                 
          	               	66        	113B4     	M_H_CPU1_SA_CA<0>   
          	               	67        	113B1     	GND                 
          	               	68        	113B4     	M_H_CPU1_SA_CA<2>   
          	               	69        	113B1     	GND                 
          	               	70        	113B4     	M_H_CPU1_SA_CA<4>   
          	               	71        	113B1     	GND                 
          	               	72        	113B4     	M_H_CPU1_SA_CA<6>   
          	               	73        	113B1     	GND                 
          	               	74        	113B4     	M_H_CPU1_SA_PAR     
          	               	75        	113B1     	GND                 
          	               	76        	113B4     	M_H_CPU1_SB_CA<0>   
          	               	77        	113B1     	GND                 
          	               	78        	113B4     	M_H_CPU1_SB_CA<2>   
          	               	79        	113B1     	GND                 
          	               	80        	113B4     	M_H_CPU1_SB_CA<4>   
          	               	81        	113B1     	GND                 
          	               	82        	113B4     	M_H_CPU1_SB_CA<6>   
          	               	83        	113B1     	GND                 
          	               	84        	113B4     	M_H_CPU1_SB_CS_N<2> 
          	               	85        	113B1     	GND                 
          	               	86        	113A4     	M_H_CPU1_SA_RSP<1>  
          	               	87        	113A4     	M_H_CPU1_SB_RSP<1>  
          	               	88        	113B1     	GND                 
          	               	89        	113B4     	M_H_CPU1_SB_CB<4>   
          	               	90        	113B1     	GND                 
          	               	91        	113B4     	M_H_CPU1_SB_CB<5>   
          	               	92        	113B1     	GND                 
          	               	93        	113B2     	M_H_CPU1_SB_DQS_DP<9>
          	               	94        	113B2     	M_H_CPU1_SB_DQS_DN<9>
          	               	95        	113B1     	GND                 
          	               	96        	113B4     	M_H_CPU1_SB_CB<0>   
          	               	97        	113B1     	GND                 
          	               	98        	113B4     	M_H_CPU1_SB_CB<1>   
          	               	99        	113B1     	GND                 
          	               	100       	113B4     	M_H_CPU1_SB_DQ<0>   
          	               	101       	113B1     	GND                 
          	               	102       	113B4     	M_H_CPU1_SB_DQ<1>   
          	               	103       	113B1     	GND                 
          	               	104       	113B2     	M_H_CPU1_SB_DQS_DP<0>
          	               	105       	113B2     	M_H_CPU1_SB_DQS_DN<0>
          	               	106       	113B1     	GND                 
          	               	107       	113B4     	M_H_CPU1_SB_DQ<4>   
          	               	108       	113B1     	GND                 
          	               	109       	113B4     	M_H_CPU1_SB_DQ<5>   
          	               	110       	113B1     	GND                 
          	               	111       	113B4     	M_H_CPU1_SB_DQ<8>   
          	               	112       	113B1     	GND                 
          	               	113       	113B4     	M_H_CPU1_SB_DQ<9>   
          	               	114       	113B1     	GND                 
          	               	115       	113B2     	M_H_CPU1_SB_DQS_DP<1>
          	               	116       	113B2     	M_H_CPU1_SB_DQS_DN<1>
          	               	117       	113B1     	GND                 
          	               	118       	113B4     	M_H_CPU1_SB_DQ<12>  
          	               	119       	113B1     	GND                 
          	               	120       	113B4     	M_H_CPU1_SB_DQ<13>  
          	               	121       	113B1     	GND                 
          	               	122       	113B4     	M_H_CPU1_SB_DQ<16>  
          	               	123       	113B1     	GND                 
          	               	124       	113B4     	M_H_CPU1_SB_DQ<17>  
          	               	125       	113B1     	GND                 
          	               	126       	113B2     	M_H_CPU1_SB_DQS_DP<2>
          	               	127       	113B2     	M_H_CPU1_SB_DQS_DN<2>
          	               	128       	113B1     	GND                 
          	               	129       	113B4     	M_H_CPU1_SB_DQ<20>  
          	               	130       	113B1     	GND                 
          	               	131       	113B4     	M_H_CPU1_SB_DQ<21>  
          	               	132       	113B1     	GND                 
          	               	133       	113B4     	M_H_CPU1_SB_DQ<24>  
          	               	134       	113B1     	GND                 
          	               	135       	113B4     	M_H_CPU1_SB_DQ<25>  
          	               	136       	113B1     	GND                 
          	               	137       	113B2     	M_H_CPU1_SB_DQS_DP<3>
          	               	138       	113B2     	M_H_CPU1_SB_DQS_DN<3>
          	               	139       	113B1     	GND                 
          	               	140       	113B4     	M_H_CPU1_SB_DQ<28>  
          	               	141       	113B1     	GND                 
          	               	142       	113B4     	M_H_CPU1_SB_DQ<29>  
          	               	143       	113B1     	GND                 
          	               	144       	113B4     	TP_CHH_CPU1_DIMM2_FRU_1
          	               	145       	113B1     	P12V_S3_AUX_CPU1_NVDIMM
          	               	146       	113B1     	P12V_S3_AUX_CPU1_NVDIMM
          	               	147       	113B4     	PWRGD_CHH_CPU1_DIMM2
          	               	148       	113B4     	PD_CHH_CPU1_DIMM2_SAA
          	               	149       	113B4     	TP_CHH_CPU1_DIMM2_FRU_2
          	               	150       	113B4     	TP_CHH_CPU1_DIMM2_FRU_3
          	               	151       	113B1     	GND                 
          	               	152       	113B4     	M_H_CPU1_SA_DQ<2>   
          	               	153       	113B1     	GND                 
          	               	154       	113B4     	M_H_CPU1_SA_DQ<3>   
          	               	155       	113B1     	GND                 
          	               	156       	113B2     	M_H_CPU1_SA_DQS_DN<5>
          	               	157       	113B2     	M_H_CPU1_SA_DQS_DP<5>
          	               	158       	113B1     	GND                 
          	               	159       	113B4     	M_H_CPU1_SA_DQ<6>   
          	               	160       	113B1     	GND                 
          	               	161       	113B4     	M_H_CPU1_SA_DQ<7>   
          	               	162       	113B1     	GND                 
          	               	163       	113B4     	M_H_CPU1_SA_DQ<10>  
          	               	164       	113B1     	GND                 
          	               	165       	113B4     	M_H_CPU1_SA_DQ<11>  
          	               	166       	113B1     	GND                 
          	               	167       	113B2     	M_H_CPU1_SA_DQS_DN<6>
          	               	168       	113B2     	M_H_CPU1_SA_DQS_DP<6>
          	               	169       	113B1     	GND                 
          	               	170       	113B4     	M_H_CPU1_SA_DQ<14>  
          	               	171       	113B1     	GND                 
          	               	172       	113B4     	M_H_CPU1_SA_DQ<15>  
          	               	173       	113B1     	GND                 
          	               	174       	113B4     	M_H_CPU1_SA_DQ<18>  
          	               	175       	113B1     	GND                 
          	               	176       	113B4     	M_H_CPU1_SA_DQ<19>  
          	               	177       	113B1     	GND                 
          	               	178       	113B2     	M_H_CPU1_SA_DQS_DN<7>
          	               	179       	113B2     	M_H_CPU1_SA_DQS_DP<7>
          	               	180       	113B1     	GND                 
          	               	181       	113B4     	M_H_CPU1_SA_DQ<22>  
          	               	182       	113B1     	GND                 
          	               	183       	113B4     	M_H_CPU1_SA_DQ<23>  
          	               	184       	113B1     	GND                 
          	               	185       	113B4     	M_H_CPU1_SA_DQ<26>  
          	               	186       	113B1     	GND                 
          	               	187       	113B4     	M_H_CPU1_SA_DQ<27>  
          	               	188       	113B1     	GND                 
          	               	189       	113B2     	M_H_CPU1_SA_DQS_DN<8>
          	               	190       	113B2     	M_H_CPU1_SA_DQS_DP<8>
          	               	191       	113B1     	GND                 
          	               	192       	113B4     	M_H_CPU1_SA_DQ<30>  
          	               	193       	113B1     	GND                 
          	               	194       	113B4     	M_H_CPU1_SA_DQ<31>  
          	               	195       	113B1     	GND                 
          	               	196       	113B4     	M_H_CPU1_SA_CB<2>   
          	               	197       	113B1     	GND                 
          	               	198       	113B4     	M_H_CPU1_SA_CB<3>   
          	               	199       	113B1     	GND                 
          	               	200       	113B2     	M_H_CPU1_SA_DQS_DN<9>
          	               	201       	113B2     	M_H_CPU1_SA_DQS_DP<9>
          	               	202       	113B1     	GND                 
          	               	203       	113B4     	M_H_CPU1_SA_CB<6>   
          	               	204       	113B1     	GND                 
          	               	205       	113B4     	M_H_CPU1_SA_CB<7>   
          	               	206       	113B1     	GND                 
          	               	207       	113B4     	RST_M_GH_CPU1_FPGA_N
          	               	208       	113B1     	GND                 
          	               	209       	113B4     	M_H_CPU1_SA_CS_N<3> 
          	               	210       	113B1     	GND                 
          	               	211       	113B4     	M_H_CPU1_SA_CA<1>   
          	               	212       	113B1     	GND                 
          	               	213       	113B4     	M_H_CPU1_SA_CA<3>   
          	               	214       	113B1     	GND                 
          	               	215       	113B4     	M_H_CPU1_SA_CA<5>   
          	               	216       	113B1     	GND                 
          	               	217       	113B4     	M_H_CPU1_CLK_DP<1>  
          	               	218       	113B4     	M_H_CPU1_CLK_DN<1>  
          	               	219       	113B1     	GND                 
          	               	220       	113B4     	TP_CHH_CPU1_DIMM2_FRU_4
          	               	221       	113B4     	M_H_CPU1_SB_CA<1>   
          	               	222       	113B1     	GND                 
          	               	223       	113B4     	M_H_CPU1_SB_CA<3>   
          	               	224       	113B1     	GND                 
          	               	225       	113B4     	M_H_CPU1_SB_CA<5>   
          	               	226       	113B1     	GND                 
          	               	227       	113B4     	M_H_CPU1_SB_PAR     
          	               	228       	113B1     	GND                 
          	               	229       	113B4     	M_H_CPU1_SB_CS_N<3> 
          	               	230       	113B1     	GND                 
          	               	231       	113B4     	TP_CHH_CPU1_DIMM2_FRU_5
          	               	232       	113B4     	TP_CHH_CPU1_DIMM2_FRU_6
          	               	233       	113B1     	GND                 
          	               	234       	113B4     	M_H_CPU1_SB_CB<6>   
          	               	235       	113B1     	GND                 
          	               	236       	113B4     	M_H_CPU1_SB_CB<7>   
          	               	237       	113B1     	GND                 
          	               	238       	113B2     	M_H_CPU1_SB_DQS_DN<4>
          	               	239       	113B2     	M_H_CPU1_SB_DQS_DP<4>
          	               	240       	113B1     	GND                 
          	               	241       	113B4     	M_H_CPU1_SB_CB<2>   
          	               	242       	113B1     	GND                 
          	               	243       	113B4     	M_H_CPU1_SB_CB<3>   
          	               	244       	113B1     	GND                 
          	               	245       	113B4     	M_H_CPU1_SB_DQ<2>   
          	               	246       	113B1     	GND                 
          	               	247       	113B4     	M_H_CPU1_SB_DQ<3>   
          	               	248       	113B1     	GND                 
          	               	249       	113B2     	M_H_CPU1_SB_DQS_DN<5>
          	               	250       	113B2     	M_H_CPU1_SB_DQS_DP<5>
          	               	251       	113B1     	GND                 
          	               	252       	113B4     	M_H_CPU1_SB_DQ<6>   
          	               	253       	113B1     	GND                 
          	               	254       	113B4     	M_H_CPU1_SB_DQ<7>   
          	               	255       	113B1     	GND                 
          	               	256       	113B4     	M_H_CPU1_SB_DQ<10>  
          	               	257       	113B1     	GND                 
          	               	258       	113B4     	M_H_CPU1_SB_DQ<11>  
          	               	259       	113B1     	GND                 
          	               	260       	113B2     	M_H_CPU1_SB_DQS_DN<6>
          	               	261       	113B2     	M_H_CPU1_SB_DQS_DP<6>
          	               	262       	113B1     	GND                 
          	               	263       	113B4     	M_H_CPU1_SB_DQ<14>  
          	               	264       	113B1     	GND                 
          	               	265       	113B4     	M_H_CPU1_SB_DQ<15>  
          	               	266       	113B1     	GND                 
          	               	267       	113B4     	M_H_CPU1_SB_DQ<18>  
          	               	268       	113B1     	GND                 
          	               	269       	113B4     	M_H_CPU1_SB_DQ<19>  
          	               	270       	113B1     	GND                 
          	               	271       	113B2     	M_H_CPU1_SB_DQS_DN<7>
          	               	272       	113B2     	M_H_CPU1_SB_DQS_DP<7>
          	               	273       	113B1     	GND                 
          	               	274       	113B4     	M_H_CPU1_SB_DQ<22>  
          	               	275       	113B1     	GND                 
          	               	276       	113B4     	M_H_CPU1_SB_DQ<23>  
          	               	277       	113B1     	GND                 
          	               	278       	113B4     	M_H_CPU1_SB_DQ<26>  
          	               	279       	113B1     	GND                 
          	               	280       	113B4     	M_H_CPU1_SB_DQ<27>  
          	               	281       	113B1     	GND                 
          	               	282       	113B2     	M_H_CPU1_SB_DQS_DN<8>
          	               	283       	113B2     	M_H_CPU1_SB_DQS_DP<8>
          	               	284       	113B1     	GND                 
          	               	285       	113B4     	M_H_CPU1_SB_DQ<30>  
          	               	286       	113B1     	GND                 
          	               	287       	113B4     	M_H_CPU1_SB_DQ<31>  
          	               	288       	113B1     	GND                 
          	               	G1        	113B1     	GND                 
          	               	G2        	113A1     	GND                 
          	               	G3        	113A1     	GND                 

J35       	SCONN168_ME1016810202011	          	          	                    
          	               	A1        	159B3     	GND                 
          	               	A2        	159B3     	GND                 
          	               	A3        	159B3     	GND                 
          	               	A4        	159B3     	GND                 
          	               	A5        	159B3     	GND                 
          	               	A6        	159B3     	GND                 
          	               	A7        	159B3     	SMB_OCP_V3_2_3V3AUX_BUF_R_SCL
          	               	A8        	159B3     	SMB_OCP_V3_2_3V3AUX_BUF_R_SDA
          	               	A9        	159B3     	RST_SMB_OCP_V3_2_N  
          	               	A10       	159B3     	OCP_V3_1_PRSNTA_R_N 
          	               	A11       	159B3     	RST_PERST1_OCP_V3_2_N
          	               	A12       	159B3     	OCP_V3_2_PRSNT2_R_N 
          	               	A13       	159B3     	GND                 
          	               	A14       	159B3     	CLK_100M_OCP_V3_2_B_DN
          	               	A15       	159B3     	CLK_100M_OCP_V3_2_B_DP
          	               	A16       	159B3     	GND                 
          	               	A17       	159B3     	P5E_CPU1_PE1_RX_DN<0>
          	               	A18       	159B3     	P5E_CPU1_PE1_RX_DP<0>
          	               	A19       	159B3     	GND                 
          	               	A20       	159B3     	P5E_CPU1_PE1_RX_DN<1>
          	               	A21       	159B3     	P5E_CPU1_PE1_RX_DP<1>
          	               	A22       	159B3     	GND                 
          	               	A23       	159B3     	P5E_CPU1_PE1_RX_DN<2>
          	               	A24       	159B3     	P5E_CPU1_PE1_RX_DP<2>
          	               	A25       	159B3     	GND                 
          	               	A26       	159B3     	P5E_CPU1_PE1_RX_DN<3>
          	               	A27       	159B3     	P5E_CPU1_PE1_RX_DP<3>
          	               	A28       	159B3     	GND                 
          	               	A29       	159B3     	GND                 
          	               	A30       	159B3     	P5E_CPU1_PE1_RX_DN<4>
          	               	A31       	159B3     	P5E_CPU1_PE1_RX_DP<4>
          	               	A32       	159B3     	GND                 
          	               	A33       	159B3     	P5E_CPU1_PE1_RX_DN<5>
          	               	A34       	159B3     	P5E_CPU1_PE1_RX_DP<5>
          	               	A35       	159B3     	GND                 
          	               	A36       	159B3     	P5E_CPU1_PE1_RX_DN<6>
          	               	A37       	159B3     	P5E_CPU1_PE1_RX_DP<6>
          	               	A38       	159B3     	GND                 
          	               	A39       	159B3     	P5E_CPU1_PE1_RX_DN<7>
          	               	A40       	159B3     	P5E_CPU1_PE1_RX_DP<7>
          	               	A41       	159B3     	GND                 
          	               	A42       	159B3     	OCP_V3_2_PRSNT1_R_N 
          	               	A43       	159B3     	GND                 
          	               	A44       	159B3     	P5E_CPU1_PE1_RX_DN<8>
          	               	A45       	159B3     	P5E_CPU1_PE1_RX_DP<8>
          	               	A46       	159B3     	GND                 
          	               	A47       	159B3     	P5E_CPU1_PE1_RX_DN<9>
          	               	A48       	159B3     	P5E_CPU1_PE1_RX_DP<9>
          	               	A49       	159B3     	GND                 
          	               	A50       	159B3     	P5E_CPU1_PE1_RX_DN<10>
          	               	A51       	159B3     	P5E_CPU1_PE1_RX_DP<10>
          	               	A52       	159B3     	GND                 
          	               	A53       	159A3     	P5E_CPU1_PE1_RX_DN<11>
          	               	A54       	159A3     	P5E_CPU1_PE1_RX_DP<11>
          	               	A55       	159A3     	GND                 
          	               	A56       	159A3     	P5E_CPU1_PE1_RX_DN<12>
          	               	A57       	159A3     	P5E_CPU1_PE1_RX_DP<12>
          	               	A58       	159A3     	GND                 
          	               	A59       	159A3     	P5E_CPU1_PE1_RX_DN<13>
          	               	A60       	159A3     	P5E_CPU1_PE1_RX_DP<13>
          	               	A61       	159A3     	GND                 
          	               	A62       	159A3     	P5E_CPU1_PE1_RX_DN<14>
          	               	A63       	159A3     	P5E_CPU1_PE1_RX_DP<14>
          	               	A64       	159A3     	GND                 
          	               	A65       	159A3     	P5E_CPU1_PE1_RX_DN<15>
          	               	A66       	159A3     	P5E_CPU1_PE1_RX_DP<15>
          	               	A67       	159A3     	GND                 
          	               	A68       	159A3     	USB2_5_R1_DN        
          	               	A69       	159A3     	USB2_5_R1_DP        
          	               	A70       	159A3     	OCP_V3_2_PWRBRK_N   
          	               	B1        	159B3     	P12V_OCP_V3_2       
          	               	B2        	159B3     	P12V_OCP_V3_2       
          	               	B3        	159B3     	P12V_OCP_V3_2       
          	               	B4        	159B3     	P12V_OCP_V3_2       
          	               	B5        	159B3     	P12V_OCP_V3_2       
          	               	B6        	159B3     	P12V_OCP_V3_2       
          	               	B7        	159B3     	OCP_V3_2_BIF0_R_N   
          	               	B8        	159B3     	OCP_V3_2_BIF1_R_N   
          	               	B9        	159B3     	OCP_V3_2_BIF2_R_N   
          	               	B10       	159B3     	RST_PERST0_OCP_V3_2_N
          	               	B11       	159B3     	P3V3_OCP_V3_2       
          	               	B12       	159B3     	OCP_V3_2_AUX_PWR_EN_R
          	               	B13       	159B3     	GND                 
          	               	B14       	159B3     	CLK_100M_OCP_V3_2_A_DN
          	               	B15       	159B3     	CLK_100M_OCP_V3_2_A_DP
          	               	B16       	159B3     	GND                 
          	               	B17       	159B3     	P5E_CPU1_PE1_TX_C_DP<0>
          	               	B18       	159B3     	P5E_CPU1_PE1_TX_C_DN<0>
          	               	B19       	159B3     	GND                 
          	               	B20       	159B3     	P5E_CPU1_PE1_TX_C_DN<1>
          	               	B21       	159B3     	P5E_CPU1_PE1_TX_C_DP<1>
          	               	B22       	159B3     	GND                 
          	               	B23       	159B3     	P5E_CPU1_PE1_TX_C_DP<2>
          	               	B24       	159B3     	P5E_CPU1_PE1_TX_C_DN<2>
          	               	B25       	159B3     	GND                 
          	               	B26       	159B3     	P5E_CPU1_PE1_TX_C_DN<3>
          	               	B27       	159B3     	P5E_CPU1_PE1_TX_C_DP<3>
          	               	B28       	159B3     	GND                 
          	               	B29       	159B3     	GND                 
          	               	B30       	159B3     	P5E_CPU1_PE1_TX_C_DP<4>
          	               	B31       	159B3     	P5E_CPU1_PE1_TX_C_DN<4>
          	               	B32       	159B3     	GND                 
          	               	B33       	159B3     	P5E_CPU1_PE1_TX_C_DN<5>
          	               	B34       	159B3     	P5E_CPU1_PE1_TX_C_DP<5>
          	               	B35       	159B3     	GND                 
          	               	B36       	159B3     	P5E_CPU1_PE1_TX_C_DP<6>
          	               	B37       	159B3     	P5E_CPU1_PE1_TX_C_DN<6>
          	               	B38       	159B3     	GND                 
          	               	B39       	159B3     	P5E_CPU1_PE1_TX_C_DN<7>
          	               	B40       	159B3     	P5E_CPU1_PE1_TX_C_DP<7>
          	               	B41       	159B3     	GND                 
          	               	B42       	159B3     	OCP_V3_2_PRSNT0_R_N 
          	               	B43       	159B3     	GND                 
          	               	B44       	159B3     	P5E_CPU1_PE1_TX_C_DP<8>
          	               	B45       	159B3     	P5E_CPU1_PE1_TX_C_DN<8>
          	               	B46       	159B3     	GND                 
          	               	B47       	159B3     	P5E_CPU1_PE1_TX_C_DN<9>
          	               	B48       	159B3     	P5E_CPU1_PE1_TX_C_DP<9>
          	               	B49       	159B3     	GND                 
          	               	B50       	159B3     	P5E_CPU1_PE1_TX_C_DP<10>
          	               	B51       	159B3     	P5E_CPU1_PE1_TX_C_DN<10>
          	               	B52       	159B3     	GND                 
          	               	B53       	159A3     	P5E_CPU1_PE1_TX_C_DN<11>
          	               	B54       	159A3     	P5E_CPU1_PE1_TX_C_DP<11>
          	               	B55       	159A3     	GND                 
          	               	B56       	159A3     	P5E_CPU1_PE1_TX_C_DP<12>
          	               	B57       	159A3     	P5E_CPU1_PE1_TX_C_DN<12>
          	               	B58       	159A3     	GND                 
          	               	B59       	159A3     	P5E_CPU1_PE1_TX_C_DN<13>
          	               	B60       	159A3     	P5E_CPU1_PE1_TX_C_DP<13>
          	               	B61       	159A3     	GND                 
          	               	B62       	159A3     	P5E_CPU1_PE1_TX_C_DP<14>
          	               	B63       	159A3     	P5E_CPU1_PE1_TX_C_DN<14>
          	               	B64       	159A3     	GND                 
          	               	B65       	159A3     	P5E_CPU1_PE1_TX_C_DN<15>
          	               	B66       	159A3     	P5E_CPU1_PE1_TX_C_DP<15>
          	               	B67       	159A3     	GND                 
          	               	B68       	159A3     	TP_OCP_V3_2_B68     
          	               	B69       	159A3     	TP_OCP_V3_2_B69     
          	               	B70       	159A3     	OCP_V3_2_PRSNT3_R_N 
          	               	G1        	159A3     	GND                 
          	               	G2        	159A3     	GND                 
          	               	G3        	159A3     	GND                 
          	               	G4        	159A3     	GND                 
          	               	G5        	159A3     	GND                 
          	               	OA1       	159B3     	RST_PERST2_OCP_V3_2_N
          	               	OA2       	159B3     	RST_PERST3_OCP_V3_2_N
          	               	OA3       	159B3     	IRQ_LVC3_OCP_V3_2_WAKE_N
          	               	OA4       	159B3     	OCP_V3_2_ISO1_RBT_ARB_IN
          	               	OA5       	159B3     	OCP_V3_2_ISO2_RBT_ARB_OUT
          	               	OA6       	159B3     	OCP_V3_2_ID1        
          	               	OA7       	159B3     	NCSI_OCP_V3_2_TX_EN 
          	               	OA8       	159B3     	NCSI_OCP_V3_2_TXD1  
          	               	OA9       	159B3     	NCSI_OCP_V3_2_TXD0  
          	               	OA10      	159B3     	GND                 
          	               	OA11      	159B3     	CLK_100M_OCP_V3_2_D_DN
          	               	OA12      	159B3     	CLK_100M_OCP_V3_2_D_DP
          	               	OA13      	159B3     	GND                 
          	               	OA14      	159B3     	CLK_50M_NCSI_OCP_V3_2_ISO
          	               	OB1       	159B3     	FM_OCP_V3_2_PWR_GOOD
          	               	OB2       	159B3     	OCP_V3_2_MAIN_PWR_EN_R
          	               	OB3       	159B3     	SGPIO_OCP_V3_2_LD_N 
          	               	OB4       	159B3     	SGPIO_OCP_V3_2_DATAIN
          	               	OB5       	159B3     	SGPIO_OCP_V3_2_DATAOUT
          	               	OB6       	159B3     	SGPIO_OCP_V3_2_CLK  
          	               	OB7       	159B3     	OCP_V3_2_ID0        
          	               	OB8       	159B3     	NCSI_OCP_V3_2_RXD1  
          	               	OB9       	159B3     	NCSI_OCP_V3_2_RXD0  
          	               	OB10      	159B3     	GND                 
          	               	OB11      	159B3     	CLK_100M_OCP_V3_2_C_DN
          	               	OB12      	159B3     	CLK_100M_OCP_V3_2_C_DP
          	               	OB13      	159B3     	GND                 
          	               	OB14      	159B3     	NCSI_OCP_V3_2_CRS_DV

J37       	SCONN168_ME1016810202011	          	          	                    
          	               	A1        	153B3     	GND                 
          	               	A2        	153B3     	GND                 
          	               	A3        	153B3     	GND                 
          	               	A4        	153B3     	GND                 
          	               	A5        	153B3     	GND                 
          	               	A6        	153B3     	GND                 
          	               	A7        	153B3     	SMB_OCP_SFF_3V3AUX_BUF_R_SCL
          	               	A8        	153B3     	SMB_OCP_SFF_3V3AUX_BUF_R_SDA
          	               	A9        	153B3     	RST_SMB_OCP_SFF_N   
          	               	A10       	153B3     	OCP_SFF_PRSNTA_R_N  
          	               	A11       	153B3     	RST_PERST1_OCP_SFF_N
          	               	A12       	153B3     	OCP_SFF_PRSNT2_R_N  
          	               	A13       	153B3     	GND                 
          	               	A14       	153B3     	CLK_100M_OCP_SFF_1_DN
          	               	A15       	153B3     	CLK_100M_OCP_SFF_1_DP
          	               	A16       	153B3     	GND                 
          	               	A17       	153B3     	P5E_CPU0_PE1_RX_DN<0>
          	               	A18       	153B3     	P5E_CPU0_PE1_RX_DP<0>
          	               	A19       	153B3     	GND                 
          	               	A20       	153B3     	P5E_CPU0_PE1_RX_DP<1>
          	               	A21       	153B3     	P5E_CPU0_PE1_RX_DN<1>
          	               	A22       	153B3     	GND                 
          	               	A23       	153B3     	P5E_CPU0_PE1_RX_DP<2>
          	               	A24       	153B3     	P5E_CPU0_PE1_RX_DN<2>
          	               	A25       	153B3     	GND                 
          	               	A26       	153B3     	P5E_CPU0_PE1_RX_DP<3>
          	               	A27       	153B3     	P5E_CPU0_PE1_RX_DN<3>
          	               	A28       	153B3     	GND                 
          	               	A29       	153B3     	GND                 
          	               	A30       	153B3     	P5E_CPU0_PE1_RX_DP<4>
          	               	A31       	153B3     	P5E_CPU0_PE1_RX_DN<4>
          	               	A32       	153B3     	GND                 
          	               	A33       	153B3     	P5E_CPU0_PE1_RX_DP<5>
          	               	A34       	153B3     	P5E_CPU0_PE1_RX_DN<5>
          	               	A35       	153B3     	GND                 
          	               	A36       	153B3     	P5E_CPU0_PE1_RX_DP<6>
          	               	A37       	153B3     	P5E_CPU0_PE1_RX_DN<6>
          	               	A38       	153B3     	GND                 
          	               	A39       	153B3     	P5E_CPU0_PE1_RX_DP<7>
          	               	A40       	153B3     	P5E_CPU0_PE1_RX_DN<7>
          	               	A41       	153B3     	GND                 
          	               	A42       	153B3     	OCP_SFF_PRSNT1_R_N  
          	               	A43       	153B3     	GND                 
          	               	A44       	153B3     	P5E_CPU0_PE1_RX_DP<8>
          	               	A45       	153B3     	P5E_CPU0_PE1_RX_DN<8>
          	               	A46       	153B3     	GND                 
          	               	A47       	153B3     	P5E_CPU0_PE1_RX_DP<9>
          	               	A48       	153B3     	P5E_CPU0_PE1_RX_DN<9>
          	               	A49       	153B3     	GND                 
          	               	A50       	153B3     	P5E_CPU0_PE1_RX_DP<10>
          	               	A51       	153B3     	P5E_CPU0_PE1_RX_DN<10>
          	               	A52       	153B3     	GND                 
          	               	A53       	153A3     	P5E_CPU0_PE1_RX_DP<11>
          	               	A54       	153A3     	P5E_CPU0_PE1_RX_DN<11>
          	               	A55       	153A3     	GND                 
          	               	A56       	153A3     	P5E_CPU0_PE1_RX_DP<12>
          	               	A57       	153A3     	P5E_CPU0_PE1_RX_DN<12>
          	               	A58       	153A3     	GND                 
          	               	A59       	153A3     	P5E_CPU0_PE1_RX_DP<13>
          	               	A60       	153A3     	P5E_CPU0_PE1_RX_DN<13>
          	               	A61       	153A3     	GND                 
          	               	A62       	153A3     	P5E_CPU0_PE1_RX_DP<14>
          	               	A63       	153A3     	P5E_CPU0_PE1_RX_DN<14>
          	               	A64       	153A3     	GND                 
          	               	A65       	153A3     	P5E_CPU0_PE1_RX_DP<15>
          	               	A66       	153A3     	P5E_CPU0_PE1_RX_DN<15>
          	               	A67       	153A3     	GND                 
          	               	A68       	153A3     	OCP_SFF_USB2_3_DN   
          	               	A69       	153A3     	OCP_SFF_USB2_3_DP   
          	               	A70       	153A3     	OCP_SFF_PWRBRK_N    
          	               	B1        	153B3     	P12V_OCP_SFF        
          	               	B2        	153B3     	P12V_OCP_SFF        
          	               	B3        	153B3     	P12V_OCP_SFF        
          	               	B4        	153B3     	P12V_OCP_SFF        
          	               	B5        	153B3     	P12V_OCP_SFF        
          	               	B6        	153B3     	P12V_OCP_SFF        
          	               	B7        	153B3     	OCP_SFF_BIF0_R_N    
          	               	B8        	153B3     	OCP_SFF_BIF1_R_N    
          	               	B9        	153B3     	OCP_SFF_BIF2_R_N    
          	               	B10       	153B3     	RST_PERST0_OCP_SFF_N
          	               	B11       	153B3     	P3V3_OCP_SFF        
          	               	B12       	153B3     	OCP_SFF_AUX_PWR_EN_R
          	               	B13       	153B3     	GND                 
          	               	B14       	153B3     	CLK_100M_OCP_SFF_0_DN
          	               	B15       	153B3     	CLK_100M_OCP_SFF_0_DP
          	               	B16       	153B3     	GND                 
          	               	B17       	153B3     	P5E_CPU0_PE1_TX_C_DN<0>
          	               	B18       	153B3     	P5E_CPU0_PE1_TX_C_DP<0>
          	               	B19       	153B3     	GND                 
          	               	B20       	153B3     	P5E_CPU0_PE1_TX_C_DN<1>
          	               	B21       	153B3     	P5E_CPU0_PE1_TX_C_DP<1>
          	               	B22       	153B3     	GND                 
          	               	B23       	153B3     	P5E_CPU0_PE1_TX_C_DP<2>
          	               	B24       	153B3     	P5E_CPU0_PE1_TX_C_DN<2>
          	               	B25       	153B3     	GND                 
          	               	B26       	153B3     	P5E_CPU0_PE1_TX_C_DN<3>
          	               	B27       	153B3     	P5E_CPU0_PE1_TX_C_DP<3>
          	               	B28       	153B3     	GND                 
          	               	B29       	153B3     	GND                 
          	               	B30       	153B3     	P5E_CPU0_PE1_TX_C_DP<4>
          	               	B31       	153B3     	P5E_CPU0_PE1_TX_C_DN<4>
          	               	B32       	153B3     	GND                 
          	               	B33       	153B3     	P5E_CPU0_PE1_TX_C_DN<5>
          	               	B34       	153B3     	P5E_CPU0_PE1_TX_C_DP<5>
          	               	B35       	153B3     	GND                 
          	               	B36       	153B3     	P5E_CPU0_PE1_TX_C_DP<6>
          	               	B37       	153B3     	P5E_CPU0_PE1_TX_C_DN<6>
          	               	B38       	153B3     	GND                 
          	               	B39       	153B3     	P5E_CPU0_PE1_TX_C_DN<7>
          	               	B40       	153B3     	P5E_CPU0_PE1_TX_C_DP<7>
          	               	B41       	153B3     	GND                 
          	               	B42       	153B3     	OCP_SFF_PRSNT0_R_N  
          	               	B43       	153B3     	GND                 
          	               	B44       	153B3     	P5E_CPU0_PE1_TX_C_DP<8>
          	               	B45       	153B3     	P5E_CPU0_PE1_TX_C_DN<8>
          	               	B46       	153B3     	GND                 
          	               	B47       	153B3     	P5E_CPU0_PE1_TX_C_DN<9>
          	               	B48       	153B3     	P5E_CPU0_PE1_TX_C_DP<9>
          	               	B49       	153B3     	GND                 
          	               	B50       	153B3     	P5E_CPU0_PE1_TX_C_DP<10>
          	               	B51       	153B3     	P5E_CPU0_PE1_TX_C_DN<10>
          	               	B52       	153B3     	GND                 
          	               	B53       	153A3     	P5E_CPU0_PE1_TX_C_DN<11>
          	               	B54       	153A3     	P5E_CPU0_PE1_TX_C_DP<11>
          	               	B55       	153A3     	GND                 
          	               	B56       	153A3     	P5E_CPU0_PE1_TX_C_DP<12>
          	               	B57       	153A3     	P5E_CPU0_PE1_TX_C_DN<12>
          	               	B58       	153A3     	GND                 
          	               	B59       	153A3     	P5E_CPU0_PE1_TX_C_DN<13>
          	               	B60       	153A3     	P5E_CPU0_PE1_TX_C_DP<13>
          	               	B61       	153A3     	GND                 
          	               	B62       	153A3     	P5E_CPU0_PE1_TX_C_DP<14>
          	               	B63       	153A3     	P5E_CPU0_PE1_TX_C_DN<14>
          	               	B64       	153A3     	GND                 
          	               	B65       	153A3     	P5E_CPU0_PE1_TX_C_DN<15>
          	               	B66       	153A3     	P5E_CPU0_PE1_TX_C_DP<15>
          	               	B67       	153A3     	GND                 
          	               	B68       	153A3     	TP_OCP_SFF_B68      
          	               	B69       	153A3     	TP_OCP_SFF_B69      
          	               	B70       	153A3     	OCP_SFF_PRSNT3_R_N  
          	               	G1        	153A3     	GND                 
          	               	G2        	153A3     	GND                 
          	               	G3        	153A3     	GND                 
          	               	G4        	153A3     	GND                 
          	               	G5        	153A3     	GND                 
          	               	OA1       	153B3     	RST_PERST2_OCP_SFF_N
          	               	OA2       	153B3     	RST_PERST3_OCP_SFF_N
          	               	OA3       	153B3     	IRQ_LVC3_OCP_SFF_WAKE_N
          	               	OA4       	153B3     	OCP_SFF_ISO1_RBT_ARB_IN
          	               	OA5       	153B3     	OCP_SFF_ISO2_RBT_ARB_OUT
          	               	OA6       	153B3     	OCP_SFF_ID1         
          	               	OA7       	153B3     	NCSI_OCP_SFF_TX_EN  
          	               	OA8       	153B3     	NCSI_OCP_SFF_TXD1   
          	               	OA9       	153B3     	NCSI_OCP_SFF_TXD0   
          	               	OA10      	153B3     	GND                 
          	               	OA11      	153B3     	CLK_100M_OCP_SFF_3_DN
          	               	OA12      	153B3     	CLK_100M_OCP_SFF_3_DP
          	               	OA13      	153B3     	GND                 
          	               	OA14      	153B3     	CLK_50M_NCSI_OCP_SFF_ISO
          	               	OB1       	153B3     	FM_OCP_SFF_PWR_GOOD 
          	               	OB2       	153B3     	OCP_SFF_MAIN_PWR_EN_R
          	               	OB3       	153B3     	SGPIO_OCP_SFF_LD_N  
          	               	OB4       	153B3     	SGPIO_OCP_SFF_DATAIN
          	               	OB5       	153B3     	SGPIO_OCP_SFF_DATAOUT
          	               	OB6       	153B3     	SGPIO_OCP_SFF_CLK   
          	               	OB7       	153B3     	OCP_SFF_ID0         
          	               	OB8       	153B3     	NCSI_OCP_SFF_RXD1   
          	               	OB9       	153B3     	NCSI_OCP_SFF_RXD0   
          	               	OB10      	153B3     	GND                 
          	               	OB11      	153B3     	CLK_100M_OCP_SFF_2_DN
          	               	OB12      	153B3     	CLK_100M_OCP_SFF_2_DP
          	               	OB13      	153B3     	GND                 
          	               	OB14      	153B3     	NCSI_OCP_SFF_CRS_DV 

J41       	SCONN168_ME1016810202011	          	          	                    
          	               	A1        	240B3     	SMB_OCP_SFF_3V3AUX_SCL_R0
          	               	A2        	240B3     	SMB_OCP_SFF_3V3AUX_SDA_R0
          	               	A3        	240B3     	SMB_HOST_3V3AUX_SCL_R0
          	               	A4        	240B3     	SMB_HOST_3V3AUX_SDA_R0
          	               	A5        	240B3     	SMB_VR_3V3AUX_SCL_R0
          	               	A6        	240B3     	SMB_VR_3V3AUX_SDA_R0
          	               	A7        	240B3     	SMB_SML1_PMBUS_3V3AUX_PCH_SCL_R
          	               	A8        	240B3     	SMB_SML1_PMBUS_3V3AUX_PCH_SDA_R
          	               	A9        	240B3     	I3C_BMC_SWB_SCL     
          	               	A10       	240B3     	I3C_BMC_SWB_SDA     
          	               	A11       	240B3     	SMB_OCP_V3_2_3V3AUX_SCL_R0
          	               	A12       	240B3     	SMB_OCP_V3_2_3V3AUX_SDA_R0
          	               	A13       	240B3     	GND                 
          	               	A14       	240B3     	CLK_100M_BMC_P3E_DP_R
          	               	A15       	240B3     	CLK_100M_BMC_P3E_DN_R
          	               	A16       	240B3     	GND                 
          	               	A17       	240B3     	P3E_PCH_BMC_TX_C_DP 
          	               	A18       	240B3     	P3E_PCH_BMC_TX_C_DN 
          	               	A19       	240B3     	GND                 
          	               	A20       	240B3     	P3E_PCH_BMC_RX_DP   
          	               	A21       	240B3     	P3E_PCH_BMC_RX_DN   
          	               	A22       	240B3     	GND                 
          	               	A23       	240B3     	SMB_PCIE0_3V3AUX_SCL
          	               	A24       	240B3     	SMB_PCIE0_3V3AUX_SDA
          	               	A25       	240B3     	SMB_SML0_3V3AUX_SCL_R1
          	               	A26       	240B3     	SMB_SML0_3V3AUX_SDA_R1
          	               	A27       	240B3     	SMB_1_PLD_3V3AUX_SCL_R3
          	               	A28       	240B3     	SMB_1_PLD_3V3AUX_SDA_R3
          	               	A29       	240B3     	SMB_FAN_3V3AUX_SCL  
          	               	A30       	240B3     	SMB_FAN_3V3AUX_SDA  
          	               	A31       	240B3     	SMB_PCIE2_3V3AUX_SCL_R0
          	               	A32       	240B3     	SMB_PCIE2_3V3AUX_SDA_R0
          	               	A33       	240B3     	GND                 
          	               	A34       	240B3     	JTAG_BMC_TCK        
          	               	A35       	240B3     	JTAG_BMC_TMS        
          	               	A36       	240B3     	JTAG_BMC_TDI        
          	               	A37       	240B3     	JTAG_BMC_TDO        
          	               	A38       	240B3     	SMB_PCIE3_3V3AUX_SCL_R
          	               	A39       	240B3     	SMB_PCIE3_3V3AUX_SDA_R
          	               	A40       	240B3     	SMB_S3M_CPU_3V3AUX_SCL_R0
          	               	A41       	240B3     	SMB_S3M_CPU_3V3AUX_SDA_R0
          	               	A42       	240B3     	GND                 
          	               	A43       	240B3     	FM_JTAG_BMC_MUX_SEL_FROM_BMC_R2
          	               	A44       	240B3     	PWRGD_PS_PWROK_R    
          	               	A45       	240B3     	TP_HPM_STBY_EN      
          	               	A46       	240B3     	RST_MB_STBY_N       
          	               	A47       	240A3     	FM_BMC_PWRBTN_OUT_R_N
          	               	A48       	240A3     	PWRGD_SYS_PWROK     
          	               	A49       	240A3     	JTAG_BMC_DBP_PREQ_N 
          	               	A50       	240A3     	JTAG_DBP_BMC_PRDY_N 
          	               	A51       	240A3     	RST_PLTRST_B_N      
          	               	A52       	240A3     	FM_UARTSW_MSB_R     
          	               	A53       	240A3     	ROT_P1_RST_IND_N    
          	               	A54       	240A3     	TP_CHASI            
          	               	A55       	240A3     	FM_UARTSW_LSB_R     
          	               	A56       	240A3     	IRQ0_A57            
          	               	A57       	240A3     	FM_SCM_PRSNT1_N     
          	               	A58       	240A3     	GND                 
          	               	A59       	240A3     	USB3_PCH_RX_DP<4>   
          	               	A60       	240A3     	USB3_PCH_RX_DN<4>   
          	               	A61       	240A3     	GND                 
          	               	A62       	240A3     	TP_PCIE_HPM_RXP<1>  
          	               	A63       	240A3     	TP_PCIE_HPM_RXN<1>  
          	               	A64       	240A3     	GND                 
          	               	A65       	240A3     	P2E_MB_BMC_RX_BUF_DP<0>
          	               	A66       	240A3     	P2E_MB_BMC_RX_BUF_DN<0>
          	               	A67       	240A3     	GND                 
          	               	A68       	240A3     	CLK_100M_BMC_RC_DP  
          	               	A69       	240A3     	CLK_100M_BMC_RC_DN  
          	               	A70       	240A3     	GND                 
          	               	B1        	240B2     	ESPI_HOST_LPC_BMC_CLK
          	               	B2        	240B2     	ESPI_HOST_LPC_BMC_LFRAME_N
          	               	B3        	240B2     	IRQ_ESPI_LPC_SERIRQ_ALERT_R_N
          	               	B4        	240B2     	ESPI_BMC_LPC_RST_N  
          	               	B5        	240B2     	ESPI_LPC_LAD0_IO0   
          	               	B6        	240B2     	ESPI_LPC_LAD0_IO1   
          	               	B7        	240B2     	ESPI_LPC_LAD0_IO2   
          	               	B8        	240B2     	ESPI_LPC_LAD0_IO3   
          	               	B9        	240B2     	FM_LPC_ESPI_SEL     
          	               	B10       	240B2     	GND                 
          	               	B11       	240B2     	SPI_SYS_CLK         
          	               	B12       	240B2     	SPI_SYS_CS0_N       
          	               	B13       	240B2     	SPI_SYS_MOSI        
          	               	B14       	240B2     	SPI_SYS_MISO        
          	               	B15       	240B2     	SPI_SYS_WP_IO2      
          	               	B16       	240B2     	SPI_SYS_HOLD_IO3    
          	               	B17       	240B2     	GND                 
          	               	B18       	240B2     	CLK_50M_RMII_BMC_OCP
          	               	B19       	240B2     	RMII_OCP_BMC_CRSDV  
          	               	B20       	240B2     	RMII_BMC_OCP_TX_EN  
          	               	B21       	240B2     	RMII_BMC_OCP_TXD_0  
          	               	B22       	240B2     	RMII_BMC_OCP_TXD_1  
          	               	B23       	240B2     	RMII_BMC_OCP_RX_ER  
          	               	B24       	240B2     	RMII_OCP_BMC_RXD_0  
          	               	B25       	240B2     	RMII_OCP_BMC_RXD_1  
          	               	B26       	240B2     	GND                 
          	               	B27       	240B2     	PECI_BMC            
          	               	B28       	240B2     	PVCCIO_PECI_BMC     
          	               	B29       	240B2     	SGPIO_DO_0          
          	               	B30       	240B2     	SGPIO_CLK_0         
          	               	B31       	240B2     	SGPIO_DI_0          
          	               	B32       	240B2     	SGPIO_LD_0          
          	               	B33       	240B2     	GND                 
          	               	B34       	240B2     	SGPIO_DO_1          
          	               	B35       	240B2     	SGPIO_CLK_1         
          	               	B36       	240B2     	SGPIO_DI_1          
          	               	B37       	240B2     	SGPIO_LD_1          
          	               	B38       	240B2     	GND                 
          	               	B39       	240B2     	RST_SGPIO_RESET_N   
          	               	B40       	240B2     	IRQ_SGPIO_INTR_N    
          	               	B41       	240B2     	P3V_BAT_R1          
          	               	B42       	240B2     	FM_AC_PWR_BTN_N     
          	               	B43       	240B2     	TP_SPI_2_PLD_CLK    
          	               	B44       	240B2     	TP_SPI_2_PLD_CS_N   
          	               	B45       	240B2     	TP_SPI_2_PLD_IO0    
          	               	B46       	240B2     	TP_SPI_2_PLD_IO1    
          	               	B47       	240A2     	TP_SPI_2_PLD_IO2    
          	               	B48       	240A2     	TP_SPI_2_PLD_IO3    
          	               	B49       	240A2     	GND                 
          	               	B50       	240A2     	USB2_HOST_BMC_B_DP  
          	               	B51       	240A2     	USB2_HOST_BMC_B_DN  
          	               	B52       	240A2     	GND                 
          	               	B53       	240A2     	USB2_8_DP           
          	               	B54       	240A2     	USB2_8_DN           
          	               	B55       	240A2     	GND                 
          	               	B56       	240A2     	USB2_HUB_2_BUF_EXT_DP
          	               	B57       	240A2     	USB2_HUB_2_BUF_EXT_DN
          	               	B58       	240A2     	GND                 
          	               	B59       	240A2     	USB3_PCH_TX_BUF_C_DP<4>
          	               	B60       	240A2     	USB3_PCH_TX_BUF_C_DN<4>
          	               	B61       	240A2     	GND                 
          	               	B62       	240A2     	TP_PCIE_HPM_TXP<1>  
          	               	B63       	240A2     	TP_PCIE_HPM_TXN<1>  
          	               	B64       	240A2     	GND                 
          	               	B65       	240A2     	P2E_MB_BMC_TX_C_DP<0>
          	               	B66       	240A2     	P2E_MB_BMC_TX_C_DN<0>
          	               	B67       	240A2     	GND                 
          	               	B68       	240A2     	TP_PCIE_HPM_TXP<3>  
          	               	B69       	240A2     	TP_PCIE_HPM_TXN<3>  
          	               	B70       	240A2     	GND                 
          	               	G1        	240A3     	GND                 
          	               	G2        	240A3     	GND                 
          	               	G3        	240A3     	GND                 
          	               	G4        	240A3     	GND                 
          	               	G5        	240A3     	GND                 
          	               	OA1       	240B3     	P12V_SCM            
          	               	OA2       	240B3     	P12V_SCM            
          	               	OA3       	240B3     	GND                 
          	               	OA4       	240B3     	GND                 
          	               	OA5       	240B3     	I3C_SPD_DDRABCD_CPU0_BMC_R_SCL
          	               	OA6       	240B3     	I3C_SPD_DDRABCD_CPU0_BMC_R_SDA
          	               	OA7       	240B3     	I3C_SPD_DDREFGH_CPU0_BMC_R_SCL
          	               	OA8       	240B3     	I3C_SPD_DDREFGH_CPU0_BMC_R_SDA
          	               	OA9       	240B3     	I3C_SPD_DDRABCD_CPU1_BMC_R_SCL
          	               	OA10      	240B3     	I3C_SPD_DDRABCD_CPU1_BMC_R_SDA
          	               	OA11      	240B3     	I3C_SPD_DDREFGH_CPU1_BMC_R_SCL
          	               	OA12      	240B3     	I3C_SPD_DDREFGH_CPU1_BMC_R_SDA
          	               	OA13      	240B3     	GND                 
          	               	OA14      	240B3     	VIRTUAL_RESEAT      
          	               	OB1       	240B2     	P12V_SCM            
          	               	OB2       	240B2     	P12V_SCM            
          	               	OB3       	240B2     	PRSNT0_N            
          	               	OB4       	240B2     	GND                 
          	               	OB5       	240B2     	UART_BMC_BIC_TX     
          	               	OB6       	240B2     	UART_BMC_BIC_BUF_RX 
          	               	OB7       	240B2     	GND                 
          	               	OB8       	240B2     	USB2_7_R_DP         
          	               	OB9       	240B2     	USB2_7_R_DN         
          	               	OB10      	240B2     	GND                 
          	               	OB11      	240B2     	RST_SRST_PLD_BMC_N  
          	               	OB12      	240B2     	SPI_TPM_CS_N        
          	               	OB13      	240B2     	H_CPU_CATERR_LVC2_BMC_N
          	               	OB14      	240B2     	FM_SOL_UART_CH_SEL_R

J42       	SCONN60_ASP21410801	          	          	                    
          	               	1         	131B3     	P1V05_PCH_AUX       
          	               	2         	131B3     	JTAG_DBP_TMS_R      
          	               	3         	131B3     	JTAG_DBP_CPU_GTL_TCK_R
          	               	4         	131B3     	JTAG_DBP_TDO_R      
          	               	5         	131B3     	JTAG_DBP_TDI_R      
          	               	6         	131B3     	JTAG_RST_DBP_RST_CO_N
          	               	7         	131B3     	JTAG_DBP_PMODE      
          	               	8         	131B3     	PD_TRST_P3          
          	               	9         	131B3     	NC_MIPI60_P9        
          	               	10        	131B3     	JTAG_DBP_PREQ_N_R   
          	               	11        	131B3     	JTAG_DBP_PRDY_R1_N  
          	               	12        	131B3     	P1V8_PCH_AUX        
          	               	13        	131B3     	JTAG_TRC_PCH_PTI0_CLK
          	               	14        	131B3     	GND                 
          	               	15        	131B3     	JTAG_DBP_PCH_DEBUG_CONSENT_N
          	               	16        	131B3     	GND                 
          	               	17        	131B3     	JTAG_DBP_PRESENT_R_N
          	               	18        	131B3     	NC_DBP_P18          
          	               	19        	131B3     	JTAG_TRC_PCH_PTI<0> 
          	               	20        	131B3     	NC_DBP_P20          
          	               	21        	131B3     	JTAG_TRC_PCH_PTI<1> 
          	               	22        	131B3     	NC_DBP_P22          
          	               	23        	131B3     	JTAG_TRC_PCH_PTI<2> 
          	               	24        	131B3     	NC_DBP_P24          
          	               	25        	131B3     	JTAG_TRC_PCH_PTI<3> 
          	               	26        	131B3     	NC_DBP_P26          
          	               	27        	131B3     	JTAG_TRC_PCH_PTI<4> 
          	               	28        	131B3     	NC_DBP_P28          
          	               	29        	131B3     	JTAG_TRC_PCH_PTI<5> 
          	               	30        	131B3     	NC_DBP_P30          
          	               	31        	131B3     	JTAG_TRC_PCH_PTI<6> 
          	               	32        	131B3     	NC_DBP_P32          
          	               	33        	131B3     	JTAG_TRC_PCH_PTI<7> 
          	               	34        	131B3     	NC_DBP_P34          
          	               	35        	131B3     	JTAG_TRC_PCH_PTI<8> 
          	               	36        	131B3     	JTAG_DBP_BOOT_HALT_N
          	               	37        	131B3     	JTAG_TRC_PCH_PTI<9> 
          	               	38        	131B3     	FM_CPU_FBRK_DEBUG_N 
          	               	39        	131B3     	JTAG_TRC_PCH_PTI<10>
          	               	40        	131B3     	JTAG_DBP_POWER_BTN_N
          	               	41        	131B3     	JTAG_TRC_PCH_PTI<11>
          	               	42        	131B3     	JTAG_RST_DBP_RSMRST_N
          	               	43        	131B3     	JTAG_TRC_PCH_PTI<12>
          	               	44        	131B3     	NC_DBP_P44          
          	               	45        	131B3     	JTAG_TRC_PCH_PTI<13>
          	               	46        	131B3     	NC_DBP_P46          
          	               	47        	131B3     	JTAG_TRC_PCH_PTI<14>
          	               	48        	131B3     	SMB_HOST_3V3AUX_XDP_R_SCL
          	               	49        	131B3     	JTAG_TRC_PCH_PTI<15>
          	               	50        	131B3     	SMB_HOST_3V3AUX_XDP_R_SDA
          	               	51        	131B3     	JTAG_DBP_TCK_R_TCK  
          	               	52        	131B3     	P3V3_AUX            
          	               	53        	131B3     	JTAG_DBP_CPU_HOOK9_MBP3_GTL_N
          	               	54        	131B3     	NC_DBP_P54          
          	               	55        	131B3     	JTAG_DBP_CPU_HOOK8_MBP2_GTL_N
          	               	56        	131B3     	NC_DBP_P56          
          	               	57        	131B3     	GND                 
          	               	58        	131B3     	GND                 
          	               	59        	131B3     	JTAG_TRC_PCH_PTI1_CLK
          	               	60        	131B3     	GND                 
          	               	G1        	131B3     	GND                 
          	               	G2        	131B3     	GND                 
          	               	G3        	131B3     	GND                 
          	               	G4        	131B3     	GND                 

J43       	CONN8_210HP1080BR1	          	          	                    
          	               	1         	221A3     	P3V3_AUX_BMC_D      
          	               	2         	221A3     	JTAG_BMC_PLD_TDO    
          	               	3         	221A3     	JTAG_BMC_PLD_TDI    
          	               	4         	221A3     	TP_PLD_CONN_P4      
          	               	5         	221A3     	TP_PLD_CONN_P5      
          	               	6         	221A3     	JTAG_BMC_PLD_TMS    
          	               	7         	221A3     	GND                 
          	               	8         	221A3     	JTAG_BMC_PLD_TCK    

J45       	CONN60_101062636003K02LF	          	          	                    
          	               	A1        	245B3     	TP_J45_A1           
          	               	A2        	245B3     	FM_AC_PWR_BTN_PDB_N 
          	               	A3        	245B3     	P3V3_PDB_AUX_ADC    
          	               	B1        	245B3     	RST_SMB_SWITCH_R_N  
          	               	B2        	245B3     	PWRGD_P3V3_AUX_PDB_BUF
          	               	B3        	245B3     	GND                 
          	               	C1        	245B3     	SMB_FAN_3V3AUX_BUF_R_SCL
          	               	C2        	245B3     	SMB_FAN_3V3AUX_BUF_R_SDA
          	               	C3        	245B3     	HPDB_HSC_PWRGD_R    
          	               	D1        	245B3     	FM_FAN_PWR_EN_R     
          	               	D2        	245B3     	FM_GPU_HSC_EN_BUF_R1
          	               	D3        	245B3     	PDB_PRSNT_N         
          	               	P1_1      	245B3     	GND                 
          	               	P1_2      	245B3     	GND                 
          	               	P1_3      	245B3     	GND                 
          	               	P1_4      	245B3     	GND                 
          	               	P1_5      	245B3     	GND                 
          	               	P1_6      	245B3     	GND                 
          	               	P1_7      	245B3     	GND                 
          	               	P1_8      	245B3     	GND                 
          	               	P2_1      	245B3     	GND                 
          	               	P2_2      	245B3     	GND                 
          	               	P2_3      	245B3     	GND                 
          	               	P2_4      	245B3     	GND                 
          	               	P2_5      	245B3     	GND                 
          	               	P2_6      	245B3     	GND                 
          	               	P2_7      	245B3     	GND                 
          	               	P2_8      	245B3     	GND                 
          	               	P3_1      	245B3     	GND                 
          	               	P3_2      	245B3     	GND                 
          	               	P3_3      	245B3     	GND                 
          	               	P3_4      	245B3     	GND                 
          	               	P3_5      	245B3     	GND                 
          	               	P3_6      	245B3     	GND                 
          	               	P3_7      	245B3     	GND                 
          	               	P3_8      	245B3     	GND                 
          	               	P4_1      	245B3     	P12V_PSU            
          	               	P4_2      	245B3     	P12V_PSU            
          	               	P4_3      	245B3     	P12V_PSU            
          	               	P4_4      	245B3     	P12V_PSU            
          	               	P4_5      	245B3     	P12V_PSU            
          	               	P4_6      	245B3     	P12V_PSU            
          	               	P4_7      	245B3     	P12V_PSU            
          	               	P4_8      	245B3     	P12V_PSU            
          	               	P5_1      	245B3     	P12V_PSU            
          	               	P5_2      	245B3     	P12V_PSU            
          	               	P5_3      	245B3     	P12V_PSU            
          	               	P5_4      	245B3     	P12V_PSU            
          	               	P5_5      	245B3     	P12V_PSU            
          	               	P5_6      	245B3     	P12V_PSU            
          	               	P5_7      	245B3     	P12V_PSU            
          	               	P5_8      	245B3     	P12V_PSU            
          	               	P6_1      	245B3     	P12V_PSU            
          	               	P6_2      	245B3     	P12V_PSU            
          	               	P6_3      	245B3     	P12V_PSU            
          	               	P6_4      	245B3     	P12V_PSU            
          	               	P6_5      	245B3     	P12V_PSU            
          	               	P6_6      	245B3     	P12V_PSU            
          	               	P6_7      	245B3     	P12V_PSU            
          	               	P6_8      	245B3     	P12V_PSU            

J59       	SCONN75K_APCI0155P004A	          	          	                    
          	               	1         	190B3     	PCIE_M2_SSD0_PRSNT_N
          	               	2         	190B3     	P3V3_M2_0           
          	               	3         	190B3     	GND                 
          	               	4         	190B3     	P3V3_M2_0           
          	               	5         	190B3     	P3E_PCH_M2_RX_DN<0> 
          	               	6         	190B3     	NC_M2_0_NC1         
          	               	7         	190B3     	P3E_PCH_M2_RX_DP<0> 
          	               	8         	190B3     	NC_M2_0_NC2         
          	               	9         	190B3     	GND                 
          	               	10        	190B3     	LED_M2_SSD_0_ACT_N  
          	               	11        	190B3     	P3E_PCH_M2_TX_C_DP<0>
          	               	12        	190B3     	P3V3_M2_0           
          	               	13        	190B3     	P3E_PCH_M2_TX_C_DN<0>
          	               	14        	190B3     	P3V3_M2_0           
          	               	15        	190B3     	GND                 
          	               	16        	190B3     	P3V3_M2_0           
          	               	17        	190B3     	P3E_PCH_M2_RX_DN<1> 
          	               	18        	190B3     	P3V3_M2_0           
          	               	19        	190B3     	P3E_PCH_M2_RX_DP<1> 
          	               	20        	190B3     	NC_M2_0_NC3         
          	               	21        	190B3     	GND                 
          	               	22        	190B3     	NC_M2_0_NC4         
          	               	23        	190B3     	P3E_PCH_M2_TX_C_DP<1>
          	               	24        	190B3     	NC_M2_0_NC5         
          	               	25        	190B3     	P3E_PCH_M2_TX_C_DN<1>
          	               	26        	190B3     	NC_M2_0_NC6         
          	               	27        	190B3     	GND                 
          	               	28        	190B3     	NC_M2_0_NC7         
          	               	29        	190B3     	P3E_PCH_M2_RX_DN<2> 
          	               	30        	190B3     	NC_M2_0_NC8         
          	               	31        	190B3     	P3E_PCH_M2_RX_DP<2> 
          	               	32        	190B3     	NC_M2_0_NC9         
          	               	33        	190B3     	GND                 
          	               	34        	190B3     	NC_M2_0_NC10        
          	               	35        	190B3     	P3E_PCH_M2_TX_C_DP<2>
          	               	36        	190B3     	NC_M2_0_NC11        
          	               	37        	190B3     	P3E_PCH_M2_TX_C_DN<2>
          	               	38        	190B3     	PD_M2_0_DEVSLP      
          	               	39        	190B3     	GND                 
          	               	40        	190B3     	SMB_M2_P0_1V8AUX_SCL
          	               	41        	190B3     	P3E_PCH_M2_RX_DN<3> 
          	               	42        	190B3     	SMB_M2_P0_1V8AUX_SDA
          	               	43        	190B3     	P3E_PCH_M2_RX_DP<3> 
          	               	44        	190B3     	NC_M2_0_NC14        
          	               	45        	190B3     	GND                 
          	               	46        	190B3     	NC_M2_0_NC15        
          	               	47        	190B3     	P3E_PCH_M2_TX_C_DP<3>
          	               	48        	190B3     	NC_M2_0_NC16        
          	               	49        	190B3     	P3E_PCH_M2_TX_C_DN<3>
          	               	50        	190B3     	RST_PCIE_PCH_DEV_0_N
          	               	51        	190B3     	GND                 
          	               	52        	190B3     	M2_SSD0_CLKREQ_EN_N_BUF
          	               	53        	190B3     	CLK_100M_PE_M2_0_DN 
          	               	54        	190B3     	M2_0_PEWAKE_N       
          	               	55        	190B3     	CLK_100M_PE_M2_0_DP 
          	               	56        	190B3     	NC_M2_0_NC17        
          	               	57        	190B3     	GND                 
          	               	58        	190B3     	NC_M2_0_NC18        
          	               	67        	190B3     	NC_M2_0_NC19        
          	               	68        	190B3     	NC_M2_0_SUSCLK      
          	               	69        	190B3     	FM_M2_SSD_0_PEDET   
          	               	70        	190B3     	P3V3_M2_0           
          	               	71        	190B3     	GND                 
          	               	72        	190B3     	P3V3_M2_0           
          	               	73        	190B3     	GND                 
          	               	74        	190B3     	P3V3_M2_0           
          	               	75        	190B3     	GND                 
          	               	G1        	190B3     	GND                 
          	               	G2        	190B3     	GND                 

J63       	DELTA_L        	          	          	                    
          	               	1         	308B4     	DELTA_L_85_5INCH_TOP_DP
          	               	2         	308B4     	DELTA_L_85_5INCH_TOP_DN
          	               	3         	308B4     	DELTA_L_GND_1       

J64       	DELTA_L        	          	          	                    
          	               	1         	308B4     	DELTA_L_85_5INCH_BOT_DP
          	               	2         	308B4     	DELTA_L_85_5INCH_BOT_DN
          	               	3         	308B4     	DELTA_L_GND_1       

J65       	DELTA_L        	          	          	                    
          	               	1         	308B4     	DELTA_L_85_5INCH_IN1_DP
          	               	2         	308B4     	DELTA_L_85_5INCH_IN1_DN
          	               	3         	308B4     	DELTA_L_GND_1       

J66       	DELTA_L        	          	          	                    
          	               	1         	308B4     	DELTA_L_85_5INCH_IN2_DP
          	               	2         	308B4     	DELTA_L_85_5INCH_IN2_DN
          	               	3         	308B4     	DELTA_L_GND_1       

J67       	DELTA_L        	          	          	                    
          	               	1         	308B4     	DELTA_L_85_5INCH_IN3_DP
          	               	2         	308B4     	DELTA_L_85_5INCH_IN3_DN
          	               	3         	308B4     	DELTA_L_GND_1       

J68       	DELTA_L        	          	          	                    
          	               	1         	308A4     	DELTA_L_85_5INCH_IN4_DP
          	               	2         	308A4     	DELTA_L_85_5INCH_IN4_DN
          	               	3         	308A4     	DELTA_L_GND_1       

J69       	DELTA_L        	          	          	                    
          	               	1         	308B4     	DELTA_L_85_5INCH_TOP_DN
          	               	2         	308B4     	DELTA_L_85_5INCH_TOP_DP
          	               	3         	308B3     	DELTA_L_GND_1       

J70       	DELTA_L        	          	          	                    
          	               	1         	308B4     	DELTA_L_85_5INCH_BOT_DN
          	               	2         	308B4     	DELTA_L_85_5INCH_BOT_DP
          	               	3         	308B3     	DELTA_L_GND_1       

J71       	DELTA_L        	          	          	                    
          	               	1         	308B4     	DELTA_L_85_5INCH_IN1_DN
          	               	2         	308B4     	DELTA_L_85_5INCH_IN1_DP
          	               	3         	308B3     	DELTA_L_GND_1       

J72       	DELTA_L        	          	          	                    
          	               	1         	308B4     	DELTA_L_85_5INCH_IN2_DN
          	               	2         	308B4     	DELTA_L_85_5INCH_IN2_DP
          	               	3         	308B3     	DELTA_L_GND_1       

J73       	DELTA_L        	          	          	                    
          	               	1         	308B4     	DELTA_L_85_5INCH_IN3_DN
          	               	2         	308B4     	DELTA_L_85_5INCH_IN3_DP
          	               	3         	308B3     	DELTA_L_GND_1       

J74       	DELTA_L        	          	          	                    
          	               	1         	308A4     	DELTA_L_85_5INCH_IN4_DN
          	               	2         	308A4     	DELTA_L_85_5INCH_IN4_DP
          	               	3         	308A3     	DELTA_L_GND_1       

J75       	DELTA_L        	          	          	                    
          	               	1         	308B2     	DELTA_L_85_10INCH_TOP_DP
          	               	2         	308B2     	DELTA_L_85_10INCH_TOP_DN
          	               	3         	308B2     	DELTA_L_GND_1       

J76       	DELTA_L        	          	          	                    
          	               	1         	308B2     	DELTA_L_85_10INCH_BOT_DP
          	               	2         	308B2     	DELTA_L_85_10INCH_BOT_DN
          	               	3         	308B2     	DELTA_L_GND_1       

J77       	DELTA_L        	          	          	                    
          	               	1         	308B2     	DELTA_L_85_10INCH_IN1_DP
          	               	2         	308B2     	DELTA_L_85_10INCH_IN1_DN
          	               	3         	308B2     	DELTA_L_GND_1       

J78       	DELTA_L        	          	          	                    
          	               	1         	308B2     	DELTA_L_85_10INCH_IN2_DP
          	               	2         	308B2     	DELTA_L_85_10INCH_IN2_DN
          	               	3         	308B2     	DELTA_L_GND_1       

J79       	DELTA_L        	          	          	                    
          	               	1         	308B2     	DELTA_L_85_10INCH_IN3_DP
          	               	2         	308B2     	DELTA_L_85_10INCH_IN3_DN
          	               	3         	308B2     	DELTA_L_GND_1       

J80       	DELTA_L        	          	          	                    
          	               	1         	308A2     	DELTA_L_85_10INCH_IN4_DP
          	               	2         	308A2     	DELTA_L_85_10INCH_IN4_DN
          	               	3         	308A2     	DELTA_L_GND_1       

J81       	DELTA_L        	          	          	                    
          	               	1         	308B1     	DELTA_L_85_10INCH_TOP_DN
          	               	2         	308B1     	DELTA_L_85_10INCH_TOP_DP
          	               	3         	308B1     	DELTA_L_GND_1       

J82       	DELTA_L        	          	          	                    
          	               	1         	308B1     	DELTA_L_85_10INCH_BOT_DN
          	               	2         	308B1     	DELTA_L_85_10INCH_BOT_DP
          	               	3         	308B1     	DELTA_L_GND_1       

J83       	DELTA_L        	          	          	                    
          	               	1         	308B1     	DELTA_L_85_10INCH_IN1_DN
          	               	2         	308B1     	DELTA_L_85_10INCH_IN1_DP
          	               	3         	308B1     	DELTA_L_GND_1       

J84       	DELTA_L        	          	          	                    
          	               	1         	308B1     	DELTA_L_85_10INCH_IN2_DN
          	               	2         	308B1     	DELTA_L_85_10INCH_IN2_DP
          	               	3         	308B1     	DELTA_L_GND_1       

J85       	DELTA_L        	          	          	                    
          	               	1         	308B1     	DELTA_L_85_10INCH_IN3_DN
          	               	2         	308B1     	DELTA_L_85_10INCH_IN3_DP
          	               	3         	308B1     	DELTA_L_GND_1       

J86       	DELTA_L        	          	          	                    
          	               	1         	308A1     	DELTA_L_85_10INCH_IN4_DN
          	               	2         	308A1     	DELTA_L_85_10INCH_IN4_DP
          	               	3         	308A1     	DELTA_L_GND_1       

J90       	SCONN56_123276793	          	          	                    
          	               	A1        	191B2     	GND                 
          	               	A2        	191B2     	GND                 
          	               	A3        	191B2     	GND                 
          	               	A4        	191B2     	GND                 
          	               	A5        	191B2     	GND                 
          	               	A6        	191B2     	GND                 
          	               	A7        	191B2     	SMB_E1S_3V3AUX_ISO_SCL
          	               	A8        	191B2     	SMB_E1S_3V3AUX_ISO_SDA
          	               	A9        	191B2     	RST_SMB_E1S_0_N     
          	               	A10       	191B2     	E1S_0_LED_ACT_N     
          	               	A11       	191B2     	E1S_0_PERST1_CLKREQ_N
          	               	A12       	191B2     	E1S_0_PRSNT_N       
          	               	A13       	191B2     	GND                 
          	               	A14       	191B2     	TP_CLK_100M_E1S_0_DN
          	               	A15       	191B2     	TP_CLK_100M_E1S_0_DP
          	               	A16       	191B2     	GND                 
          	               	A17       	191B2     	P3E_PCH_E1S_RX_DP<0>
          	               	A18       	191B2     	P3E_PCH_E1S_RX_DN<0>
          	               	A19       	191B2     	GND                 
          	               	A20       	191B2     	P3E_PCH_E1S_RX_DN<1>
          	               	A21       	191B2     	P3E_PCH_E1S_RX_DP<1>
          	               	A22       	191B2     	GND                 
          	               	A23       	191B2     	P3E_PCH_E1S_RX_DN<2>
          	               	A24       	191B2     	P3E_PCH_E1S_RX_DP<2>
          	               	A25       	191B2     	GND                 
          	               	A26       	191B2     	P3E_PCH_E1S_RX_DN<3>
          	               	A27       	191B2     	P3E_PCH_E1S_RX_DP<3>
          	               	A28       	191B2     	GND                 
          	               	B1        	191B3     	P12V_E1S_0          
          	               	B2        	191B3     	P12V_E1S_0          
          	               	B3        	191B3     	P12V_E1S_0          
          	               	B4        	191B3     	P12V_E1S_0          
          	               	B5        	191B3     	P12V_E1S_0          
          	               	B6        	191B3     	P12V_E1S_0          
          	               	B7        	191B3     	TP_E1S_0_MFG        
          	               	B8        	191B3     	TP_E1S_0_RFU        
          	               	B9        	191B3     	PU_E1S_0_DUALPORT_EN_N
          	               	B10       	191B3     	RST_PCIE_PCH_E1S_PERST_N
          	               	B11       	191B3     	P3V3_E1S_0          
          	               	B12       	191B3     	E1S_0_PWRDIS        
          	               	B13       	191B3     	GND                 
          	               	B14       	191B3     	CLK_100M_E1S_0_DN   
          	               	B15       	191B3     	CLK_100M_E1S_0_DP   
          	               	B16       	191B3     	GND                 
          	               	B17       	191B3     	P3E_PCH_E1S_TX_C_DP<0>
          	               	B18       	191B3     	P3E_PCH_E1S_TX_C_DN<0>
          	               	B19       	191B3     	GND                 
          	               	B20       	191B3     	P3E_PCH_E1S_TX_C_DP<1>
          	               	B21       	191B3     	P3E_PCH_E1S_TX_C_DN<1>
          	               	B22       	191B3     	GND                 
          	               	B23       	191B3     	P3E_PCH_E1S_TX_C_DN<2>
          	               	B24       	191B3     	P3E_PCH_E1S_TX_C_DP<2>
          	               	B25       	191B3     	GND                 
          	               	B26       	191B3     	P3E_PCH_E1S_TX_C_DN<3>
          	               	B27       	191B3     	P3E_PCH_E1S_TX_C_DP<3>
          	               	B28       	191B3     	GND                 
          	               	G1        	191B2     	GND                 
          	               	G2        	191B3     	GND                 

J90_CON   	TP_TP_BOM ONLY 	          	          	                    
          	               	1         	311A4     	NC                  

J100      	SCONN20_513860200CV01	          	          	                    
          	               	1         	228B3     	SMB_SML0_ME_SCL     
          	               	2         	228B3     	GND                 
          	               	3         	228B3     	SMB_SML0_ME_SDA     
          	               	4         	228B3     	IRQ_SML0_ALERT_R1_N 
          	               	5         	228B3     	SMB_PMBUS_SML1_ME_SCL
          	               	6         	228B3     	GND                 
          	               	7         	228B3     	SMB_PMBUS_SML1_ME_SDA
          	               	8         	228B3     	IRQ_SML1_PMBUS_ALERT_R_N
          	               	9         	228B3     	RST_RSMRST_NM_HDR_N 
          	               	10        	228B3     	GND                 
          	               	11        	228B3     	SMB_HOST_ME_SCL     
          	               	12        	228B3     	GND                 
          	               	13        	228B3     	SMB_HOST_ME_SDA     
          	               	14        	228B3     	NC                  
          	               	15        	228B3     	GND                 
          	               	16        	228B3     	PECI_BMC_ME         
          	               	17        	228B3     	GND                 
          	               	18        	228B3     	PWRGD_PS_PWROK_ME_CONN
          	               	19        	228B3     	FM_BIOS_POST_CMPLT_HDR_N
          	               	20        	228B3     	NC                  

J104      	CONN14_210HP207GBR1	          	          	                    
          	               	1         	201B3     	PU_ESPI_ENABLE_STRAP
          	               	2         	201B2     	JTAG_TRC_PCH_PTI<6> 
          	               	3         	201B3     	PU_BIOS_RCVR_BOOT   
          	               	4         	201B2     	FM_PCH_BIOS_RCVR_MODE
          	               	5         	201B3     	PU_SWAP_OVERRIDE_N  
          	               	6         	201B2     	FM_ADR_COMPLETE     
          	               	7         	201B3     	PD_BIOS_IMAGE_SWAP_N
          	               	8         	201B2     	FM_BIOS_IMAGE_SWAP_N
          	               	9         	201B3     	PU_FLASH_SECURITY_STRAP
          	               	10        	201B2     	FM_FLASH_SECURITY_STRAP
          	               	11        	201B3     	PD_ME_RCVR_N        
          	               	12        	201B2     	FM_ME_RCVR_N        
          	               	13        	201B3     	PD_PASSWORD_CLEAR   
          	               	14        	201B2     	FM_PASSWORD_CLEAR_N 

J105      	CONN112_10137002101LF	          	          	                    
          	               	A1        	136B2     	GPU_3V3IO_RSVD4     
          	               	A2        	136B2     	GND                 
          	               	A3        	136B2     	GPU_WP_HW_CTRL_ISO  
          	               	A4        	136B2     	GND                 
          	               	A5        	136B4     	GPU_3V3IO_RSVD3     
          	               	A6        	136B4     	GND                 
          	               	A7        	136B4     	GPU_3V3IO_RSVD1     
          	               	A8        	136B4     	GND                 
          	               	B1        	136B2     	GND                 
          	               	B2        	136B2     	P5E_CPU0_PE3_RX_DP<6>
          	               	B3        	136B2     	GND                 
          	               	B4        	136B2     	P5E_CPU0_PE3_RX_DP<4>
          	               	B5        	136B4     	GND                 
          	               	B6        	136B4     	P5E_CPU0_PE3_RX_DN<2>
          	               	B7        	136B4     	GND                 
          	               	B8        	136B4     	P5E_CPU0_PE3_RX_DP<0>
          	               	C1        	136B2     	P5E_CPU0_PE3_RX_DP<7>
          	               	C2        	136B2     	P5E_CPU0_PE3_RX_DN<6>
          	               	C3        	136B2     	P5E_CPU0_PE3_RX_DP<5>
          	               	C4        	136B2     	P5E_CPU0_PE3_RX_DN<4>
          	               	C5        	136B4     	P5E_CPU0_PE3_RX_DN<3>
          	               	C6        	136B4     	P5E_CPU0_PE3_RX_DP<2>
          	               	C7        	136B4     	P5E_CPU0_PE3_RX_DN<1>
          	               	C8        	136B4     	P5E_CPU0_PE3_RX_DN<0>
          	               	D1        	136B2     	P5E_CPU0_PE3_RX_DN<7>
          	               	D2        	136B2     	GND                 
          	               	D3        	136B2     	P5E_CPU0_PE3_RX_DN<5>
          	               	D4        	136B2     	GND                 
          	               	D5        	136B4     	P5E_CPU0_PE3_RX_DP<3>
          	               	D6        	136B4     	GND                 
          	               	D7        	136B4     	P5E_CPU0_PE3_RX_DP<1>
          	               	D8        	136B4     	GND                 
          	               	E1        	136B2     	GND                 
          	               	E2        	136B2     	P5E_CPU0_PE2_RX_DP<6>
          	               	E3        	136B2     	GND                 
          	               	E4        	136B2     	P5E_CPU0_PE2_RX_DP<4>
          	               	E5        	136B4     	GND                 
          	               	E6        	136B4     	P5E_CPU0_PE2_RX_DP<2>
          	               	E7        	136B4     	GND                 
          	               	E8        	136B4     	P5E_CPU0_PE2_RX_DP<0>
          	               	F1        	136B2     	P5E_CPU0_PE2_RX_DP<7>
          	               	F2        	136B2     	P5E_CPU0_PE2_RX_DN<6>
          	               	F3        	136B2     	P5E_CPU0_PE2_RX_DP<5>
          	               	F4        	136B2     	P5E_CPU0_PE2_RX_DN<4>
          	               	F5        	136B4     	P5E_CPU0_PE2_RX_DP<3>
          	               	F6        	136B4     	P5E_CPU0_PE2_RX_DN<2>
          	               	F7        	136B4     	P5E_CPU0_PE2_RX_DP<1>
          	               	F8        	136B4     	P5E_CPU0_PE2_RX_DN<0>
          	               	G1        	136B2     	P5E_CPU0_PE2_RX_DN<7>
          	               	G2        	136B2     	GND                 
          	               	G3        	136B2     	P5E_CPU0_PE2_RX_DN<5>
          	               	G4        	136B2     	GND                 
          	               	G5        	136B4     	P5E_CPU0_PE2_RX_DN<3>
          	               	G6        	136B4     	GND                 
          	               	G7        	136B4     	P5E_CPU0_PE2_RX_DN<1>
          	               	G8        	136B4     	GND                 
          	               	H1        	136B2     	GND                 
          	               	H2        	136B2     	P5E_CPU0_PE3_TX_C_DN<6>
          	               	H3        	136B2     	GND                 
          	               	H4        	136B2     	P5E_CPU0_PE3_TX_C_DN<4>
          	               	H5        	136B4     	GND                 
          	               	H6        	136B4     	P5E_CPU0_PE3_TX_C_DN<2>
          	               	H7        	136B4     	GND                 
          	               	H8        	136B4     	P5E_CPU0_PE3_TX_C_DP<0>
          	               	I1        	136A2     	P5E_CPU0_PE3_TX_C_DN<7>
          	               	I2        	136B2     	P5E_CPU0_PE3_TX_C_DP<6>
          	               	I3        	136B2     	P5E_CPU0_PE3_TX_C_DN<5>
          	               	I4        	136B2     	P5E_CPU0_PE3_TX_C_DP<4>
          	               	I5        	136A4     	P5E_CPU0_PE3_TX_C_DN<3>
          	               	I6        	136B4     	P5E_CPU0_PE3_TX_C_DP<2>
          	               	I7        	136B4     	P5E_CPU0_PE3_TX_C_DN<1>
          	               	I8        	136B4     	P5E_CPU0_PE3_TX_C_DN<0>
          	               	J1        	136A2     	P5E_CPU0_PE3_TX_C_DP<7>
          	               	J2        	136B2     	GND                 
          	               	J3        	136B2     	P5E_CPU0_PE3_TX_C_DP<5>
          	               	J4        	136B2     	GND                 
          	               	J5        	136A4     	P5E_CPU0_PE3_TX_C_DP<3>
          	               	J6        	136B4     	GND                 
          	               	J7        	136B4     	P5E_CPU0_PE3_TX_C_DP<1>
          	               	J8        	136B4     	GND                 
          	               	K1        	136A2     	GND                 
          	               	K2        	136B2     	P5E_CPU0_PE2_TX_C_DP<6>
          	               	K3        	136B2     	GND                 
          	               	K4        	136B2     	P5E_CPU0_PE2_TX_C_DP<4>
          	               	K5        	136A4     	GND                 
          	               	K6        	136B4     	P5E_CPU0_PE2_TX_C_DP<2>
          	               	K7        	136B4     	GND                 
          	               	K8        	136B4     	P5E_CPU0_PE2_TX_C_DP<0>
          	               	L1        	136A2     	P5E_CPU0_PE2_TX_C_DP<7>
          	               	L2        	136B2     	P5E_CPU0_PE2_TX_C_DN<6>
          	               	L3        	136B2     	P5E_CPU0_PE2_TX_C_DP<5>
          	               	L4        	136B2     	P5E_CPU0_PE2_TX_C_DN<4>
          	               	L5        	136A4     	P5E_CPU0_PE2_TX_C_DP<3>
          	               	L6        	136B4     	P5E_CPU0_PE2_TX_C_DN<2>
          	               	L7        	136B4     	P5E_CPU0_PE2_TX_C_DP<1>
          	               	L8        	136B4     	P5E_CPU0_PE2_TX_C_DN<0>
          	               	M1        	136A2     	P5E_CPU0_PE2_TX_C_DN<7>
          	               	M2        	136B2     	GND                 
          	               	M3        	136B2     	P5E_CPU0_PE2_TX_C_DN<5>
          	               	M4        	136B2     	GND                 
          	               	M5        	136A4     	P5E_CPU0_PE2_TX_C_DN<3>
          	               	M6        	136B4     	GND                 
          	               	M7        	136B4     	P5E_CPU0_PE2_TX_C_DN<1>
          	               	M8        	136B4     	GND                 
          	               	N1        	136A2     	GND                 
          	               	N2        	136B2     	FM_SWB_PWR_EN_R_BUF 
          	               	N3        	136B2     	GND                 
          	               	N4        	136B2     	FM_SWB_BIC_READY_N  
          	               	N5        	136A4     	GND                 
          	               	N6        	136B4     	RST_SWB_BIC_BUF_N   
          	               	N7        	136B4     	GND                 
          	               	N8        	136B4     	RST_BMC_FROM_SWB_N  

J106      	CONN112_10137002101LF	          	          	                    
          	               	A1        	137B2     	PRSNT_CABLE_SWB_B1_N
          	               	A2        	137B2     	GND                 
          	               	A3        	137B2     	FM_SWB_PWRGD        
          	               	A4        	137B2     	GND                 
          	               	A5        	137B4     	NC_J106_A5          
          	               	A6        	137B4     	GND                 
          	               	A7        	137B4     	PRSNT_CABLE_GPU_A1_N
          	               	A8        	137B4     	GND                 
          	               	B1        	137B2     	GND                 
          	               	B2        	137B2     	P5E_CPU0_PE3_RX_DP<14>
          	               	B3        	137B2     	GND                 
          	               	B4        	137B2     	P5E_CPU0_PE3_RX_DP<12>
          	               	B5        	137B4     	GND                 
          	               	B6        	137B4     	P5E_CPU0_PE3_RX_DN<10>
          	               	B7        	137B4     	GND                 
          	               	B8        	137B4     	P5E_CPU0_PE3_RX_DN<8>
          	               	C1        	137B2     	P5E_CPU0_PE3_RX_DP<15>
          	               	C2        	137B2     	P5E_CPU0_PE3_RX_DN<14>
          	               	C3        	137B2     	P5E_CPU0_PE3_RX_DP<13>
          	               	C4        	137B2     	P5E_CPU0_PE3_RX_DN<12>
          	               	C5        	137B4     	P5E_CPU0_PE3_RX_DN<11>
          	               	C6        	137B4     	P5E_CPU0_PE3_RX_DP<10>
          	               	C7        	137B4     	P5E_CPU0_PE3_RX_DN<9>
          	               	C8        	137B4     	P5E_CPU0_PE3_RX_DP<8>
          	               	D1        	137B2     	P5E_CPU0_PE3_RX_DN<15>
          	               	D2        	137B2     	GND                 
          	               	D3        	137B2     	P5E_CPU0_PE3_RX_DN<13>
          	               	D4        	137B2     	GND                 
          	               	D5        	137B4     	P5E_CPU0_PE3_RX_DP<11>
          	               	D6        	137B4     	GND                 
          	               	D7        	137B4     	P5E_CPU0_PE3_RX_DP<9>
          	               	D8        	137B4     	GND                 
          	               	E1        	137B2     	GND                 
          	               	E2        	137B2     	P5E_CPU0_PE2_RX_DP<14>
          	               	E3        	137B2     	GND                 
          	               	E4        	137B2     	P5E_CPU0_PE2_RX_DP<12>
          	               	E5        	137B4     	GND                 
          	               	E6        	137B4     	P5E_CPU0_PE2_RX_DP<10>
          	               	E7        	137B4     	GND                 
          	               	E8        	137B4     	P5E_CPU0_PE2_RX_DP<8>
          	               	F1        	137B2     	P5E_CPU0_PE2_RX_DP<15>
          	               	F2        	137B2     	P5E_CPU0_PE2_RX_DN<14>
          	               	F3        	137B2     	P5E_CPU0_PE2_RX_DP<13>
          	               	F4        	137B2     	P5E_CPU0_PE2_RX_DN<12>
          	               	F5        	137B4     	P5E_CPU0_PE2_RX_DP<11>
          	               	F6        	137B4     	P5E_CPU0_PE2_RX_DN<10>
          	               	F7        	137B4     	P5E_CPU0_PE2_RX_DP<9>
          	               	F8        	137B4     	P5E_CPU0_PE2_RX_DN<8>
          	               	G1        	137A2     	P5E_CPU0_PE2_RX_DN<15>
          	               	G2        	137B2     	GND                 
          	               	G3        	137B2     	P5E_CPU0_PE2_RX_DN<13>
          	               	G4        	137B2     	GND                 
          	               	G5        	137B4     	P5E_CPU0_PE2_RX_DN<11>
          	               	G6        	137B4     	GND                 
          	               	G7        	137B4     	P5E_CPU0_PE2_RX_DN<9>
          	               	G8        	137B4     	GND                 
          	               	H1        	137A2     	GND                 
          	               	H2        	137B2     	P5E_CPU0_PE3_TX_C_DN<14>
          	               	H3        	137B2     	GND                 
          	               	H4        	137B2     	P5E_CPU0_PE3_TX_C_DN<12>
          	               	H5        	137A4     	GND                 
          	               	H6        	137B4     	P5E_CPU0_PE3_TX_C_DN<10>
          	               	H7        	137B4     	GND                 
          	               	H8        	137B4     	P5E_CPU0_PE3_TX_C_DN<8>
          	               	I1        	137A2     	P5E_CPU0_PE3_TX_C_DN<15>
          	               	I2        	137B2     	P5E_CPU0_PE3_TX_C_DP<14>
          	               	I3        	137B2     	P5E_CPU0_PE3_TX_C_DN<13>
          	               	I4        	137B2     	P5E_CPU0_PE3_TX_C_DP<12>
          	               	I5        	137A4     	P5E_CPU0_PE3_TX_C_DN<11>
          	               	I6        	137B4     	P5E_CPU0_PE3_TX_C_DP<10>
          	               	I7        	137B4     	P5E_CPU0_PE3_TX_C_DN<9>
          	               	I8        	137B4     	P5E_CPU0_PE3_TX_C_DP<8>
          	               	J1        	137A2     	P5E_CPU0_PE3_TX_C_DP<15>
          	               	J2        	137B2     	GND                 
          	               	J3        	137B2     	P5E_CPU0_PE3_TX_C_DP<13>
          	               	J4        	137B2     	GND                 
          	               	J5        	137A4     	P5E_CPU0_PE3_TX_C_DP<11>
          	               	J6        	137B4     	GND                 
          	               	J7        	137B4     	P5E_CPU0_PE3_TX_C_DP<9>
          	               	J8        	137B4     	GND                 
          	               	K1        	137A2     	GND                 
          	               	K2        	137B2     	P5E_CPU0_PE2_TX_C_DP<14>
          	               	K3        	137B2     	GND                 
          	               	K4        	137B2     	P5E_CPU0_PE2_TX_C_DP<12>
          	               	K5        	137A4     	GND                 
          	               	K6        	137B4     	P5E_CPU0_PE2_TX_C_DP<10>
          	               	K7        	137B4     	GND                 
          	               	K8        	137B4     	P5E_CPU0_PE2_TX_C_DP<8>
          	               	L1        	137A2     	P5E_CPU0_PE2_TX_C_DN<15>
          	               	L2        	137B2     	P5E_CPU0_PE2_TX_C_DN<14>
          	               	L3        	137B2     	P5E_CPU0_PE2_TX_C_DP<13>
          	               	L4        	137B2     	P5E_CPU0_PE2_TX_C_DN<12>
          	               	L5        	137A4     	P5E_CPU0_PE2_TX_C_DP<11>
          	               	L6        	137B4     	P5E_CPU0_PE2_TX_C_DN<10>
          	               	L7        	137B4     	P5E_CPU0_PE2_TX_C_DP<9>
          	               	L8        	137B4     	P5E_CPU0_PE2_TX_C_DN<8>
          	               	M1        	137A2     	P5E_CPU0_PE2_TX_C_DP<15>
          	               	M2        	137B2     	GND                 
          	               	M3        	137B2     	P5E_CPU0_PE2_TX_C_DN<13>
          	               	M4        	137B2     	GND                 
          	               	M5        	137A4     	P5E_CPU0_PE2_TX_C_DN<11>
          	               	M6        	137B4     	GND                 
          	               	M7        	137B4     	P5E_CPU0_PE2_TX_C_DN<9>
          	               	M8        	137B4     	GND                 
          	               	N1        	137A2     	GND                 
          	               	N2        	137B2     	I3C_BMC_SWB_BUF_SDA 
          	               	N3        	137B2     	GND                 
          	               	N4        	137B2     	I3C_BMC_SWB_BUF_SCL 
          	               	N5        	137A4     	GND                 
          	               	N6        	137B4     	UART_BMC_BIC_RX     
          	               	N7        	137B4     	GND                 
          	               	N8        	137B4     	UART_BMC_BIC_TX     

J107      	CONN112_10137002101LF	          	          	                    
          	               	A1        	138B2     	NC_J107_A1          
          	               	A2        	138B2     	GND                 
          	               	A3        	138B2     	NC_J107_A3          
          	               	A4        	138B2     	GND                 
          	               	A5        	138B4     	NC_J107_A5          
          	               	A6        	138B4     	GND                 
          	               	A7        	138B4     	SWB_HSC_PWRGD       
          	               	A8        	138B4     	GND                 
          	               	B1        	138B2     	GND                 
          	               	B2        	138B2     	P5E_CPU0_PE0_RX_DN<6>
          	               	B3        	138B2     	GND                 
          	               	B4        	138B2     	P5E_CPU0_PE0_RX_DN<4>
          	               	B5        	138B4     	GND                 
          	               	B6        	138B4     	P5E_CPU0_PE0_RX_DN<2>
          	               	B7        	138B4     	GND                 
          	               	B8        	138B4     	P5E_CPU0_PE0_RX_DN<0>
          	               	C1        	138B2     	P5E_CPU0_PE0_RX_DN<7>
          	               	C2        	138B2     	P5E_CPU0_PE0_RX_DP<6>
          	               	C3        	138B2     	P5E_CPU0_PE0_RX_DN<5>
          	               	C4        	138B2     	P5E_CPU0_PE0_RX_DP<4>
          	               	C5        	138B4     	P5E_CPU0_PE0_RX_DP<3>
          	               	C6        	138B4     	P5E_CPU0_PE0_RX_DP<2>
          	               	C7        	138B4     	P5E_CPU0_PE0_RX_DP<1>
          	               	C8        	138B4     	P5E_CPU0_PE0_RX_DP<0>
          	               	D1        	138B2     	P5E_CPU0_PE0_RX_DP<7>
          	               	D2        	138B2     	GND                 
          	               	D3        	138B2     	P5E_CPU0_PE0_RX_DP<5>
          	               	D4        	138B2     	GND                 
          	               	D5        	138B4     	P5E_CPU0_PE0_RX_DN<3>
          	               	D6        	138B4     	GND                 
          	               	D7        	138B4     	P5E_CPU0_PE0_RX_DN<1>
          	               	D8        	138B4     	GND                 
          	               	E1        	138B2     	GND                 
          	               	E2        	138B2     	P5E_CPU0_PE4_RX_DP<9>
          	               	E3        	138B2     	GND                 
          	               	E4        	138B2     	P5E_CPU0_PE4_RX_DP<11>
          	               	E5        	138B4     	GND                 
          	               	E6        	138B4     	P5E_CPU0_PE4_RX_DP<13>
          	               	E7        	138B4     	GND                 
          	               	E8        	138B4     	P5E_CPU0_PE4_RX_DP<15>
          	               	F1        	138B2     	P5E_CPU0_PE4_RX_DN<8>
          	               	F2        	138B2     	P5E_CPU0_PE4_RX_DN<9>
          	               	F3        	138B2     	P5E_CPU0_PE4_RX_DN<10>
          	               	F4        	138B2     	P5E_CPU0_PE4_RX_DN<11>
          	               	F5        	138B4     	P5E_CPU0_PE4_RX_DN<12>
          	               	F6        	138B4     	P5E_CPU0_PE4_RX_DN<13>
          	               	F7        	138B4     	P5E_CPU0_PE4_RX_DN<14>
          	               	F8        	138B4     	P5E_CPU0_PE4_RX_DN<15>
          	               	G1        	138B2     	P5E_CPU0_PE4_RX_DP<8>
          	               	G2        	138B2     	GND                 
          	               	G3        	138B2     	P5E_CPU0_PE4_RX_DP<10>
          	               	G4        	138B2     	GND                 
          	               	G5        	138B4     	P5E_CPU0_PE4_RX_DP<12>
          	               	G6        	138B4     	GND                 
          	               	G7        	138B4     	P5E_CPU0_PE4_RX_DP<14>
          	               	G8        	138B4     	GND                 
          	               	H1        	138B2     	GND                 
          	               	H2        	138B2     	P5E_CPU0_PE0_TX_C_DN<6>
          	               	H3        	138B2     	GND                 
          	               	H4        	138B2     	P5E_CPU0_PE0_TX_C_DN<4>
          	               	H5        	138B4     	GND                 
          	               	H6        	138B4     	P5E_CPU0_PE0_TX_C_DN<2>
          	               	H7        	138B4     	GND                 
          	               	H8        	138B4     	P5E_CPU0_PE0_TX_C_DN<0>
          	               	I1        	138B2     	P5E_CPU0_PE0_TX_C_DN<7>
          	               	I2        	138B2     	P5E_CPU0_PE0_TX_C_DP<6>
          	               	I3        	138B2     	P5E_CPU0_PE0_TX_C_DN<5>
          	               	I4        	138B2     	P5E_CPU0_PE0_TX_C_DP<4>
          	               	I5        	138B4     	P5E_CPU0_PE0_TX_C_DN<3>
          	               	I6        	138B4     	P5E_CPU0_PE0_TX_C_DP<2>
          	               	I7        	138B4     	P5E_CPU0_PE0_TX_C_DN<1>
          	               	I8        	138B4     	P5E_CPU0_PE0_TX_C_DP<0>
          	               	J1        	138A2     	P5E_CPU0_PE0_TX_C_DP<7>
          	               	J2        	138B2     	GND                 
          	               	J3        	138B2     	P5E_CPU0_PE0_TX_C_DP<5>
          	               	J4        	138B2     	GND                 
          	               	J5        	138A4     	P5E_CPU0_PE0_TX_C_DP<3>
          	               	J6        	138B4     	GND                 
          	               	J7        	138B4     	P5E_CPU0_PE0_TX_C_DP<1>
          	               	J8        	138B4     	GND                 
          	               	K1        	138A2     	GND                 
          	               	K2        	138B2     	P5E_CPU0_PE4_TX_C_DN<9>
          	               	K3        	138B2     	GND                 
          	               	K4        	138B2     	P5E_CPU0_PE4_TX_C_DP<11>
          	               	K5        	138A4     	GND                 
          	               	K6        	138B4     	P5E_CPU0_PE4_TX_C_DN<13>
          	               	K7        	138B4     	GND                 
          	               	K8        	138B4     	P5E_CPU0_PE4_TX_C_DN<15>
          	               	L1        	138A2     	P5E_CPU0_PE4_TX_C_DN<8>
          	               	L2        	138B2     	P5E_CPU0_PE4_TX_C_DP<9>
          	               	L3        	138B2     	P5E_CPU0_PE4_TX_C_DN<10>
          	               	L4        	138B2     	P5E_CPU0_PE4_TX_C_DN<11>
          	               	L5        	138A4     	P5E_CPU0_PE4_TX_C_DN<12>
          	               	L6        	138B4     	P5E_CPU0_PE4_TX_C_DP<13>
          	               	L7        	138B4     	P5E_CPU0_PE4_TX_C_DN<14>
          	               	L8        	138B4     	P5E_CPU0_PE4_TX_C_DP<15>
          	               	M1        	138A2     	P5E_CPU0_PE4_TX_C_DP<8>
          	               	M2        	138B2     	GND                 
          	               	M3        	138B2     	P5E_CPU0_PE4_TX_C_DP<10>
          	               	M4        	138B2     	GND                 
          	               	M5        	138A4     	P5E_CPU0_PE4_TX_C_DP<12>
          	               	M6        	138B4     	GND                 
          	               	M7        	138B4     	P5E_CPU0_PE4_TX_C_DP<14>
          	               	M8        	138B4     	GND                 
          	               	N1        	138A2     	GND                 
          	               	N2        	138B2     	PRSNT_CABLE_SWB_B2_N
          	               	N3        	138B2     	GND                 
          	               	N4        	138B2     	NC_J107_N4          
          	               	N5        	138A4     	GND                 
          	               	N6        	138B4     	NC_J107_N6          
          	               	N7        	138B4     	GND                 
          	               	N8        	138B4     	SWB_HSC_EN_BUF      

J108      	CONN112_10137002101LF	          	          	                    
          	               	A1        	139B2     	GPU_3V3IO_RSVD3_FFU 
          	               	A2        	139B2     	GND                 
          	               	A3        	139B2     	PRSNT_CABLE_GPU_A2_N
          	               	A4        	139B2     	GND                 
          	               	A5        	139B4     	GPU_3V3IO_RSVD5_FFU 
          	               	A6        	139B4     	GND                 
          	               	A7        	139B4     	GPU_FPGA_OVERT_N    
          	               	A8        	139B4     	GND                 
          	               	B1        	139B2     	GND                 
          	               	B2        	139B2     	P5E_CPU0_PE0_RX_DN<14>
          	               	B3        	139B2     	GND                 
          	               	B4        	139B2     	P5E_CPU0_PE0_RX_DN<12>
          	               	B5        	139B4     	GND                 
          	               	B6        	139B4     	P5E_CPU0_PE0_RX_DN<10>
          	               	B7        	139B4     	GND                 
          	               	B8        	139B4     	P5E_CPU0_PE0_RX_DN<8>
          	               	C1        	139B2     	P5E_CPU0_PE0_RX_DN<15>
          	               	C2        	139B2     	P5E_CPU0_PE0_RX_DP<14>
          	               	C3        	139B2     	P5E_CPU0_PE0_RX_DN<13>
          	               	C4        	139B2     	P5E_CPU0_PE0_RX_DP<12>
          	               	C5        	139B4     	P5E_CPU0_PE0_RX_DP<11>
          	               	C6        	139B4     	P5E_CPU0_PE0_RX_DP<10>
          	               	C7        	139B4     	P5E_CPU0_PE0_RX_DN<9>
          	               	C8        	139B4     	P5E_CPU0_PE0_RX_DP<8>
          	               	D1        	139B2     	P5E_CPU0_PE0_RX_DP<15>
          	               	D2        	139B2     	GND                 
          	               	D3        	139B2     	P5E_CPU0_PE0_RX_DP<13>
          	               	D4        	139B2     	GND                 
          	               	D5        	139B4     	P5E_CPU0_PE0_RX_DN<11>
          	               	D6        	139B4     	GND                 
          	               	D7        	139B4     	P5E_CPU0_PE0_RX_DP<9>
          	               	D8        	139B4     	GND                 
          	               	E1        	139B2     	GND                 
          	               	E2        	139B2     	P5E_CPU0_PE4_RX_DP<1>
          	               	E3        	139B2     	GND                 
          	               	E4        	139B2     	P5E_CPU0_PE4_RX_DP<3>
          	               	E5        	139B4     	GND                 
          	               	E6        	139B4     	P5E_CPU0_PE4_RX_DP<5>
          	               	E7        	139B4     	GND                 
          	               	E8        	139B4     	P5E_CPU0_PE4_RX_DP<7>
          	               	F1        	139B2     	P5E_CPU0_PE4_RX_DN<0>
          	               	F2        	139B2     	P5E_CPU0_PE4_RX_DN<1>
          	               	F3        	139B2     	P5E_CPU0_PE4_RX_DN<2>
          	               	F4        	139B2     	P5E_CPU0_PE4_RX_DN<3>
          	               	F5        	139B4     	P5E_CPU0_PE4_RX_DN<4>
          	               	F6        	139B4     	P5E_CPU0_PE4_RX_DN<5>
          	               	F7        	139B4     	P5E_CPU0_PE4_RX_DN<6>
          	               	F8        	139B4     	P5E_CPU0_PE4_RX_DN<7>
          	               	G1        	139A2     	P5E_CPU0_PE4_RX_DP<0>
          	               	G2        	139B2     	GND                 
          	               	G3        	139B2     	P5E_CPU0_PE4_RX_DP<2>
          	               	G4        	139B2     	GND                 
          	               	G5        	139B4     	P5E_CPU0_PE4_RX_DP<4>
          	               	G6        	139B4     	GND                 
          	               	G7        	139B4     	P5E_CPU0_PE4_RX_DP<6>
          	               	G8        	139B4     	GND                 
          	               	H1        	139A2     	GND                 
          	               	H2        	139B2     	P5E_CPU0_PE0_TX_C_DN<14>
          	               	H3        	139B2     	GND                 
          	               	H4        	139B2     	P5E_CPU0_PE0_TX_C_DN<12>
          	               	H5        	139A4     	GND                 
          	               	H6        	139B4     	P5E_CPU0_PE0_TX_C_DN<10>
          	               	H7        	139B4     	GND                 
          	               	H8        	139B4     	P5E_CPU0_PE0_TX_C_DN<8>
          	               	I1        	139A2     	P5E_CPU0_PE0_TX_C_DN<15>
          	               	I2        	139B2     	P5E_CPU0_PE0_TX_C_DP<14>
          	               	I3        	139B2     	P5E_CPU0_PE0_TX_C_DN<13>
          	               	I4        	139B2     	P5E_CPU0_PE0_TX_C_DP<12>
          	               	I5        	139A4     	P5E_CPU0_PE0_TX_C_DN<11>
          	               	I6        	139B4     	P5E_CPU0_PE0_TX_C_DP<10>
          	               	I7        	139B4     	P5E_CPU0_PE0_TX_C_DN<9>
          	               	I8        	139B4     	P5E_CPU0_PE0_TX_C_DP<8>
          	               	J1        	139A2     	P5E_CPU0_PE0_TX_C_DP<15>
          	               	J2        	139B2     	GND                 
          	               	J3        	139B2     	P5E_CPU0_PE0_TX_C_DP<13>
          	               	J4        	139B2     	GND                 
          	               	J5        	139A4     	P5E_CPU0_PE0_TX_C_DP<11>
          	               	J6        	139B4     	GND                 
          	               	J7        	139B4     	P5E_CPU0_PE0_TX_C_DP<9>
          	               	J8        	139B4     	GND                 
          	               	K1        	139A2     	GND                 
          	               	K2        	139B2     	P5E_CPU0_PE4_TX_C_DP<1>
          	               	K3        	139B2     	GND                 
          	               	K4        	139B2     	P5E_CPU0_PE4_TX_C_DN<3>
          	               	K5        	139A4     	GND                 
          	               	K6        	139B4     	P5E_CPU0_PE4_TX_C_DN<5>
          	               	K7        	139B4     	GND                 
          	               	K8        	139B4     	P5E_CPU0_PE4_TX_C_DN<7>
          	               	L1        	139A2     	P5E_CPU0_PE4_TX_C_DN<0>
          	               	L2        	139B2     	P5E_CPU0_PE4_TX_C_DN<1>
          	               	L3        	139B2     	P5E_CPU0_PE4_TX_C_DN<2>
          	               	L4        	139B2     	P5E_CPU0_PE4_TX_C_DP<3>
          	               	L5        	139A4     	P5E_CPU0_PE4_TX_C_DN<4>
          	               	L6        	139B4     	P5E_CPU0_PE4_TX_C_DP<5>
          	               	L7        	139B4     	P5E_CPU0_PE4_TX_C_DN<6>
          	               	L8        	139B4     	P5E_CPU0_PE4_TX_C_DP<7>
          	               	M1        	139A2     	P5E_CPU0_PE4_TX_C_DP<0>
          	               	M2        	139B2     	GND                 
          	               	M3        	139B2     	P5E_CPU0_PE4_TX_C_DP<2>
          	               	M4        	139B2     	GND                 
          	               	M5        	139A4     	P5E_CPU0_PE4_TX_C_DP<4>
          	               	M6        	139B4     	GND                 
          	               	M7        	139B4     	P5E_CPU0_PE4_TX_C_DP<6>
          	               	M8        	139B4     	GND                 
          	               	N1        	139A2     	GND                 
          	               	N2        	139B2     	NC_J108_N2          
          	               	N3        	139B2     	GND                 
          	               	N4        	139B2     	NC_J108_N4          
          	               	N5        	139A4     	GND                 
          	               	N6        	139B4     	NC_J108_N6          
          	               	N7        	139B4     	GND                 
          	               	N8        	139B4     	PRSNT_CABLE_GPU_A3_N

J109      	CONN112_10137002101LF	          	          	                    
          	               	A1        	140B2     	BMC_MONITER_BUF     
          	               	A2        	140B2     	GND                 
          	               	A3        	140B2     	BIC_MONITER         
          	               	A4        	140B2     	GND                 
          	               	A5        	140B4     	SMB_BMC_SWB_BUF_SCL 
          	               	A6        	140B4     	GND                 
          	               	A7        	140B4     	SMB_BMC_SWB_BUF_SDA 
          	               	A8        	140B4     	GND                 
          	               	B1        	140B2     	GND                 
          	               	B2        	140B2     	P5E_CPU1_PE3_RX_DP<6>
          	               	B3        	140B2     	GND                 
          	               	B4        	140B2     	P5E_CPU1_PE3_RX_DP<4>
          	               	B5        	140B4     	GND                 
          	               	B6        	140B4     	P5E_CPU1_PE3_RX_DN<2>
          	               	B7        	140B4     	GND                 
          	               	B8        	140B4     	P5E_CPU1_PE3_RX_DP<0>
          	               	C1        	140B2     	P5E_CPU1_PE3_RX_DP<7>
          	               	C2        	140B2     	P5E_CPU1_PE3_RX_DN<6>
          	               	C3        	140B2     	P5E_CPU1_PE3_RX_DP<5>
          	               	C4        	140B2     	P5E_CPU1_PE3_RX_DN<4>
          	               	C5        	140B4     	P5E_CPU1_PE3_RX_DN<3>
          	               	C6        	140B4     	P5E_CPU1_PE3_RX_DP<2>
          	               	C7        	140B4     	P5E_CPU1_PE3_RX_DN<1>
          	               	C8        	140B4     	P5E_CPU1_PE3_RX_DN<0>
          	               	D1        	140B2     	P5E_CPU1_PE3_RX_DN<7>
          	               	D2        	140B2     	GND                 
          	               	D3        	140B2     	P5E_CPU1_PE3_RX_DN<5>
          	               	D4        	140B2     	GND                 
          	               	D5        	140B4     	P5E_CPU1_PE3_RX_DP<3>
          	               	D6        	140B4     	GND                 
          	               	D7        	140B4     	P5E_CPU1_PE3_RX_DP<1>
          	               	D8        	140B4     	GND                 
          	               	E1        	140B2     	GND                 
          	               	E2        	140B2     	P5E_CPU1_PE2_RX_DP<6>
          	               	E3        	140B2     	GND                 
          	               	E4        	140B2     	P5E_CPU1_PE2_RX_DP<4>
          	               	E5        	140B4     	GND                 
          	               	E6        	140B4     	P5E_CPU1_PE2_RX_DP<2>
          	               	E7        	140B4     	GND                 
          	               	E8        	140B4     	P5E_CPU1_PE2_RX_DP<0>
          	               	F1        	140B2     	P5E_CPU1_PE2_RX_DP<7>
          	               	F2        	140B2     	P5E_CPU1_PE2_RX_DN<6>
          	               	F3        	140B2     	P5E_CPU1_PE2_RX_DP<5>
          	               	F4        	140B2     	P5E_CPU1_PE2_RX_DN<4>
          	               	F5        	140B4     	P5E_CPU1_PE2_RX_DP<3>
          	               	F6        	140B4     	P5E_CPU1_PE2_RX_DN<2>
          	               	F7        	140B4     	P5E_CPU1_PE2_RX_DP<1>
          	               	F8        	140B4     	P5E_CPU1_PE2_RX_DN<0>
          	               	G1        	140B2     	P5E_CPU1_PE2_RX_DN<7>
          	               	G2        	140B2     	GND                 
          	               	G3        	140B2     	P5E_CPU1_PE2_RX_DN<5>
          	               	G4        	140B2     	GND                 
          	               	G5        	140B4     	P5E_CPU1_PE2_RX_DN<3>
          	               	G6        	140B4     	GND                 
          	               	G7        	140B4     	P5E_CPU1_PE2_RX_DN<1>
          	               	G8        	140B4     	GND                 
          	               	H1        	140A2     	GND                 
          	               	H2        	140B2     	P5E_CPU1_PE3_TX_C_DN<6>
          	               	H3        	140B2     	GND                 
          	               	H4        	140B2     	P5E_CPU1_PE3_TX_C_DN<4>
          	               	H5        	140B4     	GND                 
          	               	H6        	140B4     	P5E_CPU1_PE3_TX_C_DN<2>
          	               	H7        	140B4     	GND                 
          	               	H8        	140B4     	P5E_CPU1_PE3_TX_C_DP<0>
          	               	I1        	140A2     	P5E_CPU1_PE3_TX_C_DN<7>
          	               	I2        	140B2     	P5E_CPU1_PE3_TX_C_DP<6>
          	               	I3        	140B2     	P5E_CPU1_PE3_TX_C_DN<5>
          	               	I4        	140B2     	P5E_CPU1_PE3_TX_C_DP<4>
          	               	I5        	140A4     	P5E_CPU1_PE3_TX_C_DN<3>
          	               	I6        	140B4     	P5E_CPU1_PE3_TX_C_DP<2>
          	               	I7        	140B4     	P5E_CPU1_PE3_TX_C_DN<1>
          	               	I8        	140B4     	P5E_CPU1_PE3_TX_C_DN<0>
          	               	J1        	140A2     	P5E_CPU1_PE3_TX_C_DP<7>
          	               	J2        	140B2     	GND                 
          	               	J3        	140B2     	P5E_CPU1_PE3_TX_C_DP<5>
          	               	J4        	140B2     	GND                 
          	               	J5        	140A4     	P5E_CPU1_PE3_TX_C_DP<3>
          	               	J6        	140B4     	GND                 
          	               	J7        	140B4     	P5E_CPU1_PE3_TX_C_DP<1>
          	               	J8        	140B4     	GND                 
          	               	K1        	140A2     	GND                 
          	               	K2        	140B2     	P5E_CPU1_PE2_TX_C_DP<6>
          	               	K3        	140B2     	GND                 
          	               	K4        	140B2     	P5E_CPU1_PE2_TX_C_DP<4>
          	               	K5        	140A4     	GND                 
          	               	K6        	140B4     	P5E_CPU1_PE2_TX_C_DP<2>
          	               	K7        	140B4     	GND                 
          	               	K8        	140B4     	P5E_CPU1_PE2_TX_C_DP<0>
          	               	L1        	140A2     	P5E_CPU1_PE2_TX_C_DP<7>
          	               	L2        	140B2     	P5E_CPU1_PE2_TX_C_DN<6>
          	               	L3        	140B2     	P5E_CPU1_PE2_TX_C_DP<5>
          	               	L4        	140B2     	P5E_CPU1_PE2_TX_C_DN<4>
          	               	L5        	140A4     	P5E_CPU1_PE2_TX_C_DP<3>
          	               	L6        	140B4     	P5E_CPU1_PE2_TX_C_DN<2>
          	               	L7        	140B4     	P5E_CPU1_PE2_TX_C_DP<1>
          	               	L8        	140B4     	P5E_CPU1_PE2_TX_C_DN<0>
          	               	M1        	140A2     	P5E_CPU1_PE2_TX_C_DN<7>
          	               	M2        	140B2     	GND                 
          	               	M3        	140B2     	P5E_CPU1_PE2_TX_C_DN<5>
          	               	M4        	140B2     	GND                 
          	               	M5        	140A4     	P5E_CPU1_PE2_TX_C_DN<3>
          	               	M6        	140B4     	GND                 
          	               	M7        	140B4     	P5E_CPU1_PE2_TX_C_DN<1>
          	               	M8        	140B4     	GND                 
          	               	N1        	140A2     	GND                 
          	               	N2        	140B2     	GPU_FPGA_EROT_FATALERR_N
          	               	N3        	140B2     	GND                 
          	               	N4        	140B2     	GPU_3V3IO_RSVD0_FFU 
          	               	N5        	140A4     	GND                 
          	               	N6        	140B4     	GPU_3V3IO_RSVD1_FFU 
          	               	N7        	140B4     	GND                 
          	               	N8        	140B4     	PRSNT_CABLE_GPU_B3_N

J110      	CONN112_10137002101LF	          	          	                    
          	               	A1        	141B1     	GPU_FPGA_EROT_RECOV_BUF_N
          	               	A2        	141B1     	GND                 
          	               	A3        	141B1     	GPU_HMC_PRSNT_N     
          	               	A4        	141B1     	GND                 
          	               	A5        	141B4     	GPU_BASE_HMC_READY  
          	               	A6        	141B4     	GND                 
          	               	A7        	141B4     	GPU_BASE_STBY_EN_BUF
          	               	A8        	141B4     	GND                 
          	               	B1        	141B1     	GND                 
          	               	B2        	141B1     	P5E_CPU1_PE3_RX_DP<14>
          	               	B3        	141B1     	GND                 
          	               	B4        	141B1     	P5E_CPU1_PE3_RX_DP<12>
          	               	B5        	141B4     	GND                 
          	               	B6        	141B4     	P5E_CPU1_PE3_RX_DN<10>
          	               	B7        	141B4     	GND                 
          	               	B8        	141B4     	P5E_CPU1_PE3_RX_DN<8>
          	               	C1        	141B1     	P5E_CPU1_PE3_RX_DP<15>
          	               	C2        	141B1     	P5E_CPU1_PE3_RX_DN<14>
          	               	C3        	141B1     	P5E_CPU1_PE3_RX_DP<13>
          	               	C4        	141B1     	P5E_CPU1_PE3_RX_DN<12>
          	               	C5        	141B4     	P5E_CPU1_PE3_RX_DN<11>
          	               	C6        	141B4     	P5E_CPU1_PE3_RX_DP<10>
          	               	C7        	141B4     	P5E_CPU1_PE3_RX_DN<9>
          	               	C8        	141B4     	P5E_CPU1_PE3_RX_DP<8>
          	               	D1        	141B1     	P5E_CPU1_PE3_RX_DN<15>
          	               	D2        	141B1     	GND                 
          	               	D3        	141B1     	P5E_CPU1_PE3_RX_DN<13>
          	               	D4        	141B1     	GND                 
          	               	D5        	141B4     	P5E_CPU1_PE3_RX_DP<11>
          	               	D6        	141B4     	GND                 
          	               	D7        	141B4     	P5E_CPU1_PE3_RX_DP<9>
          	               	D8        	141B4     	GND                 
          	               	E1        	141B1     	GND                 
          	               	E2        	141B1     	P5E_CPU1_PE2_RX_DP<14>
          	               	E3        	141B1     	GND                 
          	               	E4        	141B1     	P5E_CPU1_PE2_RX_DP<12>
          	               	E5        	141B4     	GND                 
          	               	E6        	141B4     	P5E_CPU1_PE2_RX_DP<10>
          	               	E7        	141B4     	GND                 
          	               	E8        	141B4     	P5E_CPU1_PE2_RX_DP<8>
          	               	F1        	141B1     	P5E_CPU1_PE2_RX_DP<15>
          	               	F2        	141B1     	P5E_CPU1_PE2_RX_DN<14>
          	               	F3        	141B1     	P5E_CPU1_PE2_RX_DP<13>
          	               	F4        	141B1     	P5E_CPU1_PE2_RX_DN<12>
          	               	F5        	141B4     	P5E_CPU1_PE2_RX_DP<11>
          	               	F6        	141B4     	P5E_CPU1_PE2_RX_DN<10>
          	               	F7        	141B4     	P5E_CPU1_PE2_RX_DP<9>
          	               	F8        	141B4     	P5E_CPU1_PE2_RX_DN<8>
          	               	G1        	141B1     	P5E_CPU1_PE2_RX_DN<15>
          	               	G2        	141B1     	GND                 
          	               	G3        	141B1     	P5E_CPU1_PE2_RX_DN<13>
          	               	G4        	141B1     	GND                 
          	               	G5        	141B4     	P5E_CPU1_PE2_RX_DN<11>
          	               	G6        	141B4     	GND                 
          	               	G7        	141B4     	P5E_CPU1_PE2_RX_DN<9>
          	               	G8        	141B4     	GND                 
          	               	H1        	141B1     	GND                 
          	               	H2        	141B1     	P5E_CPU1_PE3_TX_C_DN<14>
          	               	H3        	141B1     	GND                 
          	               	H4        	141B1     	P5E_CPU1_PE3_TX_C_DN<12>
          	               	H5        	141A4     	GND                 
          	               	H6        	141B4     	P5E_CPU1_PE3_TX_C_DN<10>
          	               	H7        	141B4     	GND                 
          	               	H8        	141B4     	P5E_CPU1_PE3_TX_C_DN<8>
          	               	I1        	141A1     	P5E_CPU1_PE3_TX_C_DN<15>
          	               	I2        	141B1     	P5E_CPU1_PE3_TX_C_DP<14>
          	               	I3        	141B1     	P5E_CPU1_PE3_TX_C_DN<13>
          	               	I4        	141B1     	P5E_CPU1_PE3_TX_C_DP<12>
          	               	I5        	141A4     	P5E_CPU1_PE3_TX_C_DN<11>
          	               	I6        	141B4     	P5E_CPU1_PE3_TX_C_DP<10>
          	               	I7        	141B4     	P5E_CPU1_PE3_TX_C_DN<9>
          	               	I8        	141B4     	P5E_CPU1_PE3_TX_C_DP<8>
          	               	J1        	141A1     	P5E_CPU1_PE3_TX_C_DP<15>
          	               	J2        	141B1     	GND                 
          	               	J3        	141B1     	P5E_CPU1_PE3_TX_C_DP<13>
          	               	J4        	141B1     	GND                 
          	               	J5        	141A4     	P5E_CPU1_PE3_TX_C_DP<11>
          	               	J6        	141B4     	GND                 
          	               	J7        	141B4     	P5E_CPU1_PE3_TX_C_DP<9>
          	               	J8        	141B4     	GND                 
          	               	K1        	141A1     	GND                 
          	               	K2        	141B1     	P5E_CPU1_PE2_TX_C_DP<14>
          	               	K3        	141B1     	GND                 
          	               	K4        	141B1     	P5E_CPU1_PE2_TX_C_DP<12>
          	               	K5        	141A4     	GND                 
          	               	K6        	141B4     	P5E_CPU1_PE2_TX_C_DP<10>
          	               	K7        	141B4     	GND                 
          	               	K8        	141B4     	P5E_CPU1_PE2_TX_C_DP<8>
          	               	L1        	141A1     	P5E_CPU1_PE2_TX_C_DP<15>
          	               	L2        	141B1     	P5E_CPU1_PE2_TX_C_DN<14>
          	               	L3        	141B1     	P5E_CPU1_PE2_TX_C_DP<13>
          	               	L4        	141B1     	P5E_CPU1_PE2_TX_C_DN<12>
          	               	L5        	141A4     	P5E_CPU1_PE2_TX_C_DP<11>
          	               	L6        	141B4     	P5E_CPU1_PE2_TX_C_DN<10>
          	               	L7        	141B4     	P5E_CPU1_PE2_TX_C_DP<9>
          	               	L8        	141B4     	P5E_CPU1_PE2_TX_C_DN<8>
          	               	M1        	141A1     	P5E_CPU1_PE2_TX_C_DN<15>
          	               	M2        	141B1     	GND                 
          	               	M3        	141B1     	P5E_CPU1_PE2_TX_C_DN<13>
          	               	M4        	141B1     	GND                 
          	               	M5        	141A4     	P5E_CPU1_PE2_TX_C_DN<11>
          	               	M6        	141B4     	GND                 
          	               	M7        	141B4     	P5E_CPU1_PE2_TX_C_DN<9>
          	               	M8        	141B4     	GND                 
          	               	N1        	141A1     	GND                 
          	               	N2        	141B1     	GPU_FPGA_BOOT_EN_BUF
          	               	N3        	141B1     	GND                 
          	               	N4        	141B1     	FM_SMB_1_ALERT_GPU_N
          	               	N5        	141A4     	GND                 
          	               	N6        	141B4     	FM_SMB_2_ALERT_GPU_N
          	               	N7        	141B4     	GND                 
          	               	N8        	141B4     	GPU_FPGA_EROT_RST_BUF_N

J111      	CONN112_10137002101LF	          	          	                    
          	               	A1        	142B1     	GPU_PEX_STRAP1      
          	               	A2        	142B1     	GND                 
          	               	A3        	142B1     	GPU_BASE_ID0        
          	               	A4        	142B1     	GND                 
          	               	A5        	142B4     	GPU_PEX_STRAP0      
          	               	A6        	142B4     	GND                 
          	               	A7        	142B4     	GPU_FPGA_RST_R_BUF_N
          	               	A8        	142B4     	GND                 
          	               	B1        	142A1     	GND                 
          	               	B2        	142B1     	P5E_CPU1_PE0_RX_DN<6>
          	               	B3        	142B1     	GND                 
          	               	B4        	142B1     	P5E_CPU1_PE0_RX_DN<4>
          	               	B5        	142A4     	GND                 
          	               	B6        	142B4     	P5E_CPU1_PE0_RX_DN<2>
          	               	B7        	142B4     	GND                 
          	               	B8        	142B4     	P5E_CPU1_PE0_RX_DN<0>
          	               	C1        	142A1     	P5E_CPU1_PE0_RX_DN<7>
          	               	C2        	142B1     	P5E_CPU1_PE0_RX_DP<6>
          	               	C3        	142B1     	P5E_CPU1_PE0_RX_DN<5>
          	               	C4        	142B1     	P5E_CPU1_PE0_RX_DP<4>
          	               	C5        	142A4     	P5E_CPU1_PE0_RX_DP<3>
          	               	C6        	142B4     	P5E_CPU1_PE0_RX_DP<2>
          	               	C7        	142B4     	P5E_CPU1_PE0_RX_DP<1>
          	               	C8        	142B4     	P5E_CPU1_PE0_RX_DP<0>
          	               	D1        	142A1     	P5E_CPU1_PE0_RX_DP<7>
          	               	D2        	142B1     	GND                 
          	               	D3        	142B1     	P5E_CPU1_PE0_RX_DP<5>
          	               	D4        	142B1     	GND                 
          	               	D5        	142A4     	P5E_CPU1_PE0_RX_DN<3>
          	               	D6        	142B4     	GND                 
          	               	D7        	142B4     	P5E_CPU1_PE0_RX_DN<1>
          	               	D8        	142B4     	GND                 
          	               	E1        	142A1     	GND                 
          	               	E2        	142B1     	P5E_CPU1_PE4_RX_DP<9>
          	               	E3        	142B1     	GND                 
          	               	E4        	142B1     	P5E_CPU1_PE4_RX_DP<11>
          	               	E5        	142A4     	GND                 
          	               	E6        	142B4     	P5E_CPU1_PE4_RX_DP<13>
          	               	E7        	142B4     	GND                 
          	               	E8        	142B4     	P5E_CPU1_PE4_RX_DP<15>
          	               	F1        	142A1     	P5E_CPU1_PE4_RX_DN<8>
          	               	F2        	142B1     	P5E_CPU1_PE4_RX_DN<9>
          	               	F3        	142B1     	P5E_CPU1_PE4_RX_DN<10>
          	               	F4        	142B1     	P5E_CPU1_PE4_RX_DN<11>
          	               	F5        	142A4     	P5E_CPU1_PE4_RX_DN<12>
          	               	F6        	142B4     	P5E_CPU1_PE4_RX_DN<13>
          	               	F7        	142B4     	P5E_CPU1_PE4_RX_DN<14>
          	               	F8        	142B4     	P5E_CPU1_PE4_RX_DN<15>
          	               	G1        	142A1     	P5E_CPU1_PE4_RX_DP<8>
          	               	G2        	142B1     	GND                 
          	               	G3        	142B1     	P5E_CPU1_PE4_RX_DP<10>
          	               	G4        	142B1     	GND                 
          	               	G5        	142A4     	P5E_CPU1_PE4_RX_DP<12>
          	               	G6        	142B4     	GND                 
          	               	G7        	142B4     	P5E_CPU1_PE4_RX_DP<14>
          	               	G8        	142B4     	GND                 
          	               	H1        	142A1     	GND                 
          	               	H2        	142B1     	P5E_CPU1_PE0_TX_C_DN<6>
          	               	H3        	142B1     	GND                 
          	               	H4        	142B1     	P5E_CPU1_PE0_TX_C_DN<4>
          	               	H5        	142A4     	GND                 
          	               	H6        	142B4     	P5E_CPU1_PE0_TX_C_DN<2>
          	               	H7        	142B4     	GND                 
          	               	H8        	142B4     	P5E_CPU1_PE0_TX_C_DN<0>
          	               	I1        	142A1     	P5E_CPU1_PE0_TX_C_DN<7>
          	               	I2        	142B1     	P5E_CPU1_PE0_TX_C_DP<6>
          	               	I3        	142B1     	P5E_CPU1_PE0_TX_C_DN<5>
          	               	I4        	142B1     	P5E_CPU1_PE0_TX_C_DP<4>
          	               	I5        	142A4     	P5E_CPU1_PE0_TX_C_DN<3>
          	               	I6        	142B4     	P5E_CPU1_PE0_TX_C_DP<2>
          	               	I7        	142B4     	P5E_CPU1_PE0_TX_C_DN<1>
          	               	I8        	142B4     	P5E_CPU1_PE0_TX_C_DP<0>
          	               	J1        	142A1     	P5E_CPU1_PE0_TX_C_DP<7>
          	               	J2        	142B1     	GND                 
          	               	J3        	142B1     	P5E_CPU1_PE0_TX_C_DP<5>
          	               	J4        	142B1     	GND                 
          	               	J5        	142A4     	P5E_CPU1_PE0_TX_C_DP<3>
          	               	J6        	142B4     	GND                 
          	               	J7        	142B4     	P5E_CPU1_PE0_TX_C_DP<1>
          	               	J8        	142B4     	GND                 
          	               	K1        	142A1     	GND                 
          	               	K2        	142B1     	P5E_CPU1_PE4_TX_C_DN<9>
          	               	K3        	142B1     	GND                 
          	               	K4        	142B1     	P5E_CPU1_PE4_TX_C_DP<11>
          	               	K5        	142A4     	GND                 
          	               	K6        	142B4     	P5E_CPU1_PE4_TX_C_DN<13>
          	               	K7        	142B4     	GND                 
          	               	K8        	142B4     	P5E_CPU1_PE4_TX_C_DN<15>
          	               	L1        	142A1     	P5E_CPU1_PE4_TX_C_DN<8>
          	               	L2        	142B1     	P5E_CPU1_PE4_TX_C_DP<9>
          	               	L3        	142B1     	P5E_CPU1_PE4_TX_C_DN<10>
          	               	L4        	142B1     	P5E_CPU1_PE4_TX_C_DN<11>
          	               	L5        	142A4     	P5E_CPU1_PE4_TX_C_DN<12>
          	               	L6        	142B4     	P5E_CPU1_PE4_TX_C_DP<13>
          	               	L7        	142B4     	P5E_CPU1_PE4_TX_C_DN<14>
          	               	L8        	142B4     	P5E_CPU1_PE4_TX_C_DP<15>
          	               	M1        	142A1     	P5E_CPU1_PE4_TX_C_DP<8>
          	               	M2        	142B1     	GND                 
          	               	M3        	142B1     	P5E_CPU1_PE4_TX_C_DP<10>
          	               	M4        	142B1     	GND                 
          	               	M5        	142A4     	P5E_CPU1_PE4_TX_C_DP<12>
          	               	M6        	142B4     	GND                 
          	               	M7        	142B4     	P5E_CPU1_PE4_TX_C_DP<14>
          	               	M8        	142B4     	GND                 
          	               	N1        	142A1     	GND                 
          	               	N2        	142B1     	GPU_PRSNT_N         
          	               	N3        	142B1     	GND                 
          	               	N4        	142B1     	FM_GPU_PWR_EN_R_BUF 
          	               	N5        	142A4     	GND                 
          	               	N6        	142B4     	FM_GPU_PWRGD        
          	               	N7        	142B4     	GND                 
          	               	N8        	142B4     	GPU_BASE_ID1        

J112      	CONN160_10131762101LF	          	          	                    
          	               	A1        	143A2     	RST_PERST_2_SWB_BUF_N
          	               	A2        	143B2     	GND                 
          	               	A3        	143B2     	HGX_DETECT_N_ISO    
          	               	A4        	143B2     	GND                 
          	               	A5        	143A4     	RST_PERST_1_SWB_BUF_N
          	               	A6        	143B4     	GND                 
          	               	A7        	143B4     	PRSNT_SWB_N         
          	               	A8        	143B4     	GND                 
          	               	B1        	143A2     	GND                 
          	               	B2        	143B2     	P5E_CPU1_PE0_RX_DN<14>
          	               	B3        	143B2     	GND                 
          	               	B4        	143B2     	P5E_CPU1_PE0_RX_DN<12>
          	               	B5        	143A4     	GND                 
          	               	B6        	143B4     	P5E_CPU1_PE0_RX_DN<10>
          	               	B7        	143B4     	GND                 
          	               	B8        	143B4     	P5E_CPU1_PE0_RX_DN<8>
          	               	C1        	143A2     	P5E_CPU1_PE0_RX_DN<15>
          	               	C2        	143B2     	P5E_CPU1_PE0_RX_DP<14>
          	               	C3        	143B2     	P5E_CPU1_PE0_RX_DN<13>
          	               	C4        	143B2     	P5E_CPU1_PE0_RX_DP<12>
          	               	C5        	143A4     	P5E_CPU1_PE0_RX_DP<11>
          	               	C6        	143B4     	P5E_CPU1_PE0_RX_DP<10>
          	               	C7        	143B4     	P5E_CPU1_PE0_RX_DN<9>
          	               	C8        	143B4     	P5E_CPU1_PE0_RX_DP<8>
          	               	D1        	143A2     	P5E_CPU1_PE0_RX_DP<15>
          	               	D2        	143B2     	GND                 
          	               	D3        	143B2     	P5E_CPU1_PE0_RX_DP<13>
          	               	D4        	143B2     	GND                 
          	               	D5        	143A4     	P5E_CPU1_PE0_RX_DN<11>
          	               	D6        	143B4     	GND                 
          	               	D7        	143B4     	P5E_CPU1_PE0_RX_DP<9>
          	               	D8        	143B4     	GND                 
          	               	E1        	143A2     	GND                 
          	               	E2        	143B2     	P5E_CPU1_PE4_RX_DP<1>
          	               	E3        	143B2     	GND                 
          	               	E4        	143B2     	P5E_CPU1_PE4_RX_DP<3>
          	               	E5        	143A4     	GND                 
          	               	E6        	143B4     	P5E_CPU1_PE4_RX_DP<5>
          	               	E7        	143B4     	GND                 
          	               	E8        	143B4     	P5E_CPU1_PE4_RX_DP<7>
          	               	F1        	143A2     	P5E_CPU1_PE4_RX_DN<0>
          	               	F2        	143B2     	P5E_CPU1_PE4_RX_DN<1>
          	               	F3        	143B2     	P5E_CPU1_PE4_RX_DN<2>
          	               	F4        	143B2     	P5E_CPU1_PE4_RX_DN<3>
          	               	F5        	143A4     	P5E_CPU1_PE4_RX_DN<4>
          	               	F6        	143B4     	P5E_CPU1_PE4_RX_DN<5>
          	               	F7        	143B4     	P5E_CPU1_PE4_RX_DN<6>
          	               	F8        	143B4     	P5E_CPU1_PE4_RX_DN<7>
          	               	G1        	143A2     	P5E_CPU1_PE4_RX_DP<0>
          	               	G2        	143B2     	GND                 
          	               	G3        	143B2     	P5E_CPU1_PE4_RX_DP<2>
          	               	G4        	143B2     	GND                 
          	               	G5        	143A4     	P5E_CPU1_PE4_RX_DP<4>
          	               	G6        	143B4     	GND                 
          	               	G7        	143B4     	P5E_CPU1_PE4_RX_DP<6>
          	               	G8        	143B4     	GND                 
          	               	H1        	143A2     	GND                 
          	               	H2        	143B2     	P5E_CPU1_PE0_TX_C_DN<14>
          	               	H3        	143B2     	GND                 
          	               	H4        	143B2     	P5E_CPU1_PE0_TX_C_DN<12>
          	               	H5        	143A4     	GND                 
          	               	H6        	143B4     	P5E_CPU1_PE0_TX_C_DN<10>
          	               	H7        	143B4     	GND                 
          	               	H8        	143B4     	P5E_CPU1_PE0_TX_C_DN<8>
          	               	I1        	143A2     	P5E_CPU1_PE0_TX_C_DN<15>
          	               	I2        	143B2     	P5E_CPU1_PE0_TX_C_DP<14>
          	               	I3        	143B2     	P5E_CPU1_PE0_TX_C_DN<13>
          	               	I4        	143B2     	P5E_CPU1_PE0_TX_C_DP<12>
          	               	I5        	143A4     	P5E_CPU1_PE0_TX_C_DN<11>
          	               	I6        	143B4     	P5E_CPU1_PE0_TX_C_DP<10>
          	               	I7        	143B4     	P5E_CPU1_PE0_TX_C_DN<9>
          	               	I8        	143B4     	P5E_CPU1_PE0_TX_C_DP<8>
          	               	J1        	143A2     	P5E_CPU1_PE0_TX_C_DP<15>
          	               	J2        	143B2     	GND                 
          	               	J3        	143B2     	P5E_CPU1_PE0_TX_C_DP<13>
          	               	J4        	143B2     	GND                 
          	               	J5        	143A4     	P5E_CPU1_PE0_TX_C_DP<11>
          	               	J6        	143B4     	GND                 
          	               	J7        	143B4     	P5E_CPU1_PE0_TX_C_DP<9>
          	               	J8        	143B4     	GND                 
          	               	K1        	143A2     	GND                 
          	               	K2        	143B2     	P5E_CPU1_PE4_TX_C_DP<1>
          	               	K3        	143B2     	GND                 
          	               	K4        	143B2     	P5E_CPU1_PE4_TX_C_DN<3>
          	               	K5        	143A4     	GND                 
          	               	K6        	143B4     	P5E_CPU1_PE4_TX_C_DN<5>
          	               	K7        	143B4     	GND                 
          	               	K8        	143B4     	P5E_CPU1_PE4_TX_C_DN<7>
          	               	L1        	143A2     	P5E_CPU1_PE4_TX_C_DN<0>
          	               	L2        	143B2     	P5E_CPU1_PE4_TX_C_DN<1>
          	               	L3        	143B2     	P5E_CPU1_PE4_TX_C_DN<2>
          	               	L4        	143B2     	P5E_CPU1_PE4_TX_C_DP<3>
          	               	L5        	143A4     	P5E_CPU1_PE4_TX_C_DN<4>
          	               	L6        	143B4     	P5E_CPU1_PE4_TX_C_DP<5>
          	               	L7        	143B4     	P5E_CPU1_PE4_TX_C_DN<6>
          	               	L8        	143B4     	P5E_CPU1_PE4_TX_C_DP<7>
          	               	M1        	143A2     	P5E_CPU1_PE4_TX_C_DP<0>
          	               	M2        	143B2     	GND                 
          	               	M3        	143B2     	P5E_CPU1_PE4_TX_C_DP<2>
          	               	M4        	143B2     	GND                 
          	               	M5        	143A4     	P5E_CPU1_PE4_TX_C_DP<4>
          	               	M6        	143B4     	GND                 
          	               	M7        	143B4     	P5E_CPU1_PE4_TX_C_DP<6>
          	               	M8        	143B4     	GND                 
          	               	N1        	143A2     	GND                 
          	               	N2        	143B2     	NC_J112_N2          
          	               	N3        	143B2     	GND                 
          	               	N4        	143B2     	CLK_100M_GPU_1_DN   
          	               	N5        	143A4     	GND                 
          	               	N6        	143B4     	P2E_MB_BMC_RX_DN<0> 
          	               	N7        	143B4     	GND                 
          	               	N8        	143B4     	P3E_PCH_NVS_RX_DN<0>
          	               	O1        	143A2     	CLK_100M_GPU_2_DN   
          	               	O2        	143B2     	NC_J112_O2          
          	               	O3        	143B2     	CLK_100M_SWB_DN     
          	               	O4        	143B2     	CLK_100M_GPU_1_DP   
          	               	O5        	143A4     	NC_J112_O5          
          	               	O6        	143B4     	P2E_MB_BMC_RX_DP<0> 
          	               	O7        	143B4     	P3E_PCH_NVS_RX_DN<1>
          	               	O8        	143B4     	P3E_PCH_NVS_RX_DP<0>
          	               	P1        	143A2     	CLK_100M_GPU_2_DP   
          	               	P2        	143B2     	GND                 
          	               	P3        	143B2     	CLK_100M_SWB_DP     
          	               	P4        	143B2     	GND                 
          	               	P5        	143A4     	NC_J112_P5          
          	               	P6        	143A4     	GND                 
          	               	P7        	143B4     	P3E_PCH_NVS_RX_DP<1>
          	               	P8        	143B4     	GND                 
          	               	Q1        	143A2     	GND                 
          	               	Q2        	143B2     	CLK_100M_GPU_FPGA_DN
          	               	Q3        	143B2     	GND                 
          	               	Q4        	143B2     	SMB_1_BMC_GPU_BUF_SCL
          	               	Q5        	143A4     	GND                 
          	               	Q6        	143A4     	P2E_MB_BMC_TX_BUF_C_DN<0>
          	               	Q7        	143B4     	GND                 
          	               	Q8        	143B4     	P3E_PCH_NVS_TX_C_DN<0>
          	               	R1        	143A2     	USB2_HUB_BUF_SWB_DN 
          	               	R2        	143A2     	CLK_100M_GPU_FPGA_DP
          	               	R3        	143B2     	SMB_2_BMC_GPU_BUF_SCL
          	               	R4        	143B2     	SMB_1_BMC_GPU_BUF_SDA
          	               	R5        	143A4     	NC_J112_R5          
          	               	R6        	143A4     	P2E_MB_BMC_TX_BUF_C_DP<0>
          	               	R7        	143B4     	P3E_PCH_NVS_TX_C_DN<1>
          	               	R8        	143B4     	P3E_PCH_NVS_TX_C_DP<0>
          	               	S1        	143A2     	USB2_HUB_BUF_SWB_DP 
          	               	S2        	143A2     	GND                 
          	               	S3        	143B2     	SMB_2_BMC_GPU_BUF_SDA
          	               	S4        	143B2     	GND                 
          	               	S5        	143A4     	NC_J112_S5          
          	               	S6        	143A4     	GND                 
          	               	S7        	143B4     	P3E_PCH_NVS_TX_C_DP<1>
          	               	S8        	143B4     	GND                 
          	               	T1        	143A2     	GND                 
          	               	T2        	143A2     	GPU_FPGA_READY      
          	               	T3        	143B2     	GND                 
          	               	T4        	143B2     	GPU_NVS_PWR_BRAKE_N_BUF
          	               	T5        	143A4     	GND                 
          	               	T6        	143A4     	GPU_FPGA_THERM_OVERT_N
          	               	T7        	143B4     	GND                 
          	               	T8        	143B4     	RST_PERST_0_SWB_BUF_N

J114      	DELTA_L        	          	          	                    
          	               	1         	308A4     	DELTA_L_85_5INCH_IN5_DP
          	               	2         	308A4     	DELTA_L_85_5INCH_IN5_DN
          	               	3         	308A4     	DELTA_L_GND_1       

J115      	DELTA_L        	          	          	                    
          	               	1         	308A4     	DELTA_L_85_5INCH_IN6_DP
          	               	2         	308A4     	DELTA_L_85_5INCH_IN6_DN
          	               	3         	308A4     	DELTA_L_GND_1       

J116      	DELTA_L        	          	          	                    
          	               	1         	308A4     	DELTA_L_85_5INCH_IN5_DN
          	               	2         	308A4     	DELTA_L_85_5INCH_IN5_DP
          	               	3         	308A3     	DELTA_L_GND_1       

J117      	DELTA_L        	          	          	                    
          	               	1         	308A4     	DELTA_L_85_5INCH_IN6_DN
          	               	2         	308A4     	DELTA_L_85_5INCH_IN6_DP
          	               	3         	308A3     	DELTA_L_GND_1       

J118      	DELTA_L        	          	          	                    
          	               	1         	308A2     	DELTA_L_85_10INCH_IN5_DP
          	               	2         	308A2     	DELTA_L_85_10INCH_IN5_DN
          	               	3         	308A2     	DELTA_L_GND_1       

J119      	DELTA_L        	          	          	                    
          	               	1         	308A2     	DELTA_L_85_10INCH_IN6_DP
          	               	2         	308A2     	DELTA_L_85_10INCH_IN6_DN
          	               	3         	308A2     	DELTA_L_GND_1       

J120      	DELTA_L        	          	          	                    
          	               	1         	308A1     	DELTA_L_85_10INCH_IN5_DN
          	               	2         	308A1     	DELTA_L_85_10INCH_IN5_DP
          	               	3         	308A1     	DELTA_L_GND_1       

J121      	DELTA_L        	          	          	                    
          	               	1         	308A1     	DELTA_L_85_10INCH_IN6_DN
          	               	2         	308A1     	DELTA_L_85_10INCH_IN6_DP
          	               	3         	308A1     	DELTA_L_GND_1       

J122      	CONN1_10165288101LF	          	          	                    
          	               	SCR_H1    	310B1     	NC                  

J123      	CONN1_10165288101LF	          	          	                    
          	               	SCR_H1    	310B1     	NC                  

JP4       	CONN3_210HP1030BR1	          	          	                    
          	               	1         	183B4     	SMB_SML0_3V3AUX_PCH_SCL
          	               	2         	183B4     	GND                 
          	               	3         	183B4     	SMB_SML0_3V3AUX_PCH_SDA

JP7       	CONN3_210HP1030BR1	          	          	                    
          	               	1         	235A4     	FM_SMB_PEHPCPU0_PCIE_ALERT_N
          	               	2         	235A4     	GND                 
          	               	3         	235A4     	FM_SMB_PEHPCPU1_PCIE_ALERT_N

JP9       	CONN3_210HP1030BR1	          	          	                    
          	               	1         	183B4     	SMB_SML1_PMBUS_3V3AUX_PCH_SCL_1
          	               	2         	183B4     	GND                 
          	               	3         	183B4     	SMB_SML1_PMBUS_3V3AUX_PCH_SDA_1

JP10      	CONN3_210HP1030BR1	          	          	                    
          	               	1         	305B2     	SMB_SML1_PMBUS_HSC_MODULE_SCL
          	               	2         	305B2     	SMB_SML1_PMBUS_HSC_MODULE_SDA
          	               	3         	305B2     	GND                 

JP15      	CONN3_210HP1030BR1	          	          	                    
          	               	1         	215B4     	PU_FORCE_PWRON      
          	               	2         	215B4     	FM_FORCE_PWRON_LVC3 
          	               	3         	215B4     	PD_FORCE_PWRON      

JP15_23   	TP_TP_BOM ONLY 	          	          	                    
          	               	1         	311A4     	NC                  

JP16      	CONN3_210HP1030BR1	          	          	                    
          	               	1         	248B3     	PU_JTAG_SW_PU       
          	               	2         	248B3     	JTAG_BMC_SW_OE      
          	               	3         	248B3     	GND                 

JP16_12   	TP_TP_BOM ONLY 	          	          	                    
          	               	1         	311A4     	NC                  

JP4003    	CONN3_210HP1030BR1	          	          	                    
          	               	1         	301A4     	NC                  
          	               	2         	301A4     	PDB_PRSNT_N         
          	               	3         	301A4     	GND                 

JP4003_12 	TP_TP_BOM ONLY 	          	          	                    
          	               	1         	311A4     	NC                  

L1        	Q_INDUCTOR_SMLF	          	          	                    
          	               	1         	210B4     	P3V3_AUX            
          	               	2         	210B4     	P3V3_AUX_CLK_GEN_VDD_CK440

L2        	Q_INDUCTOR_SMLF	          	          	                    
          	               	1         	189B2     	P1V05_PCH_AUX       
          	               	2         	189B2     	P1V05_PCH_PLL_AUX   

L3        	Q_INDUCTOR_SMLF	          	          	                    
          	               	1         	206B4     	P3V3                
          	               	2         	206B4     	P3V3_DB2000_VDD     

L4        	Q_INDUCTOR_SMLF	          	          	                    
          	               	1         	206B4     	P3V3                
          	               	2         	206B4     	P3V3_DB2000_FB_VDD  

L10       	Q_INDUCTOR_SMLF	          	          	                    
          	               	1         	189B2     	P1V8_PCH_AUX        
          	               	2         	189B2     	P1V8_PCH_PLL_AUX    

L13       	Q_INDUCTOR_SMLF	          	          	                    
          	               	1         	210B4     	P3V3_AUX            
          	               	2         	210B4     	P3V3_AUX_CLK_GEN_VDDXTAL_CK440

L14       	Q_INDUCTOR_SMLF	          	          	                    
          	               	1         	210B4     	P3V3_AUX            
          	               	2         	210B4     	P3V3_AUX_CLK_GEN_VDDMXCK_CK440

L15       	Q_INDUCTOR_SMLF	          	          	                    
          	               	1         	250B1     	P3V3_MAX11617_VDD   
          	               	2         	250B1     	P3V3_AUX            

L16       	Q_INDUCTOR_SMLF	          	          	                    
          	               	1         	250B3     	P3V3_AUX            
          	               	2         	250B3     	P3V3_ADC128_VCC     

L17       	Q_INDUCTOR_SMLF	          	          	                    
          	               	1         	212B4     	P3V3_AUX            
          	               	2         	212B4     	VFG3P3_CLK_GEN      

L18       	Q_INDUCTOR_SMLF	          	          	                    
          	               	1         	169B4     	P3V3_AUX            
          	               	2         	169B4     	P3V3_AUX_USB_BUF    

L19       	Q_INDUCTOR_SMLF	          	          	                    
          	               	1         	211B4     	P3V3                
          	               	2         	211B4     	P3V3_9ZXL045        

L20       	Q_INDUCTOR_SMLF	          	          	                    
          	               	1         	211B3     	P3V3                
          	               	2         	211B3     	P3V3_9ZXL045_VDD    

OSC1      	Q_OSC4P_SMLF   	          	          	                    
          	               	1         	155A4     	CLK_50M_EN          
          	               	2         	155A4     	GND                 
          	               	3         	155A4     	CLK_50M_RMII        
          	               	4         	155A4     	P3V3_AUX            

OSC2      	Q_OSC4P_SMLF   	          	          	                    
          	               	1         	214A4     	PU_CLK25M_OSC_FPGA_EN
          	               	2         	214A4     	GND                 
          	               	3         	214A4     	CLK_25M_OSC_FPGA_R  
          	               	4         	214A4     	P3V3_AUX            

PC1       	Q_CAP_C0805    	          	          	                    
          	               	1         	279B2     	PVCCD_HV_CPU0       
          	               	2         	279B2     	GND                 

PC2       	Q_CAP_C0805    	          	          	                    
          	               	1         	297B1     	PVCCD_HV_CPU1       
          	               	2         	297B1     	GND                 

PC3       	Q_CAPP_THLF    	          	          	                    
          	               	1         	259B4     	SW_P3V3_AUX_FLT     
          	               	2         	259B4     	GND                 

PC8       	Q_CAP_C0603    	          	          	                    
          	               	1         	259B3     	P12V_AUX            
          	               	2         	259B3     	GND                 

PC16      	Q_CAPP_THLF    	          	          	                    
          	               	1         	267B2     	PVCCIN_CPU0         
          	               	2         	267B2     	GND                 

PC27      	Q_CAP_0402     	          	          	                    
          	               	1         	282A3     	PVNN_MAIN_CPU0_REF  
          	               	2         	282A3     	GND                 

PC28      	Q_CAP_0402     	          	          	                    
          	               	1         	300A3     	PVNN_MAIN_CPU1_REF  
          	               	2         	300A3     	GND                 

PC71      	Q_CAP_C0805    	          	          	                    
          	               	1         	259B4     	SW_P3V3_AUX_FLT     
          	               	2         	259B4     	GND                 

PC83      	Q_CAPP_THLF    	          	          	                    
          	               	1         	285B2     	PVCCIN_CPU1         
          	               	2         	285B2     	GND                 

PC100     	Q_CAP_0402     	          	          	                    
          	               	1         	266A1     	PVCCFA_EHV_FIVRA_CPU0_BTSEN
          	               	2         	266A1     	GND                 

PC101     	Q_CAP_0402     	          	          	                    
          	               	1         	284A1     	PVCCFA_EHV_FIVRA_CPU1_BTSEN
          	               	2         	284A1     	GND                 

PC113     	Q_CAP_C0402    	          	          	                    
          	               	1         	262A4     	P1V05_PCH_AUX_VCC   
          	               	2         	262A4     	GND                 

PC117     	Q_CAPP_SMLF    	          	          	                    
          	               	1         	262A1     	P1V05_PCH_AUX       
          	               	2         	262A1     	GND                 

PC175     	Q_CAP_C0402    	          	          	                    
          	               	1         	276B4     	PVCCFA_EHV_CPU0_VDD1
          	               	2         	276B4     	GND                 

PC176     	Q_CAP_0402     	          	          	                    
          	               	1         	276B3     	SW_P12V_PVCCINFAON_CPU0_FLT
          	               	2         	276B3     	GND                 

PC177     	Q_CAP_C0402    	          	          	                    
          	               	1         	276B3     	SW_P12V_PVCCINFAON_CPU0_FLT
          	               	2         	276B3     	GND                 

PC178     	Q_CAP_C0402    	          	          	                    
          	               	1         	276B2     	SW_PVCCFA_EHV_CPU0_BOOT1_R
          	               	2         	276B2     	SW_PVCCFA_EHV_CPU0_BOOTR1

PC179     	Q_CAP_C0805    	          	          	                    
          	               	1         	276B3     	SW_P12V_PVCCINFAON_CPU0_FLT
          	               	2         	276B3     	GND                 

PC180     	Q_CAP_C0805    	          	          	                    
          	               	1         	276B2     	SW_P12V_PVCCINFAON_CPU0_FLT
          	               	2         	276B2     	GND                 

PC181     	Q_CAP_C0402    	          	          	                    
          	               	1         	276B2     	PVCCFA_EHV_CPU0     
          	               	2         	276B2     	GND                 

PC184     	Q_CAP_C0805    	          	          	                    
          	               	1         	276B2     	PVCCFA_EHV_CPU0     
          	               	2         	276B2     	GND                 

PC186     	Q_CAP_C0805    	          	          	                    
          	               	1         	276B2     	PVCCFA_EHV_CPU0     
          	               	2         	276B2     	GND                 

PC187     	Q_CAP_C0402    	          	          	                    
          	               	1         	275B4     	PVCCINFAON_CPU0_VDD1
          	               	2         	275B4     	GND                 

PC188     	Q_CAP_C0402    	          	          	                    
          	               	1         	275A4     	PVCCINFAON_CPU0_VDD2
          	               	2         	275A4     	GND                 

PC189     	Q_CAPP_SMLF    	          	          	                    
          	               	1         	285A1     	PVCCIN_CPU1         
          	               	2         	285A1     	GND                 

PC189_P0_1	Q_CAP_0402     	          	          	                    
          	               	1         	275B4     	SW_P12V_PVCCINFAON_CPU0_FLT
          	               	2         	275B4     	GND                 

PC190     	Q_CAP_C0402    	          	          	                    
          	               	1         	162B3     	P3V3_OCP_VCC_2      
          	               	2         	162B3     	GND                 

PC190_P0_2	Q_CAP_0402     	          	          	                    
          	               	1         	275B4     	SW_P12V_PVCCINFAON_CPU0_FLT
          	               	2         	275A4     	GND                 

PC191_P0_1	Q_CAP_C0402    	          	          	                    
          	               	1         	275B3     	SW_P12V_PVCCINFAON_CPU0_FLT
          	               	2         	275B3     	GND                 

PC192_P0_2	Q_CAP_C0402    	          	          	                    
          	               	1         	275B3     	SW_P12V_PVCCINFAON_CPU0_FLT
          	               	2         	275A3     	GND                 

PC193     	Q_CAP_C0402    	          	          	                    
          	               	1         	275B3     	SW_PVCCINFAON_CPU0_BOOT1_R
          	               	2         	275B3     	SW_PVCCINFAON_CPU0_BOOTR1

PC194     	Q_CAP_C0402    	          	          	                    
          	               	1         	275A3     	SW_PVCCINFAON_CPU0_BOOT2_R
          	               	2         	275A3     	SW_PVCCINFAON_CPU0_BOOTR2

PC195_P0_1	Q_CAP_C0805    	          	          	                    
          	               	1         	275B3     	SW_P12V_PVCCINFAON_CPU0_FLT
          	               	2         	275B3     	GND                 

PC196_P0_2	Q_CAP_C0805    	          	          	                    
          	               	1         	275B3     	SW_P12V_PVCCINFAON_CPU0_FLT
          	               	2         	275A3     	GND                 

PC197_P0_1	Q_CAP_C0805    	          	          	                    
          	               	1         	275B3     	SW_P12V_PVCCINFAON_CPU0_FLT
          	               	2         	275B3     	GND                 

PC198_P0_2	Q_CAP_C0805    	          	          	                    
          	               	1         	275B3     	SW_P12V_PVCCINFAON_CPU0_FLT
          	               	2         	275A3     	GND                 

PC199_P0_1	Q_CAP_C0402    	          	          	                    
          	               	1         	275B3     	PVCCINFAON_CPU0     
          	               	2         	275B3     	GND                 

PC202_P0_1	Q_CAP_C0805    	          	          	                    
          	               	1         	275B2     	PVCCINFAON_CPU0     
          	               	2         	275B2     	GND                 

PC203_P0_2	Q_CAP_C0805    	          	          	                    
          	               	1         	275A2     	PVCCINFAON_CPU0     
          	               	2         	275A2     	GND                 

PC204_P0_1	Q_CAP_C0805    	          	          	                    
          	               	1         	275B2     	PVCCINFAON_CPU0     
          	               	2         	275B2     	GND                 

PC205_P0_2	Q_CAP_C0805    	          	          	                    
          	               	1         	275A2     	PVCCINFAON_CPU0     
          	               	2         	275A2     	GND                 

PC207     	Q_CAPP_THLF    	          	          	                    
          	               	1         	275B2     	SW_P12V_PVCCINFAON_CPU0_FLT
          	               	2         	275B2     	GND                 

PC208     	Q_CAPP_THLF    	          	          	                    
          	               	1         	275B1     	SW_P12V_PVCCINFAON_CPU0_FLT
          	               	2         	275B1     	GND                 

PC214     	Q_CAP_0402     	          	          	                    
          	               	1         	274A4     	PVCCINFAON_CPU0_CSPIN
          	               	2         	274A4     	GND                 

PC215     	Q_CAP_0402     	          	          	                    
          	               	1         	274B4     	SH_PVCCINFAON_CPU0_R
          	               	2         	274B4     	VSENSE_PVCCINFAON_CPU0_DN

PC216     	Q_CAP_0402     	          	          	                    
          	               	1         	274B4     	SH_PVCCFA_EHV_CPU0_R
          	               	2         	274B4     	VSENSE_PVCCFA_EHV_CPU0_DN

PC221     	Q_CAP_0402     	          	          	                    
          	               	1         	274A3     	PVCCINFAON_CPU0_VIN_CSNIN
          	               	2         	274A3     	GND                 

PC222     	Q_CAP_0402     	          	          	                    
          	               	1         	274A2     	PVCCINFAON_CPU0_ATSEN
          	               	2         	274A2     	GND                 

PC223     	Q_CAP_C0402    	          	          	                    
          	               	1         	274B2     	PVCCINFAON_CPU0_VCC 
          	               	2         	274B2     	GND                 

PC224     	Q_CAP_C0402    	          	          	                    
          	               	1         	274B2     	PVCCINFAON_CPU0_VREF
          	               	2         	274B2     	GND                 

PC225     	Q_CAP_C0402    	          	          	                    
          	               	1         	274B2     	PVCCINFAON_CPU0_VCC 
          	               	2         	274B2     	GND                 

PC226     	Q_CAP_C0402    	          	          	                    
          	               	1         	270A4     	PVCCIN_CPU0_VDD8    
          	               	2         	270A4     	GND                 

PC227     	Q_CAP_C0402    	          	          	                    
          	               	1         	270B4     	PVCCIN_CPU0_VDD7    
          	               	2         	270B4     	GND                 

PC228_P0_8	Q_CAP_C0402    	          	          	                    
          	               	1         	270B4     	PVCCIN_CPU0_PVCC    
          	               	2         	270B4     	GND                 

PC229_P0_7	Q_CAP_C0402    	          	          	                    
          	               	1         	270B4     	PVCCIN_CPU0_PVCC    
          	               	2         	270B4     	GND                 

PC230_P0_8	Q_CAP_0402     	          	          	                    
          	               	1         	270B3     	SW_P12V_PVCCIN_CPU0_FLT
          	               	2         	270B3     	GND                 

PC231_P0_7	Q_CAP_0402     	          	          	                    
          	               	1         	270B3     	SW_P12V_PVCCIN_CPU0_FLT
          	               	2         	270B3     	GND                 

PC232_P0_8	Q_CAP_C0402    	          	          	                    
          	               	1         	270B3     	SW_P12V_PVCCIN_CPU0_FLT
          	               	2         	270B3     	GND                 

PC233_P0_7	Q_CAP_C0402    	          	          	                    
          	               	1         	270B3     	SW_P12V_PVCCIN_CPU0_FLT
          	               	2         	270B3     	GND                 

PC234     	Q_CAP_C0402    	          	          	                    
          	               	1         	270A2     	SW_PVCCIN_CPU0_BOOT8_R
          	               	2         	270A2     	SW_PVCCIN_CPU0_BOOTR8

PC235     	Q_CAP_C0402    	          	          	                    
          	               	1         	270B2     	SW_PVCCIN_CPU0_BOOT7_R
          	               	2         	270B2     	SW_PVCCIN_CPU0_BOOTR7

PC236_P0_8	Q_CAP_C0805    	          	          	                    
          	               	1         	270B3     	SW_P12V_PVCCIN_CPU0_FLT
          	               	2         	270B3     	GND                 

PC237     	Q_CAP_0402     	          	          	                    
          	               	1         	282A2     	PVNN_MAIN_CPU0_FB   
          	               	2         	282A2     	PVNN_MAIN_CPU0_FB_RC

PC237_P0_7	Q_CAP_C0805    	          	          	                    
          	               	1         	270B2     	SW_P12V_PVCCIN_CPU0_FLT
          	               	2         	270B2     	GND                 

PC238     	Q_CAP_0402     	          	          	                    
          	               	1         	300A2     	PVNN_MAIN_CPU1_FB   
          	               	2         	300A2     	PVNN_MAIN_CPU1_FB_RC

PC238_P0_8	Q_CAP_C0805    	          	          	                    
          	               	1         	270B2     	SW_P12V_PVCCIN_CPU0_FLT
          	               	2         	270B2     	GND                 

PC239_P0_7	Q_CAP_C0805    	          	          	                    
          	               	1         	270B2     	SW_P12V_PVCCIN_CPU0_FLT
          	               	2         	270B2     	GND                 

PC240_P0_8	Q_CAP_C0805    	          	          	                    
          	               	1         	270B2     	SW_P12V_PVCCIN_CPU0_FLT
          	               	2         	270B2     	GND                 

PC241_P0_7	Q_CAP_C0805    	          	          	                    
          	               	1         	270B2     	SW_P12V_PVCCIN_CPU0_FLT
          	               	2         	270B2     	GND                 

PC242_P0_8	Q_CAP_C0402    	          	          	                    
          	               	1         	270A1     	PVCCIN_CPU0         
          	               	2         	270A1     	GND                 

PC243_P0_7	Q_CAP_C0402    	          	          	                    
          	               	1         	270B1     	PVCCIN_CPU0         
          	               	2         	270B1     	GND                 

PC244_P0_8	Q_CAP_C0805    	          	          	                    
          	               	1         	270A1     	PVCCIN_CPU0         
          	               	2         	270A1     	GND                 

PC245_P0_7	Q_CAP_C0805    	          	          	                    
          	               	1         	270B1     	PVCCIN_CPU0         
          	               	2         	270B1     	GND                 

PC246_P0_8	Q_CAP_C0805    	          	          	                    
          	               	1         	270A1     	PVCCIN_CPU0         
          	               	2         	270A1     	GND                 

PC247_P0_7	Q_CAP_C0805    	          	          	                    
          	               	1         	270B1     	PVCCIN_CPU0         
          	               	2         	270B1     	GND                 

PC248     	Q_CAP_C0402    	          	          	                    
          	               	1         	269A4     	PVCCIN_CPU0_VDD6    
          	               	2         	269A4     	GND                 

PC249     	Q_CAP_C0402    	          	          	                    
          	               	1         	269B4     	PVCCIN_CPU0_VDD5    
          	               	2         	269B4     	GND                 

PC250_P0_6	Q_CAP_C0402    	          	          	                    
          	               	1         	269B4     	PVCCIN_CPU0_PVCC    
          	               	2         	269A4     	GND                 

PC251_P0_5	Q_CAP_C0402    	          	          	                    
          	               	1         	269B4     	PVCCIN_CPU0_PVCC    
          	               	2         	269B4     	GND                 

PC252_P0_6	Q_CAP_0402     	          	          	                    
          	               	1         	269B3     	SW_P12V_PVCCIN_CPU0_FLT
          	               	2         	269A3     	GND                 

PC253_P0_5	Q_CAP_0402     	          	          	                    
          	               	1         	269B3     	SW_P12V_PVCCIN_CPU0_FLT
          	               	2         	269B3     	GND                 

PC254_P0_6	Q_CAP_C0402    	          	          	                    
          	               	1         	269B3     	SW_P12V_PVCCIN_CPU0_FLT
          	               	2         	269A3     	GND                 

PC255_P0_5	Q_CAP_C0402    	          	          	                    
          	               	1         	269B3     	SW_P12V_PVCCIN_CPU0_FLT
          	               	2         	269B3     	GND                 

PC256     	Q_CAP_C0402    	          	          	                    
          	               	1         	269A2     	SW_PVCCIN_CPU0_BOOT6_R
          	               	2         	269A2     	SW_PVCCIN_CPU0_BOOTR6

PC257     	Q_CAP_C0402    	          	          	                    
          	               	1         	269B2     	SW_PVCCIN_CPU0_BOOT5_R
          	               	2         	269B2     	SW_PVCCIN_CPU0_BOOTR5

PC258_P0_6	Q_CAP_C0805    	          	          	                    
          	               	1         	269B2     	SW_P12V_PVCCIN_CPU0_FLT
          	               	2         	269A2     	GND                 

PC259_P0_5	Q_CAP_C0805    	          	          	                    
          	               	1         	269B2     	SW_P12V_PVCCIN_CPU0_FLT
          	               	2         	269B2     	GND                 

PC260_P0_6	Q_CAP_C0805    	          	          	                    
          	               	1         	269B2     	SW_P12V_PVCCIN_CPU0_FLT
          	               	2         	269A2     	GND                 

PC261_P0_5	Q_CAP_C0805    	          	          	                    
          	               	1         	269B2     	SW_P12V_PVCCIN_CPU0_FLT
          	               	2         	269B2     	GND                 

PC262_P0_6	Q_CAP_C0805    	          	          	                    
          	               	1         	269B2     	SW_P12V_PVCCIN_CPU0_FLT
          	               	2         	269A2     	GND                 

PC263_P0_5	Q_CAP_C0805    	          	          	                    
          	               	1         	269B2     	SW_P12V_PVCCIN_CPU0_FLT
          	               	2         	269B2     	GND                 

PC266_P0_6	Q_CAP_C0805    	          	          	                    
          	               	1         	269A1     	PVCCIN_CPU0         
          	               	2         	269A1     	GND                 

PC267_P0_5	Q_CAP_C0805    	          	          	                    
          	               	1         	269B1     	PVCCIN_CPU0         
          	               	2         	269B1     	GND                 

PC268_P0_6	Q_CAP_C0805    	          	          	                    
          	               	1         	269A1     	PVCCIN_CPU0         
          	               	2         	269A1     	GND                 

PC269_P0_5	Q_CAP_C0805    	          	          	                    
          	               	1         	269B1     	PVCCIN_CPU0         
          	               	2         	269B1     	GND                 

PC270     	Q_CAP_C0402    	          	          	                    
          	               	1         	268A4     	PVCCIN_CPU0_VDD4    
          	               	2         	268A4     	GND                 

PC271     	Q_CAP_C0402    	          	          	                    
          	               	1         	268B4     	PVCCIN_CPU0_VDD3    
          	               	2         	268B4     	GND                 

PC272_P0_4	Q_CAP_C0402    	          	          	                    
          	               	1         	268B4     	PVCCIN_CPU0_PVCC    
          	               	2         	268A4     	GND                 

PC273_P0_3	Q_CAP_C0402    	          	          	                    
          	               	1         	268B4     	PVCCIN_CPU0_PVCC    
          	               	2         	268B4     	GND                 

PC274_P0_4	Q_CAP_0402     	          	          	                    
          	               	1         	268B3     	SW_P12V_PVCCIN_CPU0_FLT
          	               	2         	268A3     	GND                 

PC275_P0_3	Q_CAP_0402     	          	          	                    
          	               	1         	268B3     	SW_P12V_PVCCIN_CPU0_FLT
          	               	2         	268B3     	GND                 

PC276_P0_4	Q_CAP_C0402    	          	          	                    
          	               	1         	268B3     	SW_P12V_PVCCIN_CPU0_FLT
          	               	2         	268A3     	GND                 

PC277_P0_3	Q_CAP_C0402    	          	          	                    
          	               	1         	268B3     	SW_P12V_PVCCIN_CPU0_FLT
          	               	2         	268B3     	GND                 

PC278     	Q_CAP_C0402    	          	          	                    
          	               	1         	268A2     	SW_PVCCIN_CPU0_BOOT4_R
          	               	2         	268A2     	SW_PVCCIN_CPU0_BOOTR4

PC279     	Q_CAP_C0402    	          	          	                    
          	               	1         	268B2     	SW_PVCCIN_CPU0_BOOT3_R
          	               	2         	268B2     	SW_PVCCIN_CPU0_BOOTR3

PC280_P0_4	Q_CAP_C0805    	          	          	                    
          	               	1         	268B2     	SW_P12V_PVCCIN_CPU0_FLT
          	               	2         	268A2     	GND                 

PC281_P0_3	Q_CAP_C0805    	          	          	                    
          	               	1         	268B2     	SW_P12V_PVCCIN_CPU0_FLT
          	               	2         	268B2     	GND                 

PC282_P0_4	Q_CAP_C0805    	          	          	                    
          	               	1         	268B2     	SW_P12V_PVCCIN_CPU0_FLT
          	               	2         	268A2     	GND                 

PC283_P0_3	Q_CAP_C0805    	          	          	                    
          	               	1         	268B2     	SW_P12V_PVCCIN_CPU0_FLT
          	               	2         	268B2     	GND                 

PC284_P0_4	Q_CAP_C0805    	          	          	                    
          	               	1         	268B2     	SW_P12V_PVCCIN_CPU0_FLT
          	               	2         	268A2     	GND                 

PC285_P0_3	Q_CAP_C0805    	          	          	                    
          	               	1         	268B2     	SW_P12V_PVCCIN_CPU0_FLT
          	               	2         	268B2     	GND                 

PC288_P0_4	Q_CAP_C0805    	          	          	                    
          	               	1         	268A1     	PVCCIN_CPU0         
          	               	2         	268A1     	GND                 

PC289_P0_3	Q_CAP_C0805    	          	          	                    
          	               	1         	268B1     	PVCCIN_CPU0         
          	               	2         	268B1     	GND                 

PC290_P0_4	Q_CAP_C0805    	          	          	                    
          	               	1         	268A1     	PVCCIN_CPU0         
          	               	2         	268A1     	GND                 

PC291_P0_3	Q_CAP_C0805    	          	          	                    
          	               	1         	268B1     	PVCCIN_CPU0         
          	               	2         	268B1     	GND                 

PC292     	Q_CAP_C0402    	          	          	                    
          	               	1         	267A4     	PVCCIN_CPU0_VDD2    
          	               	2         	267A4     	GND                 

PC293     	Q_CAP_C0402    	          	          	                    
          	               	1         	267B4     	PVCCIN_CPU0_VDD1    
          	               	2         	267B4     	GND                 

PC294_P0_2	Q_CAP_C0402    	          	          	                    
          	               	1         	267B4     	PVCCIN_CPU0_PVCC    
          	               	2         	267A4     	GND                 

PC295_P0_1	Q_CAP_C0402    	          	          	                    
          	               	1         	267B4     	PVCCIN_CPU0_PVCC    
          	               	2         	267B4     	GND                 

PC296_P0_2	Q_CAP_0402     	          	          	                    
          	               	1         	267B4     	SW_P12V_PVCCIN_CPU0_FLT
          	               	2         	267A4     	GND                 

PC297_P0_1	Q_CAP_0402     	          	          	                    
          	               	1         	267B3     	SW_P12V_PVCCIN_CPU0_FLT
          	               	2         	267B3     	GND                 

PC298_P0_2	Q_CAP_C0402    	          	          	                    
          	               	1         	267B3     	SW_P12V_PVCCIN_CPU0_FLT
          	               	2         	267A3     	GND                 

PC299_P0_1	Q_CAP_C0402    	          	          	                    
          	               	1         	267B3     	SW_P12V_PVCCIN_CPU0_FLT
          	               	2         	267B3     	GND                 

PC300     	Q_CAP_C0402    	          	          	                    
          	               	1         	267A3     	SW_PVCCIN_CPU0_BOOT2_R
          	               	2         	267A3     	SW_PVCCIN_CPU0_BOOTR2

PC301     	Q_CAP_C0402    	          	          	                    
          	               	1         	267B3     	SW_PVCCIN_CPU0_BOOT1_R
          	               	2         	267B3     	SW_PVCCIN_CPU0_BOOTR1

PC302_P0_2	Q_CAP_C0805    	          	          	                    
          	               	1         	267B3     	SW_P12V_PVCCIN_CPU0_FLT
          	               	2         	267A3     	GND                 

PC303_P0_1	Q_CAP_C0805    	          	          	                    
          	               	1         	267B3     	SW_P12V_PVCCIN_CPU0_FLT
          	               	2         	267B3     	GND                 

PC304_P0_2	Q_CAP_C0805    	          	          	                    
          	               	1         	267B3     	SW_P12V_PVCCIN_CPU0_FLT
          	               	2         	267A3     	GND                 

PC305_P0_1	Q_CAP_C0805    	          	          	                    
          	               	1         	267B3     	SW_P12V_PVCCIN_CPU0_FLT
          	               	2         	267B3     	GND                 

PC306_P0_2	Q_CAP_C0805    	          	          	                    
          	               	1         	267B3     	SW_P12V_PVCCIN_CPU0_FLT
          	               	2         	267A3     	GND                 

PC307_P0_1	Q_CAP_C0805    	          	          	                    
          	               	1         	267B3     	SW_P12V_PVCCIN_CPU0_FLT
          	               	2         	267B3     	GND                 

PC308_P0_1	Q_CAP_C0402    	          	          	                    
          	               	1         	267B2     	PVCCIN_CPU0         
          	               	2         	267B2     	GND                 

PC310_P0_1	Q_CAP_C0402    	          	          	                    
          	               	1         	267B2     	PVCCIN_CPU0         
          	               	2         	267B2     	GND                 

PC311_P0_2	Q_CAP_C0805    	          	          	                    
          	               	1         	267A1     	PVCCIN_CPU0         
          	               	2         	267A1     	GND                 

PC312_P0_1	Q_CAP_C0805    	          	          	                    
          	               	1         	267B1     	PVCCIN_CPU0         
          	               	2         	267B1     	GND                 

PC313_P0_2	Q_CAP_C0805    	          	          	                    
          	               	1         	267A1     	PVCCIN_CPU0         
          	               	2         	267A1     	GND                 

PC314_P0_1	Q_CAP_C0805    	          	          	                    
          	               	1         	267B1     	PVCCIN_CPU0         
          	               	2         	267B1     	GND                 

PC315     	Q_CAPP_THLF    	          	          	                    
          	               	1         	267B2     	SW_P12V_PVCCIN_CPU0_FLT
          	               	2         	267B2     	GND                 

PC316     	Q_CAPP_THLF    	          	          	                    
          	               	1         	267B2     	PVCCIN_CPU0         
          	               	2         	267B2     	GND                 

PC318     	Q_CAPP_THLF    	          	          	                    
          	               	1         	267B1     	SW_P12V_PVCCIN_CPU0_FLT
          	               	2         	267B1     	GND                 

PC319     	Q_CAPP_THLF    	          	          	                    
          	               	1         	267B1     	PVCCIN_CPU0         
          	               	2         	267B1     	GND                 

PC321     	Q_CAPP_THLF    	          	          	                    
          	               	1         	267B1     	SW_P12V_PVCCIN_CPU0_FLT
          	               	2         	267B1     	GND                 

PC322     	Q_CAPP_THLF    	          	          	                    
          	               	1         	267B1     	PVCCIN_CPU0         
          	               	2         	267B1     	GND                 

PC323     	Q_CAPP_SMLF    	          	          	                    
          	               	1         	267A1     	PVCCIN_CPU0         
          	               	2         	267A1     	GND                 

PC324     	Q_CAPP_THLF    	          	          	                    
          	               	1         	267B1     	SW_P12V_PVCCIN_CPU0_FLT
          	               	2         	267B1     	GND                 

PC325     	Q_CAPP_THLF    	          	          	                    
          	               	1         	267B1     	PVCCIN_CPU0         
          	               	2         	267B1     	GND                 

PC326     	Q_CAPP_SMLF    	          	          	                    
          	               	1         	267A1     	PVCCIN_CPU0         
          	               	2         	267A1     	GND                 

PC329     	Q_CAP_0402     	          	          	                    
          	               	1         	266A4     	PVCCIN_CPU0_CSPIN   
          	               	2         	266A4     	GND                 

PC330     	Q_CAP_0402     	          	          	                    
          	               	1         	266A3     	PVCCIN_CPU0_VIN_CSNIN
          	               	2         	266A3     	GND                 

PC331     	Q_CAP_0402     	          	          	                    
          	               	1         	266B4     	SH_PVCCIN_CPU0_R    
          	               	2         	266B4     	VSENSE_PVCCIN_CPU0_DN

PC334     	Q_CAP_0402     	          	          	                    
          	               	1         	266B2     	PVCCIN_CPU0_VCC     
          	               	2         	266B2     	GND                 

PC335     	Q_CAP_C0402    	          	          	                    
          	               	1         	266B2     	PVCCIN_CPU0_VREF    
          	               	2         	266B2     	GND                 

PC336     	Q_CAP_0402     	          	          	                    
          	               	1         	266A2     	PVCCIN_CPU0_ATSEN   
          	               	2         	266A2     	GND                 

PC337     	Q_CAP_C0402    	          	          	                    
          	               	1         	266B2     	PVCCIN_CPU0_VCC     
          	               	2         	266B2     	GND                 

PC373     	Q_CAP_C0402    	          	          	                    
          	               	1         	297B4     	PVCCD_HV_CPU1_VDD1  
          	               	2         	297B4     	GND                 

PC374     	Q_CAP_0402     	          	          	                    
          	               	1         	297B3     	SW_P12V_PVCCINFAON_CPU1_FLT
          	               	2         	297B3     	GND                 

PC375     	Q_CAP_C0402    	          	          	                    
          	               	1         	297B3     	SW_P12V_PVCCINFAON_CPU1_FLT
          	               	2         	297B3     	GND                 

PC376     	Q_CAP_C0402    	          	          	                    
          	               	1         	297B3     	SW_PVCCD_HV_CPU1_BOOT1_R
          	               	2         	297B3     	SW_PVCCD_HV_CPU1_BOOTR1

PC377     	Q_CAP_C0805    	          	          	                    
          	               	1         	297B3     	SW_P12V_PVCCINFAON_CPU1_FLT
          	               	2         	297B3     	GND                 

PC378     	Q_CAP_C0805    	          	          	                    
          	               	1         	297B3     	SW_P12V_PVCCINFAON_CPU1_FLT
          	               	2         	297B3     	GND                 

PC379     	Q_CAP_C0402    	          	          	                    
          	               	1         	297B2     	PVCCD_HV_CPU1       
          	               	2         	297B2     	GND                 

PC381     	Q_CAP_C0805    	          	          	                    
          	               	1         	297B2     	PVCCD_HV_CPU1       
          	               	2         	297B2     	GND                 

PC382     	Q_CAP_C0805    	          	          	                    
          	               	1         	297B2     	PVCCD_HV_CPU1       
          	               	2         	297B2     	GND                 

PC384     	Q_CAPP_THLF    	          	          	                    
          	               	1         	297A2     	PVCCD_HV_CPU1       
          	               	2         	297A2     	GND                 

PC385     	Q_CAPP_THLF    	          	          	                    
          	               	1         	297A1     	PVCCD_HV_CPU1       
          	               	2         	297A1     	GND                 

PC386     	Q_CAP_0402     	          	          	                    
          	               	1         	296A4     	PVCCD_HV_CPU1_ISENSE_P
          	               	2         	296A4     	GND                 

PC389     	Q_CAP_0402     	          	          	                    
          	               	1         	296B3     	SH_PVCCD_HV_CPU1_R  
          	               	2         	296B3     	VSENSE_PVCCD_HV_CPU1_DN

PC390     	Q_CAP_0402     	          	          	                    
          	               	1         	296A3     	PVCCD_HV_CPU1_ISENSE_N
          	               	2         	296A3     	GND                 

PC391     	Q_CAP_C0402    	          	          	                    
          	               	1         	296B2     	PVCCD_HV_CPU1_VCC   
          	               	2         	296B2     	GND                 

PC392     	Q_CAP_C0402    	          	          	                    
          	               	1         	296B2     	PVCCD_HV_CPU1_VREF  
          	               	2         	296B2     	GND                 

PC393     	Q_CAP_0402     	          	          	                    
          	               	1         	296A2     	PVCCD_HV_CPU1_ATSEN 
          	               	2         	296A2     	GND                 

PC394     	Q_CAP_C0402    	          	          	                    
          	               	1         	296B2     	PVCCD_HV_CPU1_VCC   
          	               	2         	296B2     	GND                 

PC395     	Q_CAP_C0402    	          	          	                    
          	               	1         	289B4     	PVCCFA_EHV_FIVRA_CPU1_VDD1
          	               	2         	289B4     	GND                 

PC396     	Q_CAP_C0402    	          	          	                    
          	               	1         	289A4     	PVCCFA_EHV_FIVRA_CPU1_VDD2
          	               	2         	289A4     	GND                 

PC397_P1_1	Q_CAP_0402     	          	          	                    
          	               	1         	289B3     	SW_P12V_PVCCFA_EHV_FIVRA_CPU1_R
          	               	2         	289B3     	GND                 

PC398_P1_2	Q_CAP_0402     	          	          	                    
          	               	1         	289A3     	SW_P12V_PVCCFA_EHV_FIVRA_CPU1_L
          	               	2         	289A3     	GND                 

PC399_P1_1	Q_CAP_C0402    	          	          	                    
          	               	1         	289B3     	SW_P12V_PVCCFA_EHV_FIVRA_CPU1_R
          	               	2         	289B3     	GND                 

PC400_P1_2	Q_CAP_C0402    	          	          	                    
          	               	1         	289A3     	SW_P12V_PVCCFA_EHV_FIVRA_CPU1_L
          	               	2         	289A3     	GND                 

PC401     	Q_CAP_C0402    	          	          	                    
          	               	1         	289B3     	SW_PVCCFA_EHV_FIVRA_CPU1_BOOT1_
          	               	2         	289B3     	SW_PVCCFA_EHV_FIVRA_CPU1_BOOTR1

PC402     	Q_CAP_C0402    	          	          	                    
          	               	1         	289A3     	SW_PVCCFA_EHV_FIVRA_CPU1_BOOT2_
          	               	2         	289A3     	SW_PVCCFA_EHV_FIVRA_CPU1_BOOTR2

PC403_P1_1	Q_CAP_C0805    	          	          	                    
          	               	1         	289B3     	SW_P12V_PVCCFA_EHV_FIVRA_CPU1_R
          	               	2         	289B3     	GND                 

PC404_P1_2	Q_CAP_C0805    	          	          	                    
          	               	1         	289A3     	SW_P12V_PVCCFA_EHV_FIVRA_CPU1_L
          	               	2         	289A3     	GND                 

PC405_P1_1	Q_CAP_C0805    	          	          	                    
          	               	1         	289B3     	SW_P12V_PVCCFA_EHV_FIVRA_CPU1_R
          	               	2         	289B3     	GND                 

PC406_P1_2	Q_CAP_C0805    	          	          	                    
          	               	1         	289A3     	SW_P12V_PVCCFA_EHV_FIVRA_CPU1_L
          	               	2         	289A3     	GND                 

PC408_P1_2	Q_CAP_C0402    	          	          	                    
          	               	1         	289A2     	PVCCFA_EHV_FIVRA_CPU1
          	               	2         	289A2     	GND                 

PC410_P1_1	Q_CAP_C0805    	          	          	                    
          	               	1         	289B2     	PVCCFA_EHV_FIVRA_CPU1
          	               	2         	289B2     	GND                 

PC411_P1_2	Q_CAP_C0805    	          	          	                    
          	               	1         	289A2     	PVCCFA_EHV_FIVRA_CPU1
          	               	2         	289A2     	GND                 

PC412_P1_1	Q_CAP_C0805    	          	          	                    
          	               	1         	289B1     	PVCCFA_EHV_FIVRA_CPU1
          	               	2         	289B1     	GND                 

PC413_P1_2	Q_CAP_C0805    	          	          	                    
          	               	1         	289A1     	PVCCFA_EHV_FIVRA_CPU1
          	               	2         	289A1     	GND                 

PC414     	Q_CAPP_THLF    	          	          	                    
          	               	1         	289A2     	PVCCFA_EHV_FIVRA_CPU1
          	               	2         	289A2     	GND                 

PC415     	Q_CAPP_THLF    	          	          	                    
          	               	1         	289A2     	PVCCFA_EHV_FIVRA_CPU1
          	               	2         	289A2     	GND                 

PC416     	Q_CAPP_THLF    	          	          	                    
          	               	1         	289A1     	PVCCFA_EHV_FIVRA_CPU1
          	               	2         	289A1     	GND                 

PC417     	Q_CAPP_THLF    	          	          	                    
          	               	1         	289B1     	SW_P12V_PVCCFA_EHV_FIVRA_CPU1_L
          	               	2         	289B1     	GND                 

PC418     	Q_CAPP_SMLF    	          	          	                    
          	               	1         	289A1     	PVCCFA_EHV_FIVRA_CPU1
          	               	2         	289A1     	GND                 

PC422     	Q_CAP_0402     	          	          	                    
          	               	1         	284B3     	SH_PVCCFA_EHV_FIVRA_CPU1_R
          	               	2         	284B3     	VSENSE_PVCCFA_EHV_FIVRA_CPU1_DN

PC428     	Q_CAP_C0402    	          	          	                    
          	               	1         	294B4     	PVCCFA_EHV_CPU1_VDD1
          	               	2         	294B4     	GND                 

PC429     	Q_CAP_0402     	          	          	                    
          	               	1         	294B3     	SW_P12V_PVCCINFAON_CPU1_FLT
          	               	2         	294B3     	GND                 

PC430     	Q_CAP_C0402    	          	          	                    
          	               	1         	294B3     	SW_P12V_PVCCINFAON_CPU1_FLT
          	               	2         	294B3     	GND                 

PC431     	Q_CAP_C0402    	          	          	                    
          	               	1         	294B2     	SW_PVCCFA_EHV_CPU1_BOOT1_R
          	               	2         	294B2     	SW_PVCCFA_EHV_CPU1_BOOTR1

PC432     	Q_CAP_C0805    	          	          	                    
          	               	1         	294B3     	SW_P12V_PVCCINFAON_CPU1_FLT
          	               	2         	294B3     	GND                 

PC433     	Q_CAP_C0805    	          	          	                    
          	               	1         	294B2     	SW_P12V_PVCCINFAON_CPU1_FLT
          	               	2         	294B2     	GND                 

PC434     	Q_CAP_C0402    	          	          	                    
          	               	1         	294B2     	PVCCFA_EHV_CPU1     
          	               	2         	294B2     	GND                 

PC435     	Q_CAP_C0805    	          	          	                    
          	               	1         	294B2     	PVCCFA_EHV_CPU1     
          	               	2         	294B2     	GND                 

PC437     	Q_CAP_C0805    	          	          	                    
          	               	1         	294B2     	PVCCFA_EHV_CPU1     
          	               	2         	294B2     	GND                 

PC440     	Q_CAP_C0402    	          	          	                    
          	               	1         	293B4     	PVCCINFAON_CPU1_VDD1
          	               	2         	293B4     	GND                 

PC441     	Q_CAP_C0402    	          	          	                    
          	               	1         	293A4     	PVCCINFAON_CPU1_VDD2
          	               	2         	293A4     	GND                 

PC442_P1_1	Q_CAP_0402     	          	          	                    
          	               	1         	293B3     	SW_P12V_PVCCINFAON_CPU1_FLT
          	               	2         	293B3     	GND                 

PC443_P1_2	Q_CAP_0402     	          	          	                    
          	               	1         	293A3     	SW_P12V_PVCCINFAON_CPU1_FLT
          	               	2         	293A3     	GND                 

PC444_P1_1	Q_CAP_C0402    	          	          	                    
          	               	1         	293B3     	SW_P12V_PVCCINFAON_CPU1_FLT
          	               	2         	293B3     	GND                 

PC445_P1_2	Q_CAP_C0402    	          	          	                    
          	               	1         	293A3     	SW_P12V_PVCCINFAON_CPU1_FLT
          	               	2         	293A3     	GND                 

PC446     	Q_CAP_C0402    	          	          	                    
          	               	1         	293B3     	SW_PVCCINFAON_CPU1_BOOT1_R
          	               	2         	293B3     	SW_PVCCINFAON_CPU1_BOOTR1

PC447     	Q_CAP_C0402    	          	          	                    
          	               	1         	293A3     	SW_PVCCINFAON_CPU1_BOOT2_R
          	               	2         	293A3     	SW_PVCCINFAON_CPU1_BOOTR2

PC448_P1_1	Q_CAP_C0805    	          	          	                    
          	               	1         	293B3     	SW_P12V_PVCCINFAON_CPU1_FLT
          	               	2         	293B3     	GND                 

PC449_P1_2	Q_CAP_C0805    	          	          	                    
          	               	1         	293A3     	SW_P12V_PVCCINFAON_CPU1_FLT
          	               	2         	293A3     	GND                 

PC450_P1_1	Q_CAP_C0805    	          	          	                    
          	               	1         	293B3     	SW_P12V_PVCCINFAON_CPU1_FLT
          	               	2         	293B3     	GND                 

PC451_P1_2	Q_CAP_C0805    	          	          	                    
          	               	1         	293A3     	SW_P12V_PVCCINFAON_CPU1_FLT
          	               	2         	293A3     	GND                 

PC452_P1_1	Q_CAP_C0402    	          	          	                    
          	               	1         	293B2     	PVCCINFAON_CPU1     
          	               	2         	293B2     	GND                 

PC455_P1_1	Q_CAP_C0805    	          	          	                    
          	               	1         	293B2     	PVCCINFAON_CPU1     
          	               	2         	293B2     	GND                 

PC456_P1_2	Q_CAP_C0805    	          	          	                    
          	               	1         	293A2     	PVCCINFAON_CPU1     
          	               	2         	293A2     	GND                 

PC457_P1_1	Q_CAP_C0805    	          	          	                    
          	               	1         	293B2     	PVCCINFAON_CPU1     
          	               	2         	293B2     	GND                 

PC458_P1_2	Q_CAP_C0805    	          	          	                    
          	               	1         	293A2     	PVCCINFAON_CPU1     
          	               	2         	293A2     	GND                 

PC460     	Q_CAPP_THLF    	          	          	                    
          	               	1         	293B2     	SW_P12V_PVCCINFAON_CPU1_FLT
          	               	2         	293B2     	GND                 

PC461     	Q_CAPP_THLF    	          	          	                    
          	               	1         	293B1     	SW_P12V_PVCCINFAON_CPU1_FLT
          	               	2         	293B1     	GND                 

PC467     	Q_CAP_0402     	          	          	                    
          	               	1         	292A4     	PVCCINFAON_CPU1_CSPIN
          	               	2         	292A4     	GND                 

PC468     	Q_CAP_0402     	          	          	                    
          	               	1         	292B4     	SH_PVCCINFAON_CPU1_R
          	               	2         	292B4     	VSENSE_PVCCINFAON_CPU1_DN

PC469     	Q_CAP_0402     	          	          	                    
          	               	1         	292B4     	SH_PVCCFA_EHV_CPU1_R
          	               	2         	292B4     	VSENSE_PVCCFA_EHV_CPU1_DN

PC474     	Q_CAP_0402     	          	          	                    
          	               	1         	292A3     	PVCCINFAON_CPU1_VIN_CSNIN
          	               	2         	292A3     	GND                 

PC475     	Q_CAP_0402     	          	          	                    
          	               	1         	292A2     	PVCCINFAON_CPU1_ATSEN
          	               	2         	292A2     	GND                 

PC476     	Q_CAP_C0402    	          	          	                    
          	               	1         	292B2     	PVCCINFAON_CPU1_VCC 
          	               	2         	292B2     	GND                 

PC477     	Q_CAP_C0402    	          	          	                    
          	               	1         	292B2     	PVCCINFAON_CPU1_VREF
          	               	2         	292B2     	GND                 

PC478     	Q_CAP_C0402    	          	          	                    
          	               	1         	292B2     	PVCCINFAON_CPU1_VCC 
          	               	2         	292B2     	GND                 

PC479     	Q_CAP_C0402    	          	          	                    
          	               	1         	288A4     	PVCCIN_CPU1_VDD8    
          	               	2         	288A4     	GND                 

PC480     	Q_CAP_C0402    	          	          	                    
          	               	1         	288B4     	PVCCIN_CPU1_VDD7    
          	               	2         	288B4     	GND                 

PC481_P1_8	Q_CAP_C0402    	          	          	                    
          	               	1         	288B4     	PVCCIN_CPU1_PVCC    
          	               	2         	288A4     	GND                 

PC482_P1_7	Q_CAP_C0402    	          	          	                    
          	               	1         	288B4     	PVCCIN_CPU1_PVCC    
          	               	2         	288B4     	GND                 

PC483_P1_8	Q_CAP_0402     	          	          	                    
          	               	1         	288B3     	SW_P12V_PVCCIN_CPU1_FLT
          	               	2         	288A3     	GND                 

PC484_P1_7	Q_CAP_0402     	          	          	                    
          	               	1         	288B3     	SW_P12V_PVCCIN_CPU1_FLT
          	               	2         	288B3     	GND                 

PC485_P1_8	Q_CAP_C0402    	          	          	                    
          	               	1         	288B3     	SW_P12V_PVCCIN_CPU1_FLT
          	               	2         	288A3     	GND                 

PC486_P1_7	Q_CAP_C0402    	          	          	                    
          	               	1         	288B3     	SW_P12V_PVCCIN_CPU1_FLT
          	               	2         	288B3     	GND                 

PC487     	Q_CAP_C0402    	          	          	                    
          	               	1         	288A2     	SW_PVCCIN_CPU1_BOOT8_R
          	               	2         	288A2     	SW_PVCCIN_CPU1_BOOTR8

PC488     	Q_CAP_C0402    	          	          	                    
          	               	1         	288B2     	SW_PVCCIN_CPU1_BOOT7_R
          	               	2         	288B2     	SW_PVCCIN_CPU1_BOOTR7

PC489_P1_8	Q_CAP_C0805    	          	          	                    
          	               	1         	288B3     	SW_P12V_PVCCIN_CPU1_FLT
          	               	2         	288A3     	GND                 

PC490_P1_7	Q_CAP_C0805    	          	          	                    
          	               	1         	288B3     	SW_P12V_PVCCIN_CPU1_FLT
          	               	2         	288B3     	GND                 

PC491_P1_8	Q_CAP_C0805    	          	          	                    
          	               	1         	288B2     	SW_P12V_PVCCIN_CPU1_FLT
          	               	2         	288A2     	GND                 

PC492_P1_7	Q_CAP_C0805    	          	          	                    
          	               	1         	288B2     	SW_P12V_PVCCIN_CPU1_FLT
          	               	2         	288B2     	GND                 

PC493_P1_8	Q_CAP_C0805    	          	          	                    
          	               	1         	288B2     	SW_P12V_PVCCIN_CPU1_FLT
          	               	2         	288A2     	GND                 

PC494_P1_7	Q_CAP_C0805    	          	          	                    
          	               	1         	288B2     	SW_P12V_PVCCIN_CPU1_FLT
          	               	2         	288B2     	GND                 

PC495_P1_8	Q_CAP_C0402    	          	          	                    
          	               	1         	288A1     	PVCCIN_CPU1         
          	               	2         	288A1     	GND                 

PC496_P1_7	Q_CAP_C0402    	          	          	                    
          	               	1         	288B1     	PVCCIN_CPU1         
          	               	2         	288B1     	GND                 

PC497_P1_8	Q_CAP_C0805    	          	          	                    
          	               	1         	288A1     	PVCCIN_CPU1         
          	               	2         	288A1     	GND                 

PC498_P1_7	Q_CAP_C0805    	          	          	                    
          	               	1         	288B1     	PVCCIN_CPU1         
          	               	2         	288B1     	GND                 

PC499_P1_8	Q_CAP_C0805    	          	          	                    
          	               	1         	288A1     	PVCCIN_CPU1         
          	               	2         	288A1     	GND                 

PC500_P1_7	Q_CAP_C0805    	          	          	                    
          	               	1         	288B1     	PVCCIN_CPU1         
          	               	2         	288B1     	GND                 

PC501     	Q_CAP_C0402    	          	          	                    
          	               	1         	287A4     	PVCCIN_CPU1_VDD6    
          	               	2         	287A4     	GND                 

PC502     	Q_CAP_C0402    	          	          	                    
          	               	1         	287B4     	PVCCIN_CPU1_VDD5    
          	               	2         	287B4     	GND                 

PC503_P1_6	Q_CAP_C0402    	          	          	                    
          	               	1         	287B4     	PVCCIN_CPU1_PVCC    
          	               	2         	287A4     	GND                 

PC504_P1_5	Q_CAP_C0402    	          	          	                    
          	               	1         	287B4     	PVCCIN_CPU1_PVCC    
          	               	2         	287B4     	GND                 

PC505_P1_6	Q_CAP_0402     	          	          	                    
          	               	1         	287A3     	SW_P12V_PVCCIN_CPU1_FLT
          	               	2         	287A3     	GND                 

PC506_P1_5	Q_CAP_0402     	          	          	                    
          	               	1         	287B3     	SW_P12V_PVCCIN_CPU1_FLT
          	               	2         	287B3     	GND                 

PC507_P1_6	Q_CAP_C0402    	          	          	                    
          	               	1         	287A3     	SW_P12V_PVCCIN_CPU1_FLT
          	               	2         	287A3     	GND                 

PC508_P1_5	Q_CAP_C0402    	          	          	                    
          	               	1         	287B3     	SW_P12V_PVCCIN_CPU1_FLT
          	               	2         	287B3     	GND                 

PC509     	Q_CAP_C0402    	          	          	                    
          	               	1         	287A2     	SW_PVCCIN_CPU1_BOOT6_R
          	               	2         	287A2     	SW_PVCCIN_CPU1_BOOTR6

PC510     	Q_CAP_C0402    	          	          	                    
          	               	1         	287B2     	SW_PVCCIN_CPU1_BOOT5_R
          	               	2         	287B2     	SW_PVCCIN_CPU1_BOOTR5

PC511_P1_6	Q_CAP_C0805    	          	          	                    
          	               	1         	287A3     	SW_P12V_PVCCIN_CPU1_FLT
          	               	2         	287A3     	GND                 

PC512_P1_5	Q_CAP_C0805    	          	          	                    
          	               	1         	287B3     	SW_P12V_PVCCIN_CPU1_FLT
          	               	2         	287B3     	GND                 

PC513_P1_6	Q_CAP_C0805    	          	          	                    
          	               	1         	287A2     	SW_P12V_PVCCIN_CPU1_FLT
          	               	2         	287A2     	GND                 

PC514_P1_5	Q_CAP_C0805    	          	          	                    
          	               	1         	287B2     	SW_P12V_PVCCIN_CPU1_FLT
          	               	2         	287B2     	GND                 

PC515_P1_6	Q_CAP_C0805    	          	          	                    
          	               	1         	287A2     	SW_P12V_PVCCIN_CPU1_FLT
          	               	2         	287A2     	GND                 

PC516_P1_5	Q_CAP_C0805    	          	          	                    
          	               	1         	287B2     	SW_P12V_PVCCIN_CPU1_FLT
          	               	2         	287B2     	GND                 

PC519_P1_6	Q_CAP_C0805    	          	          	                    
          	               	1         	287A1     	PVCCIN_CPU1         
          	               	2         	287A1     	GND                 

PC520_P1_5	Q_CAP_C0805    	          	          	                    
          	               	1         	287B1     	PVCCIN_CPU1         
          	               	2         	287B1     	GND                 

PC521_P1_6	Q_CAP_C0805    	          	          	                    
          	               	1         	287A1     	PVCCIN_CPU1         
          	               	2         	287A1     	GND                 

PC522_P1_5	Q_CAP_C0805    	          	          	                    
          	               	1         	287B1     	PVCCIN_CPU1         
          	               	2         	287B1     	GND                 

PC523     	Q_CAP_C0402    	          	          	                    
          	               	1         	286A4     	PVCCIN_CPU1_VDD4    
          	               	2         	286A4     	GND                 

PC524     	Q_CAP_C0402    	          	          	                    
          	               	1         	286B4     	PVCCIN_CPU1_VDD3    
          	               	2         	286B4     	GND                 

PC525_P1_4	Q_CAP_C0402    	          	          	                    
          	               	1         	286B4     	PVCCIN_CPU1_PVCC    
          	               	2         	286B4     	GND                 

PC526_P1_3	Q_CAP_C0402    	          	          	                    
          	               	1         	286B4     	PVCCIN_CPU1_PVCC    
          	               	2         	286B4     	GND                 

PC527_P1_4	Q_CAP_0402     	          	          	                    
          	               	1         	286B3     	SW_P12V_PVCCIN_CPU1_FLT
          	               	2         	286B3     	GND                 

PC528_P1_3	Q_CAP_0402     	          	          	                    
          	               	1         	286B3     	SW_P12V_PVCCIN_CPU1_FLT
          	               	2         	286B3     	GND                 

PC529_P1_4	Q_CAP_C0402    	          	          	                    
          	               	1         	286B3     	SW_P12V_PVCCIN_CPU1_FLT
          	               	2         	286B3     	GND                 

PC530_P1_3	Q_CAP_C0402    	          	          	                    
          	               	1         	286B3     	SW_P12V_PVCCIN_CPU1_FLT
          	               	2         	286B3     	GND                 

PC531     	Q_CAP_C0402    	          	          	                    
          	               	1         	286A2     	SW_PVCCIN_CPU1_BOOT4_R
          	               	2         	286A2     	SW_PVCCIN_CPU1_BOOTR4

PC532     	Q_CAP_C0402    	          	          	                    
          	               	1         	286B2     	SW_PVCCIN_CPU1_BOOT3_R
          	               	2         	286B2     	SW_PVCCIN_CPU1_BOOTR3

PC533_P1_4	Q_CAP_C0805    	          	          	                    
          	               	1         	286B2     	SW_P12V_PVCCIN_CPU1_FLT
          	               	2         	286B2     	GND                 

PC534_P1_3	Q_CAP_C0805    	          	          	                    
          	               	1         	286B2     	SW_P12V_PVCCIN_CPU1_FLT
          	               	2         	286B2     	GND                 

PC535_P1_4	Q_CAP_C0805    	          	          	                    
          	               	1         	286B2     	SW_P12V_PVCCIN_CPU1_FLT
          	               	2         	286B2     	GND                 

PC536_P1_3	Q_CAP_C0805    	          	          	                    
          	               	1         	286B2     	SW_P12V_PVCCIN_CPU1_FLT
          	               	2         	286B2     	GND                 

PC537_P1_4	Q_CAP_C0805    	          	          	                    
          	               	1         	286B2     	SW_P12V_PVCCIN_CPU1_FLT
          	               	2         	286B2     	GND                 

PC538_P1_3	Q_CAP_C0805    	          	          	                    
          	               	1         	286B2     	SW_P12V_PVCCIN_CPU1_FLT
          	               	2         	286B2     	GND                 

PC541_P1_4	Q_CAP_C0805    	          	          	                    
          	               	1         	286A1     	PVCCIN_CPU1         
          	               	2         	286A1     	GND                 

PC542_P1_3	Q_CAP_C0805    	          	          	                    
          	               	1         	286B1     	PVCCIN_CPU1         
          	               	2         	286B1     	GND                 

PC543_P1_4	Q_CAP_C0805    	          	          	                    
          	               	1         	286A1     	PVCCIN_CPU1         
          	               	2         	286A1     	GND                 

PC544_P1_3	Q_CAP_C0805    	          	          	                    
          	               	1         	286B1     	PVCCIN_CPU1         
          	               	2         	286B1     	GND                 

PC547     	Q_CAP_0402     	          	          	                    
          	               	1         	284A4     	PVCCIN_CPU1_CSPIN   
          	               	2         	284A4     	GND                 

PC548     	Q_CAP_0402     	          	          	                    
          	               	1         	284A3     	PVCCIN_CPU1_VIN_CSNIN
          	               	2         	284A3     	GND                 

PC549     	Q_CAP_0402     	          	          	                    
          	               	1         	284B4     	SH_PVCCIN_CPU1_R    
          	               	2         	284B4     	VSENSE_PVCCIN_CPU1_DN

PC552     	Q_CAP_C0402    	          	          	                    
          	               	1         	284B2     	PVCCIN_CPU1_VCC     
          	               	2         	284B2     	GND                 

PC553     	Q_CAP_C0402    	          	          	                    
          	               	1         	284B2     	PVCCIN_CPU1_VREF    
          	               	2         	284B2     	GND                 

PC554     	Q_CAP_0402     	          	          	                    
          	               	1         	284A2     	PVCCIN_CPU1_ATSEN   
          	               	2         	284A2     	GND                 

PC555     	Q_CAP_C0402    	          	          	                    
          	               	1         	284B2     	PVCCIN_CPU1_VCC     
          	               	2         	284B2     	GND                 

PC556     	Q_CAP_C0402    	          	          	                    
          	               	1         	285A4     	PVCCIN_CPU1_VDD2    
          	               	2         	285A4     	GND                 

PC557     	Q_CAP_C0402    	          	          	                    
          	               	1         	285B4     	PVCCIN_CPU1_VDD1    
          	               	2         	285B4     	GND                 

PC558_P1_2	Q_CAP_C0402    	          	          	                    
          	               	1         	285B4     	PVCCIN_CPU1_PVCC    
          	               	2         	285A4     	GND                 

PC559_P1_1	Q_CAP_C0402    	          	          	                    
          	               	1         	285B4     	PVCCIN_CPU1_PVCC    
          	               	2         	285B4     	GND                 

PC560_P1_2	Q_CAP_0402     	          	          	                    
          	               	1         	285B3     	SW_P12V_PVCCIN_CPU1_FLT
          	               	2         	285A3     	GND                 

PC561_P1_1	Q_CAP_0402     	          	          	                    
          	               	1         	285B3     	SW_P12V_PVCCIN_CPU1_FLT
          	               	2         	285B3     	GND                 

PC562_P1_2	Q_CAP_C0402    	          	          	                    
          	               	1         	285B3     	SW_P12V_PVCCIN_CPU1_FLT
          	               	2         	285A3     	GND                 

PC563_P1_1	Q_CAP_C0402    	          	          	                    
          	               	1         	285B3     	SW_P12V_PVCCIN_CPU1_FLT
          	               	2         	285B3     	GND                 

PC564     	Q_CAP_C0402    	          	          	                    
          	               	1         	285A3     	SW_PVCCIN_CPU1_BOOT2_R
          	               	2         	285A3     	SW_PVCCIN_CPU1_BOOTR2

PC565     	Q_CAP_C0402    	          	          	                    
          	               	1         	285B3     	SW_PVCCIN_CPU1_BOOT1_R
          	               	2         	285B3     	SW_PVCCIN_CPU1_BOOTR1

PC566     	Q_CAPP_THLF    	          	          	                    
          	               	1         	259B4     	SW_P3V3_AUX_FLT     
          	               	2         	259B4     	GND                 

PC566_P1_2	Q_CAP_C0805    	          	          	                    
          	               	1         	285B3     	SW_P12V_PVCCIN_CPU1_FLT
          	               	2         	285A3     	GND                 

PC567     	Q_CAP_C0805    	          	          	                    
          	               	1         	259B4     	SW_P3V3_AUX_FLT     
          	               	2         	259B4     	GND                 

PC567_P1_1	Q_CAP_C0805    	          	          	                    
          	               	1         	285B3     	SW_P12V_PVCCIN_CPU1_FLT
          	               	2         	285B3     	GND                 

PC568     	Q_CAP_C0402    	          	          	                    
          	               	1         	259B2     	SW_P3V3_AUX_BOOTR   
          	               	2         	259B2     	SW_P3V3_AUX_BOOT_R  

PC568_P1_2	Q_CAP_C0805    	          	          	                    
          	               	1         	285B3     	SW_P12V_PVCCIN_CPU1_FLT
          	               	2         	285A3     	GND                 

PC569     	Q_CAP_0402     	          	          	                    
          	               	1         	259A2     	P3V3_AUX_FB         
          	               	2         	259A2     	P3V3_AUX            

PC569_P1_1	Q_CAP_C0805    	          	          	                    
          	               	1         	285B3     	SW_P12V_PVCCIN_CPU1_FLT
          	               	2         	285B3     	GND                 

PC570     	Q_CAP_C0805    	          	          	                    
          	               	1         	259B4     	SW_P3V3_AUX_FLT     
          	               	2         	259B4     	GND                 

PC570_P1_2	Q_CAP_C0805    	          	          	                    
          	               	1         	285B3     	SW_P12V_PVCCIN_CPU1_FLT
          	               	2         	285A3     	GND                 

PC571     	Q_CAP_C0805    	          	          	                    
          	               	1         	259B4     	SW_P3V3_AUX_FLT     
          	               	2         	259B4     	GND                 

PC571_P1_1	Q_CAP_C0805    	          	          	                    
          	               	1         	285B3     	SW_P12V_PVCCIN_CPU1_FLT
          	               	2         	285B3     	GND                 

PC572_P1_1	Q_CAP_C0402    	          	          	                    
          	               	1         	285B2     	PVCCIN_CPU1         
          	               	2         	285B2     	GND                 

PC574_P1_1	Q_CAP_C0402    	          	          	                    
          	               	1         	285B1     	PVCCIN_CPU1         
          	               	2         	285B1     	GND                 

PC575_P1_2	Q_CAP_C0805    	          	          	                    
          	               	1         	285A1     	PVCCIN_CPU1         
          	               	2         	285A1     	GND                 

PC576     	Q_CAP_C0805    	          	          	                    
          	               	1         	259B4     	SW_P3V3_AUX_FLT     
          	               	2         	259B4     	GND                 

PC576_P1_1	Q_CAP_C0805    	          	          	                    
          	               	1         	285B1     	PVCCIN_CPU1         
          	               	2         	285B1     	GND                 

PC577     	Q_CAP_0402     	          	          	                    
          	               	1         	259B4     	SW_P3V3_AUX_FLT     
          	               	2         	259B4     	GND                 

PC577_P1_2	Q_CAP_C0805    	          	          	                    
          	               	1         	285A1     	PVCCIN_CPU1         
          	               	2         	285A1     	GND                 

PC578_P1_1	Q_CAP_C0805    	          	          	                    
          	               	1         	285B1     	PVCCIN_CPU1         
          	               	2         	285B1     	GND                 

PC579     	Q_CAPP_THLF    	          	          	                    
          	               	1         	285B2     	SW_P12V_PVCCIN_CPU1_FLT
          	               	2         	285B2     	GND                 

PC580     	Q_CAPP_THLF    	          	          	                    
          	               	1         	285B2     	PVCCIN_CPU1         
          	               	2         	285B2     	GND                 

PC581     	Q_CAP_C0603    	          	          	                    
          	               	1         	259B4     	P3V3_AUX_VDRV       
          	               	2         	259B4     	GND                 

PC582     	Q_CAPP_THLF    	          	          	                    
          	               	1         	285B1     	SW_P12V_PVCCIN_CPU1_FLT
          	               	2         	285B1     	GND                 

PC583     	Q_CAPP_THLF    	          	          	                    
          	               	1         	285B1     	PVCCIN_CPU1         
          	               	2         	285B1     	GND                 

PC585     	Q_CAPP_THLF    	          	          	                    
          	               	1         	285B1     	SW_P12V_PVCCIN_CPU1_FLT
          	               	2         	285B1     	GND                 

PC586     	Q_CAPP_THLF    	          	          	                    
          	               	1         	285B1     	PVCCIN_CPU1         
          	               	2         	285B1     	GND                 

PC587     	Q_CAPP_SMLF    	          	          	                    
          	               	1         	285A1     	PVCCIN_CPU1         
          	               	2         	285A1     	GND                 

PC588     	Q_CAPP_THLF    	          	          	                    
          	               	1         	285B1     	SW_P12V_PVCCIN_CPU1_FLT
          	               	2         	285B1     	GND                 

PC589     	Q_CAPP_THLF    	          	          	                    
          	               	1         	285B1     	PVCCIN_CPU1         
          	               	2         	285B1     	GND                 

PC590     	Q_CAPP_SMLF    	          	          	                    
          	               	1         	285A1     	PVCCIN_CPU1         
          	               	2         	285A1     	GND                 

PC591     	Q_CAP_C0603    	          	          	                    
          	               	1         	259B4     	P3V3_AUX_VCC        
          	               	2         	259B4     	GND                 

PC594     	Q_CAP_0402     	          	          	                    
          	               	1         	266B3     	SH_PVCCFA_EHV_FIVRA_CPU0_R
          	               	2         	266B3     	VSENSE_PVCCFA_EHV_FIVRA_CPU0_DN

PC600     	Q_CAP_C0402    	          	          	                    
          	               	1         	271B4     	PVCCFA_EHV_FIVRA_CPU0_VDD1
          	               	2         	271B4     	GND                 

PC601     	Q_CAP_C0402    	          	          	                    
          	               	1         	271A4     	PVCCFA_EHV_FIVRA_CPU0_VDD2
          	               	2         	271A4     	GND                 

PC602_P0_1	Q_CAP_0402     	          	          	                    
          	               	1         	271B3     	SW_P12V_PVCCFA_EHV_FIVRA_CPU0_R
          	               	2         	271B3     	GND                 

PC603_P0_2	Q_CAP_0402     	          	          	                    
          	               	1         	271A3     	SW_P12V_PVCCFA_EHV_FIVRA_CPU0_L
          	               	2         	271A3     	GND                 

PC604_P0_1	Q_CAP_C0402    	          	          	                    
          	               	1         	271B3     	SW_P12V_PVCCFA_EHV_FIVRA_CPU0_R
          	               	2         	271B3     	GND                 

PC605_P0_2	Q_CAP_C0402    	          	          	                    
          	               	1         	271A3     	SW_P12V_PVCCFA_EHV_FIVRA_CPU0_L
          	               	2         	271A3     	GND                 

PC606     	Q_CAP_C0402    	          	          	                    
          	               	1         	271B3     	SW_PVCCFA_EHV_FIVRA_CPU0_BOOT1_
          	               	2         	271B3     	SW_PVCCFA_EHV_FIVRA_CPU0_BOOTR1

PC607     	Q_CAP_C0402    	          	          	                    
          	               	1         	271A3     	SW_PVCCFA_EHV_FIVRA_CPU0_BOOT2_
          	               	2         	271A3     	SW_PVCCFA_EHV_FIVRA_CPU0_BOOTR2

PC608_P0_1	Q_CAP_C0805    	          	          	                    
          	               	1         	271B3     	SW_P12V_PVCCFA_EHV_FIVRA_CPU0_R
          	               	2         	271B3     	GND                 

PC609_P0_2	Q_CAP_C0805    	          	          	                    
          	               	1         	271A3     	SW_P12V_PVCCFA_EHV_FIVRA_CPU0_L
          	               	2         	271A3     	GND                 

PC610_P0_1	Q_CAP_C0805    	          	          	                    
          	               	1         	271B3     	SW_P12V_PVCCFA_EHV_FIVRA_CPU0_R
          	               	2         	271B3     	GND                 

PC611_P0_2	Q_CAP_C0805    	          	          	                    
          	               	1         	271A3     	SW_P12V_PVCCFA_EHV_FIVRA_CPU0_L
          	               	2         	271A3     	GND                 

PC612_P0_1	Q_CAP_C0402    	          	          	                    
          	               	1         	271B2     	PVCCFA_EHV_FIVRA_CPU0
          	               	2         	271B2     	GND                 

PC613_P0_2	Q_CAP_C0402    	          	          	                    
          	               	1         	271A2     	PVCCFA_EHV_FIVRA_CPU0
          	               	2         	271A2     	GND                 

PC615_P0_1	Q_CAP_C0805    	          	          	                    
          	               	1         	271B2     	PVCCFA_EHV_FIVRA_CPU0
          	               	2         	271B2     	GND                 

PC616_P0_2	Q_CAP_C0805    	          	          	                    
          	               	1         	271A2     	PVCCFA_EHV_FIVRA_CPU0
          	               	2         	271A2     	GND                 

PC617_P0_1	Q_CAP_C0805    	          	          	                    
          	               	1         	271B1     	PVCCFA_EHV_FIVRA_CPU0
          	               	2         	271B1     	GND                 

PC618_P0_2	Q_CAP_C0805    	          	          	                    
          	               	1         	271A1     	PVCCFA_EHV_FIVRA_CPU0
          	               	2         	271A1     	GND                 

PC619     	Q_CAPP_THLF    	          	          	                    
          	               	1         	271B2     	PVCCFA_EHV_FIVRA_CPU0
          	               	2         	271A2     	GND                 

PC620     	Q_CAPP_THLF    	          	          	                    
          	               	1         	271B1     	PVCCFA_EHV_FIVRA_CPU0
          	               	2         	271A1     	GND                 

PC621     	Q_CAPP_THLF    	          	          	                    
          	               	1         	271B1     	PVCCFA_EHV_FIVRA_CPU0
          	               	2         	271A1     	GND                 

PC621_P1_1	Q_CAP_C0402    	          	          	                    
          	               	1         	289B2     	PVCCFA_EHV_FIVRA_CPU1
          	               	2         	289B2     	GND                 

PC622     	Q_CAPP_THLF    	          	          	                    
          	               	1         	271B1     	SW_P12V_PVCCFA_EHV_FIVRA_CPU0_L
          	               	2         	271B1     	GND                 

PC623     	Q_CAPP_SMLF    	          	          	                    
          	               	1         	271B1     	PVCCFA_EHV_FIVRA_CPU0
          	               	2         	271A1     	GND                 

PC624     	Q_CAP_0402     	          	          	                    
          	               	1         	278A4     	PVCCD_HV_CPU0_ISENSE_P
          	               	2         	278A4     	GND                 

PC627     	Q_CAP_0402     	          	          	                    
          	               	1         	278B3     	SH_PVCCD_HV_CPU0_R  
          	               	2         	278B3     	VSENSE_PVCCD_HV_CPU0_DN

PC628     	Q_CAP_0402     	          	          	                    
          	               	1         	278A3     	PVCCD_HV_CPU0_ISENSE_N
          	               	2         	278A3     	GND                 

PC629     	Q_CAP_C0402    	          	          	                    
          	               	1         	278B2     	PVCCD_HV_CPU0_VCC   
          	               	2         	278B2     	GND                 

PC630     	Q_CAP_C0402    	          	          	                    
          	               	1         	278B2     	PVCCD_HV_CPU0_VREF  
          	               	2         	278B2     	GND                 

PC631     	Q_CAP_0402     	          	          	                    
          	               	1         	278A2     	PVCCD_HV_CPU0_ATSEN 
          	               	2         	278A2     	GND                 

PC632     	Q_CAP_C0402    	          	          	                    
          	               	1         	278B2     	PVCCD_HV_CPU0_VCC   
          	               	2         	278B2     	GND                 

PC633     	Q_CAP_C0402    	          	          	                    
          	               	1         	279B4     	PVCCD_HV_CPU0_VDD1  
          	               	2         	279B4     	GND                 

PC634     	Q_CAP_0402     	          	          	                    
          	               	1         	279B3     	SW_P12V_PVCCINFAON_CPU0_FLT
          	               	2         	279B3     	GND                 

PC635     	Q_CAP_C0402    	          	          	                    
          	               	1         	279B3     	SW_P12V_PVCCINFAON_CPU0_FLT
          	               	2         	279B3     	GND                 

PC636     	Q_CAP_C0402    	          	          	                    
          	               	1         	279B3     	SW_PVCCD_HV_CPU0_BOOT1_R
          	               	2         	279B3     	SW_PVCCD_HV_CPU0_BOOTR1

PC637     	Q_CAP_C0805    	          	          	                    
          	               	1         	279B3     	SW_P12V_PVCCINFAON_CPU0_FLT
          	               	2         	279B3     	GND                 

PC638     	Q_CAP_C0805    	          	          	                    
          	               	1         	279B3     	SW_P12V_PVCCINFAON_CPU0_FLT
          	               	2         	279B3     	GND                 

PC639     	Q_CAP_C0402    	          	          	                    
          	               	1         	279B2     	PVCCD_HV_CPU0       
          	               	2         	279B2     	GND                 

PC641     	Q_CAP_C0805    	          	          	                    
          	               	1         	279B2     	PVCCD_HV_CPU0       
          	               	2         	279B2     	GND                 

PC642     	Q_CAP_C0805    	          	          	                    
          	               	1         	279B2     	PVCCD_HV_CPU0       
          	               	2         	279B2     	GND                 

PC644     	Q_CAP_C0402    	          	          	                    
          	               	1         	299A4     	PVPP_HBM_CPU1_VCC   
          	               	2         	299A4     	GND                 

PC720_P0_1	Q_CAP_C0805    	          	          	                    
          	               	1         	271B2     	SW_P12V_PVCCFA_EHV_FIVRA_CPU0_R
          	               	2         	271B2     	GND                 

PC721_P0_2	Q_CAP_C0805    	          	          	                    
          	               	1         	271A2     	SW_P12V_PVCCFA_EHV_FIVRA_CPU0_L
          	               	2         	271A2     	GND                 

PC722_P0_3	Q_CAP_C0805    	          	          	                    
          	               	1         	272B3     	SW_P12V_PVCCFA_EHV_FIVRA_CPU0_R
          	               	2         	272B3     	GND                 

PC723_P0_4	Q_CAP_C0805    	          	          	                    
          	               	1         	272B3     	SW_P12V_PVCCFA_EHV_FIVRA_CPU0_L
          	               	2         	272B3     	GND                 

PC724_P1_1	Q_CAP_C0805    	          	          	                    
          	               	1         	289B3     	SW_P12V_PVCCFA_EHV_FIVRA_CPU1_R
          	               	2         	289B3     	GND                 

PC725_P1_2	Q_CAP_C0805    	          	          	                    
          	               	1         	289A3     	SW_P12V_PVCCFA_EHV_FIVRA_CPU1_L
          	               	2         	289A3     	GND                 

PC726_P1_3	Q_CAP_C0805    	          	          	                    
          	               	1         	290B3     	SW_P12V_PVCCFA_EHV_FIVRA_CPU1_R
          	               	2         	290B3     	GND                 

PC727_P1_4	Q_CAP_C0805    	          	          	                    
          	               	1         	290B3     	SW_P12V_PVCCFA_EHV_FIVRA_CPU1_L
          	               	2         	290B3     	GND                 

PC813     	Q_CAP_C0402    	          	          	                    
          	               	1         	278A3     	PVCCD_HV_CPU0_ISENSE_N
          	               	2         	278A3     	PVCCD_HV_CPU0_ISENSE_P

PC814     	Q_CAP_C0402    	          	          	                    
          	               	1         	296A3     	PVCCD_HV_CPU1_ISENSE_N
          	               	2         	296A3     	PVCCD_HV_CPU1_ISENSE_P

PC831     	Q_CAP_C0805    	          	          	                    
          	               	1         	281B4     	SW_P12V_PVCCIN_CPU0_FLT
          	               	2         	281B4     	GND                 

PC1171    	Q_CAP_C0402    	          	          	                    
          	               	1         	272B4     	PVCCFA_EHV_FIVRA_CPU0_VDD3
          	               	2         	272B4     	GND                 

PC1172    	Q_CAP_C0402    	          	          	                    
          	               	1         	272A4     	PVCCFA_EHV_FIVRA_CPU0_VDD4
          	               	2         	272A4     	GND                 

PC1173    	Q_CAP_C0402    	          	          	                    
          	               	1         	266B2     	PVCCIN_CPU0_VREF    
          	               	2         	266B2     	GND                 

PC1173_P0_3	Q_CAP_0402     	          	          	                    
          	               	1         	272B3     	SW_P12V_PVCCFA_EHV_FIVRA_CPU0_R
          	               	2         	272B3     	GND                 

PC1174_P0_4	Q_CAP_0402     	          	          	                    
          	               	1         	272B3     	SW_P12V_PVCCFA_EHV_FIVRA_CPU0_L
          	               	2         	272B3     	GND                 

PC1175_P0_3	Q_CAP_C0402    	          	          	                    
          	               	1         	272B3     	SW_P12V_PVCCFA_EHV_FIVRA_CPU0_R
          	               	2         	272B3     	GND                 

PC1176_P0_4	Q_CAP_C0402    	          	          	                    
          	               	1         	272B3     	SW_P12V_PVCCFA_EHV_FIVRA_CPU0_L
          	               	2         	272B3     	GND                 

PC1177    	Q_CAP_C0402    	          	          	                    
          	               	1         	272B3     	SW_PVCCFA_EHV_FIVRA_CPU0_BOOT3_
          	               	2         	272B3     	SW_PVCCFA_EHV_FIVRA_CPU0_BOOTR3

PC1178    	Q_CAP_C0402    	          	          	                    
          	               	1         	272A3     	SW_PVCCFA_EHV_FIVRA_CPU0_BOOT4_
          	               	2         	272A3     	SW_PVCCFA_EHV_FIVRA_CPU0_BOOTR4

PC1179_P0_3	Q_CAP_C0805    	          	          	                    
          	               	1         	272B3     	SW_P12V_PVCCFA_EHV_FIVRA_CPU0_R
          	               	2         	272B3     	GND                 

PC1180_P0_4	Q_CAP_C0805    	          	          	                    
          	               	1         	272B3     	SW_P12V_PVCCFA_EHV_FIVRA_CPU0_L
          	               	2         	272B3     	GND                 

PC1181_P0_3	Q_CAP_C0805    	          	          	                    
          	               	1         	272B3     	SW_P12V_PVCCFA_EHV_FIVRA_CPU0_R
          	               	2         	272B3     	GND                 

PC1182_P0_4	Q_CAP_C0805    	          	          	                    
          	               	1         	272B3     	SW_P12V_PVCCFA_EHV_FIVRA_CPU0_L
          	               	2         	272B3     	GND                 

PC1183    	Q_CAPP_THLF    	          	          	                    
          	               	1         	272B2     	PVCCFA_EHV_FIVRA_CPU0
          	               	2         	272B2     	GND                 

PC1183_P0_3	Q_CAP_C0402    	          	          	                    
          	               	1         	272B2     	PVCCFA_EHV_FIVRA_CPU0
          	               	2         	272B2     	GND                 

PC1183_P0_4	Q_CAP_C0402    	          	          	                    
          	               	1         	272A2     	PVCCFA_EHV_FIVRA_CPU0
          	               	2         	272A2     	GND                 

PC1185    	Q_CAPP_THLF    	          	          	                    
          	               	1         	272B1     	PVCCFA_EHV_FIVRA_CPU0
          	               	2         	272B1     	GND                 

PC1185_P0_3	Q_CAP_C0805    	          	          	                    
          	               	1         	272B2     	PVCCFA_EHV_FIVRA_CPU0
          	               	2         	272B2     	GND                 

PC1186    	Q_CAPP_THLF    	          	          	                    
          	               	1         	272B1     	PVCCFA_EHV_FIVRA_CPU0
          	               	2         	272B1     	GND                 

PC1186_P0_4	Q_CAP_C0805    	          	          	                    
          	               	1         	272A2     	PVCCFA_EHV_FIVRA_CPU0
          	               	2         	272A2     	GND                 

PC1187    	Q_CAPP_SMLF    	          	          	                    
          	               	1         	272B1     	PVCCFA_EHV_FIVRA_CPU0
          	               	2         	272B1     	GND                 

PC1187_P0_3	Q_CAP_C0805    	          	          	                    
          	               	1         	272B1     	PVCCFA_EHV_FIVRA_CPU0
          	               	2         	272B1     	GND                 

PC1188_P0_4	Q_CAP_C0805    	          	          	                    
          	               	1         	272A1     	PVCCFA_EHV_FIVRA_CPU0
          	               	2         	272A1     	GND                 

PC1189    	Q_CAPP_THLF    	          	          	                    
          	               	1         	272B1     	SW_P12V_PVCCFA_EHV_FIVRA_CPU0_R
          	               	2         	272B1     	GND                 

PC1191    	Q_CAP_C0402    	          	          	                    
          	               	1         	290B4     	PVCCFA_EHV_FIVRA_CPU1_VDD3
          	               	2         	290B4     	GND                 

PC1192    	Q_CAP_C0402    	          	          	                    
          	               	1         	290A4     	PVCCFA_EHV_FIVRA_CPU1_VDD4
          	               	2         	290A4     	GND                 

PC1193    	Q_CAP_C0402    	          	          	                    
          	               	1         	292B2     	PVCCINFAON_CPU1_VREF
          	               	2         	292B2     	GND                 

PC1193_P1_3	Q_CAP_0402     	          	          	                    
          	               	1         	290B3     	SW_P12V_PVCCFA_EHV_FIVRA_CPU1_R
          	               	2         	290B3     	GND                 

PC1194    	Q_CAP_C0402    	          	          	                    
          	               	1         	284B2     	PVCCIN_CPU1_VREF    
          	               	2         	284B2     	GND                 

PC1194_P1_4	Q_CAP_0402     	          	          	                    
          	               	1         	290B3     	SW_P12V_PVCCFA_EHV_FIVRA_CPU1_L
          	               	2         	290B3     	GND                 

PC1195_P1_3	Q_CAP_C0402    	          	          	                    
          	               	1         	290B3     	SW_P12V_PVCCFA_EHV_FIVRA_CPU1_R
          	               	2         	290B3     	GND                 

PC1196    	Q_CAP_C0402    	          	          	                    
          	               	1         	278B2     	PVCCD_HV_CPU0_VREF  
          	               	2         	278B2     	GND                 

PC1196_P1_4	Q_CAP_C0402    	          	          	                    
          	               	1         	290B3     	SW_P12V_PVCCFA_EHV_FIVRA_CPU1_L
          	               	2         	290B3     	GND                 

PC1197    	Q_CAP_C0402    	          	          	                    
          	               	1         	290B3     	SW_PVCCFA_EHV_FIVRA_CPU1_BOOT3_
          	               	2         	290B3     	SW_PVCCFA_EHV_FIVRA_CPU1_BOOTR3

PC1198    	Q_CAP_C0402    	          	          	                    
          	               	1         	290A3     	SW_PVCCFA_EHV_FIVRA_CPU1_BOOT4_
          	               	2         	290A3     	SW_PVCCFA_EHV_FIVRA_CPU1_BOOTR4

PC1199_P1_3	Q_CAP_C0805    	          	          	                    
          	               	1         	290B3     	SW_P12V_PVCCFA_EHV_FIVRA_CPU1_R
          	               	2         	290B3     	GND                 

PC1200_P1_4	Q_CAP_C0805    	          	          	                    
          	               	1         	290B3     	SW_P12V_PVCCFA_EHV_FIVRA_CPU1_L
          	               	2         	290B3     	GND                 

PC1201    	Q_CAPP_THLF    	          	          	                    
          	               	1         	290B2     	PVCCFA_EHV_FIVRA_CPU1
          	               	2         	290B2     	GND                 

PC1201_P1_3	Q_CAP_C0805    	          	          	                    
          	               	1         	290B3     	SW_P12V_PVCCFA_EHV_FIVRA_CPU1_R
          	               	2         	290B3     	GND                 

PC1202_P1_4	Q_CAP_C0805    	          	          	                    
          	               	1         	290B3     	SW_P12V_PVCCFA_EHV_FIVRA_CPU1_L
          	               	2         	290B3     	GND                 

PC1203    	Q_CAPP_THLF    	          	          	                    
          	               	1         	290B1     	PVCCFA_EHV_FIVRA_CPU1
          	               	2         	290B1     	GND                 

PC1203_P1_4	Q_CAP_C0402    	          	          	                    
          	               	1         	290A2     	PVCCFA_EHV_FIVRA_CPU1
          	               	2         	290A2     	GND                 

PC1204    	Q_CAPP_THLF    	          	          	                    
          	               	1         	290B1     	PVCCFA_EHV_FIVRA_CPU1
          	               	2         	290B1     	GND                 

PC1204_P1_3	Q_CAP_C0402    	          	          	                    
          	               	1         	290B2     	PVCCFA_EHV_FIVRA_CPU1
          	               	2         	290B2     	GND                 

PC1205    	Q_CAPP_SMLF    	          	          	                    
          	               	1         	290B1     	PVCCFA_EHV_FIVRA_CPU1
          	               	2         	290B1     	GND                 

PC1206    	Q_CAP_C0805    	          	          	                    
          	               	1         	282B1     	PVNN_MAIN_CPU0      
          	               	2         	282B1     	GND                 

PC1206_P1_3	Q_CAP_C0805    	          	          	                    
          	               	1         	290B2     	PVCCFA_EHV_FIVRA_CPU1
          	               	2         	290B2     	GND                 

PC1207    	Q_CAP_C0805    	          	          	                    
          	               	1         	300B1     	PVNN_MAIN_CPU1      
          	               	2         	300A1     	GND                 

PC1207_P1_4	Q_CAP_C0805    	          	          	                    
          	               	1         	290A2     	PVCCFA_EHV_FIVRA_CPU1
          	               	2         	290A2     	GND                 

PC1208_P1_3	Q_CAP_C0805    	          	          	                    
          	               	1         	290B2     	PVCCFA_EHV_FIVRA_CPU1
          	               	2         	290B2     	GND                 

PC1209_P1_4	Q_CAP_C0805    	          	          	                    
          	               	1         	290A2     	PVCCFA_EHV_FIVRA_CPU1
          	               	2         	290A2     	GND                 

PC1210    	Q_CAPP_THLF    	          	          	                    
          	               	1         	290B1     	SW_P12V_PVCCFA_EHV_FIVRA_CPU1_R
          	               	2         	290B1     	GND                 

PC1211_P0_1	Q_CAP_C0402    	          	          	                    
          	               	1         	271B4     	PVCCFA_EHV_FIVRA_CPU0_PVCC1
          	               	2         	271B4     	GND                 

PC1212_P0_2	Q_CAP_C0402    	          	          	                    
          	               	1         	271A4     	PVCCFA_EHV_FIVRA_CPU0_PVCC2
          	               	2         	271A4     	GND                 

PC1213_P0_3	Q_CAP_C0402    	          	          	                    
          	               	1         	272B4     	PVCCFA_EHV_FIVRA_CPU0_PVCC1
          	               	2         	272B4     	GND                 

PC1214_P0_4	Q_CAP_C0402    	          	          	                    
          	               	1         	272B4     	PVCCFA_EHV_FIVRA_CPU0_PVCC2
          	               	2         	272B4     	GND                 

PC1215    	Q_CAPP_SMLF    	          	          	                    
          	               	1         	262B4     	SW_P12V_AUX_P1V05_PCH_AUX_FLT
          	               	2         	262B4     	GND                 

PC1216    	Q_CAP_C0805    	          	          	                    
          	               	1         	262B4     	SW_P12V_AUX_P1V05_PCH_AUX_FLT
          	               	2         	262B4     	GND                 

PC1217    	Q_CAP_C0805    	          	          	                    
          	               	1         	262B4     	SW_P12V_AUX_P1V05_PCH_AUX_FLT
          	               	2         	262B4     	GND                 

PC1218    	Q_CAP_C0805    	          	          	                    
          	               	1         	262B4     	SW_P12V_AUX_P1V05_PCH_AUX_FLT
          	               	2         	262B4     	GND                 

PC1219    	Q_CAP_C0402    	          	          	                    
          	               	1         	262B4     	SW_P12V_AUX_P1V05_PCH_AUX_FLT
          	               	2         	262B4     	GND                 

PC1221    	Q_CAP_0402     	          	          	                    
          	               	1         	262A3     	P1V05_PCH_AUX_REF   
          	               	2         	262A3     	SH_P1V05_PCH_AUX_N  

PC1222    	Q_CAP_C0402    	          	          	                    
          	               	1         	262B2     	SW_P1V05_PCH_AUX_BST
          	               	2         	262B2     	SW_P1V05_PCH_AUX_SW 

PC1223    	Q_CAP_0402     	          	          	                    
          	               	1         	262A2     	P1V05_PCH_AUX_FB    
          	               	2         	262A2     	SH_P1V05_PCH_AUX_P  

PC1224    	Q_CAP_0402     	          	          	                    
          	               	1         	262B2     	P1V05_PCH_AUX       
          	               	2         	262B2     	GND                 

PC1225    	Q_CAP_C0805    	          	          	                    
          	               	1         	262B1     	P1V05_PCH_AUX       
          	               	2         	262B1     	GND                 

PC1226    	Q_CAP_C0805    	          	          	                    
          	               	1         	262B1     	P1V05_PCH_AUX       
          	               	2         	262B1     	GND                 

PC1227    	Q_CAPP_THLF    	          	          	                    
          	               	1         	262A1     	P1V05_PCH_AUX       
          	               	2         	262A1     	GND                 

PC1229    	Q_CAPP_SMLF    	          	          	                    
          	               	1         	262B1     	P1V05_PCH_AUX       
          	               	2         	262B1     	GND                 

PC1230    	Q_CAPP_THLF    	          	          	                    
          	               	1         	262A1     	P1V05_PCH_AUX       
          	               	2         	262A1     	GND                 

PC1232    	Q_CAP_C0805    	          	          	                    
          	               	1         	263B4     	SW_P1V8_PCH_AUX_FLT 
          	               	2         	263B4     	GND                 

PC1233    	Q_CAP_C0805    	          	          	                    
          	               	1         	263B4     	SW_P1V8_PCH_AUX_FLT 
          	               	2         	263B4     	GND                 

PC1234    	Q_CAP_C0402    	          	          	                    
          	               	1         	263B4     	SW_P1V8_PCH_AUX_FLT 
          	               	2         	263B4     	GND                 

PC1235    	Q_CAP_C0402    	          	          	                    
          	               	1         	263B3     	SW_P1V8_PCH_AUX_BST 
          	               	2         	263B3     	SW_P1V8_PCH_AUX_SW  

PC1236    	Q_CAP_C0402    	          	          	                    
          	               	1         	263B2     	P1V8_PCH_AUX        
          	               	2         	263B2     	GND                 

PC1237    	Q_CAP_C0805    	          	          	                    
          	               	1         	263B2     	P1V8_PCH_AUX        
          	               	2         	263B2     	GND                 

PC1238    	Q_CAP_C0805    	          	          	                    
          	               	1         	263B2     	P1V8_PCH_AUX        
          	               	2         	263B2     	GND                 

PC1239    	Q_CAP_C0805    	          	          	                    
          	               	1         	263B1     	P1V8_PCH_AUX        
          	               	2         	263B1     	GND                 

PC1240    	Q_CAP_C0805    	          	          	                    
          	               	1         	263B1     	P1V8_PCH_AUX        
          	               	2         	263B1     	GND                 

PC1241    	Q_CAP_C0805    	          	          	                    
          	               	1         	263B1     	P1V8_PCH_AUX        
          	               	2         	263B1     	GND                 

PC1242_P1_1	Q_CAP_C0402    	          	          	                    
          	               	1         	289B4     	PVCCFA_EHV_FIVRA_CPU1_PVCC1
          	               	2         	289B4     	GND                 

PC1243_P1_2	Q_CAP_C0402    	          	          	                    
          	               	1         	289A4     	PVCCFA_EHV_FIVRA_CPU1_PVCC2
          	               	2         	289A4     	GND                 

PC1244_P1_3	Q_CAP_C0402    	          	          	                    
          	               	1         	290B4     	PVCCFA_EHV_FIVRA_CPU1_PVCC1
          	               	2         	290B4     	GND                 

PC1245_P1_4	Q_CAP_C0402    	          	          	                    
          	               	1         	290B4     	PVCCFA_EHV_FIVRA_CPU1_PVCC2
          	               	2         	290B4     	GND                 

PC1247    	Q_CAP_C0805    	          	          	                    
          	               	1         	281B4     	SW_P12V_PVCCIN_CPU0_FLT
          	               	2         	281B4     	GND                 

PC1248    	Q_CAP_C0805    	          	          	                    
          	               	1         	281B4     	SW_P12V_PVCCIN_CPU0_FLT
          	               	2         	281B4     	GND                 

PC1249    	Q_CAP_C0402    	          	          	                    
          	               	1         	281B4     	SW_P12V_PVCCIN_CPU0_FLT
          	               	2         	281B4     	GND                 

PC1251    	Q_CAP_0402     	          	          	                    
          	               	1         	281A3     	PVPP_HBM_CPU0_REF   
          	               	2         	281A3     	SH_PVPP_HBM_CPU0_N  

PC1252    	Q_CAP_C0402    	          	          	                    
          	               	1         	281B3     	SW_PVPP_HBM_CPU0_BST
          	               	2         	281B3     	SW_PVPP_HBM_CPU0_SW 

PC1253    	Q_CAP_C0402    	          	          	                    
          	               	1         	281A2     	PVPP_HBM_CPU0_FB    
          	               	2         	281A2     	SH_PVPP_HBM_CPU0_P  

PC1254    	Q_CAP_0402     	          	          	                    
          	               	1         	281B2     	PVPP_HBM_CPU0       
          	               	2         	281B2     	GND                 

PC1255    	Q_CAP_C0805    	          	          	                    
          	               	1         	281B2     	PVPP_HBM_CPU0       
          	               	2         	281B2     	GND                 

PC1256    	Q_CAP_C0805    	          	          	                    
          	               	1         	281B1     	PVPP_HBM_CPU0       
          	               	2         	281B1     	GND                 

PC1257    	Q_CAP_C0805    	          	          	                    
          	               	1         	281B1     	PVPP_HBM_CPU0       
          	               	2         	281B1     	GND                 

PC1258    	Q_CAPP_THLF    	          	          	                    
          	               	1         	281B1     	PVPP_HBM_CPU0       
          	               	2         	281B1     	GND                 

PC1259    	Q_CAP_C0805    	          	          	                    
          	               	1         	299B4     	SW_P12V_PVCCIN_CPU1_FLT
          	               	2         	299B4     	GND                 

PC1260    	Q_CAP_C0805    	          	          	                    
          	               	1         	299B4     	SW_P12V_PVCCIN_CPU1_FLT
          	               	2         	299B4     	GND                 

PC1261    	Q_CAP_C0805    	          	          	                    
          	               	1         	299B4     	SW_P12V_PVCCIN_CPU1_FLT
          	               	2         	299B4     	GND                 

PC1262    	Q_CAP_C0402    	          	          	                    
          	               	1         	299B4     	SW_P12V_PVCCIN_CPU1_FLT
          	               	2         	299B4     	GND                 

PC1264    	Q_CAP_0402     	          	          	                    
          	               	1         	299A3     	PVPP_HBM_CPU1_REF   
          	               	2         	299A3     	SH_PVPP_HBM_CPU1_N  

PC1265    	Q_CAP_C0402    	          	          	                    
          	               	1         	299B3     	SW_PVPP_HBM_CPU1_BST
          	               	2         	299B3     	SW_PVPP_HBM_CPU1_SW 

PC1266    	Q_CAP_0402     	          	          	                    
          	               	1         	299A2     	PVPP_HBM_CPU1_FB    
          	               	2         	299A2     	SH_PVPP_HBM_CPU1_P  

PC1267    	Q_CAP_0402     	          	          	                    
          	               	1         	299B2     	PVPP_HBM_CPU1       
          	               	2         	299B2     	GND                 

PC1268    	Q_CAP_C0805    	          	          	                    
          	               	1         	299B2     	PVPP_HBM_CPU1       
          	               	2         	299B2     	GND                 

PC1269    	Q_CAP_C0805    	          	          	                    
          	               	1         	299B2     	PVPP_HBM_CPU1       
          	               	2         	299B2     	GND                 

PC1270    	Q_CAP_C0805    	          	          	                    
          	               	1         	299B1     	PVPP_HBM_CPU1       
          	               	2         	299B1     	GND                 

PC1271    	Q_CAP_0402     	          	          	                    
          	               	1         	274A2     	PVCCFA_EHV_CPU0_BTSEN
          	               	2         	274A2     	GND                 

PC1272    	Q_CAP_C0805    	          	          	                    
          	               	1         	282B4     	SW_P12V_PVCCINFAON_CPU0_FLT
          	               	2         	282B4     	GND                 

PC1273    	Q_CAP_C0805    	          	          	                    
          	               	1         	282B4     	SW_P12V_PVCCINFAON_CPU0_FLT
          	               	2         	282B4     	GND                 

PC1274    	Q_CAP_C0402    	          	          	                    
          	               	1         	282B4     	SW_P12V_PVCCINFAON_CPU0_FLT
          	               	2         	282B4     	GND                 

PC1275    	Q_CAP_C0402    	          	          	                    
          	               	1         	282B2     	SW_PVNN_MAIN_CPU0_BST_R
          	               	2         	282B2     	SW_PVNN_MAIN_CPU0_SW

PC1276    	Q_CAP_C0402    	          	          	                    
          	               	1         	282B2     	PVNN_MAIN_CPU0      
          	               	2         	282B2     	GND                 

PC1277    	Q_CAP_C0805    	          	          	                    
          	               	1         	282B1     	PVNN_MAIN_CPU0      
          	               	2         	282B1     	GND                 

PC1278    	Q_CAP_C0805    	          	          	                    
          	               	1         	282B1     	PVNN_MAIN_CPU0      
          	               	2         	282B1     	GND                 

PC1279    	Q_CAP_C0805    	          	          	                    
          	               	1         	282B1     	PVNN_MAIN_CPU0      
          	               	2         	282B1     	GND                 

PC1280    	Q_CAP_C0805    	          	          	                    
          	               	1         	300B4     	SW_P12V_PVCCINFAON_CPU1_FLT
          	               	2         	300B4     	GND                 

PC1281    	Q_CAP_C0805    	          	          	                    
          	               	1         	300B4     	SW_P12V_PVCCINFAON_CPU1_FLT
          	               	2         	300B4     	GND                 

PC1282    	Q_CAP_C0402    	          	          	                    
          	               	1         	300B4     	SW_P12V_PVCCINFAON_CPU1_FLT
          	               	2         	300B4     	GND                 

PC1283    	Q_CAP_C0402    	          	          	                    
          	               	1         	300B2     	SW_PVNN_MAIN_CPU1_BST_R
          	               	2         	300B2     	SW_PVNN_MAIN_CPU1_SW

PC1284    	Q_CAP_C0402    	          	          	                    
          	               	1         	300B2     	PVNN_MAIN_CPU1      
          	               	2         	300A2     	GND                 

PC1285    	Q_CAP_C0805    	          	          	                    
          	               	1         	300B2     	PVNN_MAIN_CPU1      
          	               	2         	300A2     	GND                 

PC1286    	Q_CAP_C0805    	          	          	                    
          	               	1         	300B1     	PVNN_MAIN_CPU1      
          	               	2         	300A1     	GND                 

PC1287    	Q_CAP_C0805    	          	          	                    
          	               	1         	300B1     	PVNN_MAIN_CPU1      
          	               	2         	300A1     	GND                 

PC1289    	Q_CAP_C0402    	          	          	                    
          	               	1         	296B2     	PVCCD_HV_CPU1_VREF  
          	               	2         	296B2     	GND                 

PC1292    	Q_CAP_0402     	          	          	                    
          	               	1         	292A2     	PVCCFA_EHV_CPU1_BTSEN
          	               	2         	292A2     	GND                 

PC1320    	Q_CAP_C0603    	          	          	                    
          	               	1         	163A2     	P12V_OCP_AVIN_PD_2  
          	               	2         	163A2     	GND                 

PC1321    	Q_CAP_0402     	          	          	                    
          	               	1         	163B2     	P3V3_OCP_DVDT_2     
          	               	2         	163B2     	GND                 

PC1322    	Q_CAP_0402     	          	          	                    
          	               	1         	163B1     	P3V3_OCP_GATE_PU207_2
          	               	2         	163B1     	GND                 

PC1338    	Q_CAP_0402     	          	          	                    
          	               	1         	285A4     	GND                 
          	               	2         	285A4     	PVCCIN_CPU1_VREF    

PC1339    	Q_CAP_0402     	          	          	                    
          	               	1         	285B4     	GND                 
          	               	2         	285B4     	PVCCIN_CPU1_VREF    

PC1340    	Q_CAP_0402     	          	          	                    
          	               	1         	268A4     	GND                 
          	               	2         	268A4     	PVCCIN_CPU0_VREF    

PC1341    	Q_CAP_0402     	          	          	                    
          	               	1         	268B4     	GND                 
          	               	2         	268B4     	PVCCIN_CPU0_VREF    

PC1342    	Q_CAP_0402     	          	          	                    
          	               	1         	269A4     	GND                 
          	               	2         	269A4     	PVCCIN_CPU0_VREF    

PC1343    	Q_CAP_0402     	          	          	                    
          	               	1         	269B4     	GND                 
          	               	2         	269B4     	PVCCIN_CPU0_VREF    

PC1344    	Q_CAP_0402     	          	          	                    
          	               	1         	270A4     	GND                 
          	               	2         	270A4     	PVCCIN_CPU0_VREF    

PC1345    	Q_CAP_0402     	          	          	                    
          	               	1         	270B4     	GND                 
          	               	2         	270B4     	PVCCIN_CPU0_VREF    

PC1346    	Q_CAP_0402     	          	          	                    
          	               	1         	275A4     	GND                 
          	               	2         	275A4     	PVCCINFAON_CPU0_VREF

PC1347    	Q_CAP_0402     	          	          	                    
          	               	1         	275B4     	GND                 
          	               	2         	275B4     	PVCCINFAON_CPU0_VREF

PC1348    	Q_CAP_0402     	          	          	                    
          	               	1         	276B4     	GND                 
          	               	2         	276B4     	PVCCINFAON_CPU0_VREF

PC1349    	Q_CAP_0402     	          	          	                    
          	               	1         	271B4     	GND                 
          	               	2         	271B4     	PVCCIN_CPU0_VREF    

PC1350    	Q_CAP_0402     	          	          	                    
          	               	1         	271A4     	GND                 
          	               	2         	271A4     	PVCCIN_CPU0_VREF    

PC1351    	Q_CAP_0402     	          	          	                    
          	               	1         	272B4     	GND                 
          	               	2         	272B4     	PVCCIN_CPU0_VREF    

PC1352    	Q_CAP_0402     	          	          	                    
          	               	1         	272A4     	GND                 
          	               	2         	272A4     	PVCCIN_CPU0_VREF    

PC1354    	Q_CAP_0402     	          	          	                    
          	               	1         	279B4     	GND                 
          	               	2         	279B4     	PVCCD_HV_CPU0_VREF  

PC1355    	Q_CAP_0402     	          	          	                    
          	               	1         	267A4     	GND                 
          	               	2         	267A4     	PVCCIN_CPU0_VREF    

PC1356    	Q_CAP_0402     	          	          	                    
          	               	1         	267B4     	GND                 
          	               	2         	267B4     	PVCCIN_CPU0_VREF    

PC1358    	Q_CAP_0402     	          	          	                    
          	               	1         	286A4     	GND                 
          	               	2         	286A4     	PVCCIN_CPU1_VREF    

PC1359    	Q_CAP_0402     	          	          	                    
          	               	1         	286B4     	GND                 
          	               	2         	286B4     	PVCCIN_CPU1_VREF    

PC1360    	Q_CAP_0402     	          	          	                    
          	               	1         	287A4     	GND                 
          	               	2         	287A4     	PVCCIN_CPU1_VREF    

PC1361    	Q_CAP_0402     	          	          	                    
          	               	1         	287B4     	GND                 
          	               	2         	287B4     	PVCCIN_CPU1_VREF    

PC1362    	Q_CAP_0402     	          	          	                    
          	               	1         	288A4     	GND                 
          	               	2         	288A4     	PVCCIN_CPU1_VREF    

PC1363    	Q_CAP_0402     	          	          	                    
          	               	1         	288B4     	GND                 
          	               	2         	288B4     	PVCCIN_CPU1_VREF    

PC1364    	Q_CAP_0402     	          	          	                    
          	               	1         	293B4     	GND                 
          	               	2         	293B4     	PVCCINFAON_CPU1_VREF

PC1365    	Q_CAP_0402     	          	          	                    
          	               	1         	293A4     	GND                 
          	               	2         	293A4     	PVCCINFAON_CPU1_VREF

PC1366    	Q_CAP_0402     	          	          	                    
          	               	1         	294B4     	GND                 
          	               	2         	294B4     	PVCCINFAON_CPU1_VREF

PC1367    	Q_CAP_0402     	          	          	                    
          	               	1         	289B4     	GND                 
          	               	2         	289B4     	PVCCIN_CPU1_VREF    

PC1368    	Q_CAP_0402     	          	          	                    
          	               	1         	289A4     	GND                 
          	               	2         	289A4     	PVCCIN_CPU1_VREF    

PC1369    	Q_CAP_0402     	          	          	                    
          	               	1         	290B4     	GND                 
          	               	2         	290B4     	PVCCIN_CPU1_VREF    

PC1370    	Q_CAP_0402     	          	          	                    
          	               	1         	290A4     	GND                 
          	               	2         	290A4     	PVCCIN_CPU1_VREF    

PC1371    	Q_CAP_0402     	          	          	                    
          	               	1         	297B4     	GND                 
          	               	2         	297B4     	PVCCD_HV_CPU1_VREF  

PC1372    	Q_CAP_C0402    	          	          	                    
          	               	1         	274B2     	PVCCINFAON_CPU0_VREF
          	               	2         	274B2     	GND                 

PC1420    	Q_CAP_0402     	          	          	                    
          	               	1         	282A1     	PVNN_MAIN_CPU0_FB_RC
          	               	2         	282A1     	GND                 

PC1421    	Q_CAP_0402     	          	          	                    
          	               	1         	281A1     	SH_PVPP_HBM_CPU0_P  
          	               	2         	281A1     	SH_PVPP_HBM_CPU0_N  

PC1525    	Q_CAP_C0402    	          	          	                    
          	               	1         	302B4     	HSC_VDD_R_1         
          	               	2         	302B4     	AGND_HSC            

PC1573    	Q_CAPP_SMLF    	          	          	                    
          	               	1         	275B2     	PVCCINFAON_CPU0     
          	               	2         	275B2     	GND                 

PC1574    	Q_CAPP_THLF    	          	          	                    
          	               	1         	275B2     	PVCCINFAON_CPU0     
          	               	2         	275B2     	GND                 

PC1575    	Q_CAPP_SMLF    	          	          	                    
          	               	1         	275B1     	PVCCINFAON_CPU0     
          	               	2         	275B1     	GND                 

PC1576    	Q_CAPP_THLF    	          	          	                    
          	               	1         	275B1     	PVCCINFAON_CPU0     
          	               	2         	275B1     	GND                 

PC1579    	Q_CAPP_THLF    	          	          	                    
          	               	1         	275B1     	PVCCINFAON_CPU0     
          	               	2         	275B1     	GND                 

PC1588    	Q_CAPP_SMLF    	          	          	                    
          	               	1         	293B2     	PVCCINFAON_CPU1     
          	               	2         	293B2     	GND                 

PC1593    	Q_CAPP_THLF    	          	          	                    
          	               	1         	293A2     	PVCCINFAON_CPU1     
          	               	2         	293A2     	GND                 

PC1594    	Q_CAPP_SMLF    	          	          	                    
          	               	1         	293B1     	PVCCINFAON_CPU1     
          	               	2         	293B1     	GND                 

PC1595    	Q_CAPP_THLF    	          	          	                    
          	               	1         	293A1     	PVCCINFAON_CPU1     
          	               	2         	293A1     	GND                 

PC1596    	Q_CAPP_THLF    	          	          	                    
          	               	1         	293A1     	PVCCINFAON_CPU1     
          	               	2         	293A1     	GND                 

PC1599    	Q_CAP_C0805    	          	          	                    
          	               	1         	259B1     	P3V3_AUX            
          	               	2         	259A1     	GND                 

PC1600    	Q_CAP_C0805    	          	          	                    
          	               	1         	259B1     	P3V3_AUX            
          	               	2         	259A1     	GND                 

PC1642    	Q_CAP_C0402    	          	          	                    
          	               	1         	263A4     	P1V8_PCH_AUX_VCC    
          	               	2         	263A4     	GND                 

PC1644    	Q_CAPP_THLF    	          	          	                    
          	               	1         	279A2     	PVCCD_HV_CPU0       
          	               	2         	279A2     	GND                 

PC1645    	Q_CAPP_THLF    	          	          	                    
          	               	1         	279A1     	PVCCD_HV_CPU0       
          	               	2         	279A1     	GND                 

PC1648    	Q_CAP_C0402    	          	          	                    
          	               	1         	258B4     	P12V_AUX            
          	               	2         	258B4     	GND                 

PC1649    	Q_CAP_C0402    	          	          	                    
          	               	1         	259B4     	P12V_AUX            
          	               	2         	259B4     	GND                 

PC1650    	Q_CAP_C0402    	          	          	                    
          	               	1         	262B4     	P12V_AUX            
          	               	2         	262B4     	GND                 

PC1651    	Q_CAP_C0402    	          	          	                    
          	               	1         	263B4     	P12V_AUX            
          	               	2         	263B4     	GND                 

PC1652    	Q_CAP_C0402    	          	          	                    
          	               	1         	267B2     	P12V_AUX            
          	               	2         	267B2     	GND                 

PC1653    	Q_CAP_C0402    	          	          	                    
          	               	1         	271B2     	P12V_AUX            
          	               	2         	271B2     	GND                 

PC1654    	Q_CAP_C0402    	          	          	                    
          	               	1         	272B2     	P12V_AUX            
          	               	2         	272B2     	GND                 

PC1655    	Q_CAP_C0402    	          	          	                    
          	               	1         	275B2     	P12V_AUX            
          	               	2         	275B2     	GND                 

PC1656    	Q_CAP_C0402    	          	          	                    
          	               	1         	285B2     	P12V_AUX            
          	               	2         	285B2     	GND                 

PC1657    	Q_CAP_C0402    	          	          	                    
          	               	1         	289B2     	P12V_AUX            
          	               	2         	289B2     	GND                 

PC1658    	Q_CAP_C0402    	          	          	                    
          	               	1         	290B2     	P12V_AUX            
          	               	2         	290B2     	GND                 

PC1659    	Q_CAP_C0402    	          	          	                    
          	               	1         	293B2     	P12V_AUX            
          	               	2         	293B2     	GND                 

PC1669    	Q_CAP_C0805    	          	          	                    
          	               	1         	271B1     	SW_P12V_PVCCFA_EHV_FIVRA_CPU0_L
          	               	2         	271B1     	GND                 

PC1670    	Q_CAP_C0805    	          	          	                    
          	               	1         	271B1     	SW_P12V_PVCCFA_EHV_FIVRA_CPU0_L
          	               	2         	271B1     	GND                 

PC1671    	Q_CAP_C0805    	          	          	                    
          	               	1         	271B1     	SW_P12V_PVCCFA_EHV_FIVRA_CPU0_L
          	               	2         	271B1     	GND                 

PC1672    	Q_CAP_C0805    	          	          	                    
          	               	1         	271B1     	SW_P12V_PVCCFA_EHV_FIVRA_CPU0_L
          	               	2         	271B1     	GND                 

PC1673    	Q_CAP_C0805    	          	          	                    
          	               	1         	272B2     	SW_P12V_PVCCFA_EHV_FIVRA_CPU0_R
          	               	2         	272B2     	GND                 

PC1674    	Q_CAP_C0805    	          	          	                    
          	               	1         	272B1     	SW_P12V_PVCCFA_EHV_FIVRA_CPU0_R
          	               	2         	272B1     	GND                 

PC1675    	Q_CAP_C0805    	          	          	                    
          	               	1         	272B1     	SW_P12V_PVCCFA_EHV_FIVRA_CPU0_R
          	               	2         	272B1     	GND                 

PC1676    	Q_CAP_C0805    	          	          	                    
          	               	1         	272B1     	SW_P12V_PVCCFA_EHV_FIVRA_CPU0_R
          	               	2         	272B1     	GND                 

PC1677    	Q_CAP_C0805    	          	          	                    
          	               	1         	289B1     	SW_P12V_PVCCFA_EHV_FIVRA_CPU1_L
          	               	2         	289B1     	GND                 

PC1678    	Q_CAP_C0805    	          	          	                    
          	               	1         	289B1     	SW_P12V_PVCCFA_EHV_FIVRA_CPU1_L
          	               	2         	289B1     	GND                 

PC1679    	Q_CAP_C0805    	          	          	                    
          	               	1         	289B1     	SW_P12V_PVCCFA_EHV_FIVRA_CPU1_L
          	               	2         	289B1     	GND                 

PC1680    	Q_CAP_C0805    	          	          	                    
          	               	1         	289B1     	SW_P12V_PVCCFA_EHV_FIVRA_CPU1_L
          	               	2         	289B1     	GND                 

PC1681    	Q_CAP_C0805    	          	          	                    
          	               	1         	290B2     	SW_P12V_PVCCFA_EHV_FIVRA_CPU1_R
          	               	2         	290B2     	GND                 

PC1682    	Q_CAP_C0805    	          	          	                    
          	               	1         	290B1     	SW_P12V_PVCCFA_EHV_FIVRA_CPU1_R
          	               	2         	290B1     	GND                 

PC1683    	Q_CAP_C0805    	          	          	                    
          	               	1         	290B1     	SW_P12V_PVCCFA_EHV_FIVRA_CPU1_R
          	               	2         	290B1     	GND                 

PC1684    	Q_CAP_C0805    	          	          	                    
          	               	1         	290B1     	SW_P12V_PVCCFA_EHV_FIVRA_CPU1_R
          	               	2         	290B1     	GND                 

PC1750    	Q_CAP_C0402    	          	          	                    
          	               	1         	304B1     	P12V_AUX            
          	               	2         	304A1     	P12V_HSC_GATE2      

PC1751    	Q_CAP_0402     	          	          	                    
          	               	1         	304A1     	P12V_HSC_GATE_RC    
          	               	2         	304A1     	P12V_HSC_GATE2      

PC1771    	Q_CAPP_THLF    	          	          	                    
          	               	1         	299B1     	PVPP_HBM_CPU1       
          	               	2         	299B1     	GND                 

PC1789    	Q_CAP_0402     	          	          	                    
          	               	1         	305B1     	P12V_AUX            
          	               	2         	305B1     	GND                 

PC1845    	Q_CAPP_SMLF    	          	          	                    
          	               	1         	258B2     	P5V_AUX             
          	               	2         	258B2     	GND                 

PC1846    	Q_CAP_C0402    	          	          	                    
          	               	1         	258B4     	SW_P5V_AUX_FLT      
          	               	2         	258B4     	GND                 

PC1847    	Q_CAP_C0402    	          	          	                    
          	               	1         	258B3     	SW_P5V_AUX_BST      
          	               	2         	258B3     	SW_P5V_AUX_SW       

PC1848    	Q_CAP_C0402    	          	          	                    
          	               	1         	258B4     	P5V_AUX_VCC         
          	               	2         	258A4     	GND                 

PC1849    	Q_CAP_C0805    	          	          	                    
          	               	1         	258B4     	SW_P5V_AUX_FLT      
          	               	2         	258B4     	GND                 

PC1850    	Q_CAP_C0805    	          	          	                    
          	               	1         	258B4     	SW_P5V_AUX_FLT      
          	               	2         	258B4     	GND                 

PC1852    	Q_CAP_0402     	          	          	                    
          	               	1         	258B1     	P5V_AUX             
          	               	2         	258B1     	GND                 

PC1853    	Q_CAP_0402     	          	          	                    
          	               	1         	258A3     	P5V_AUX_REF         
          	               	2         	258A3     	GND                 

PC1855    	Q_CAP_C0805    	          	          	                    
          	               	1         	258B1     	P5V_AUX             
          	               	2         	258B1     	GND                 

PC1856    	Q_CAP_C0805    	          	          	                    
          	               	1         	258B1     	P5V_AUX             
          	               	2         	258B1     	GND                 

PC1866    	Q_CAPP_THLF    	          	          	                    
          	               	1         	259B2     	P3V3_AUX            
          	               	2         	259A2     	GND                 

PC1867    	Q_CAPP_THLF    	          	          	                    
          	               	1         	259B2     	P3V3_AUX            
          	               	2         	259A2     	GND                 

PC1868    	Q_CAP_C0805    	          	          	                    
          	               	1         	259B1     	P3V3_AUX            
          	               	2         	259A1     	GND                 

PC1869    	Q_CAP_0402     	          	          	                    
          	               	1         	259B1     	P3V3_AUX            
          	               	2         	259A1     	GND                 

PC1877    	Q_CAP_0402     	          	          	                    
          	               	1         	258A2     	P5V_AUX_FB          
          	               	2         	258A2     	P5V_AUX             

PC1898    	Q_CAP_C0805    	          	          	                    
          	               	1         	258B4     	SW_P5V_AUX_FLT      
          	               	2         	258B4     	GND                 

PC1900    	Q_CAPP_SMLF    	          	          	                    
          	               	1         	276B1     	PVCCFA_EHV_CPU0     
          	               	2         	276B1     	GND                 

PC1910    	Q_CAPP_SMLF    	          	          	                    
          	               	1         	279A2     	PVCCD_HV_CPU0       
          	               	2         	279A2     	GND                 

PC1920    	Q_CAPP_SMLF    	          	          	                    
          	               	1         	267A1     	PVCCIN_CPU0         
          	               	2         	267A1     	GND                 

PC1930    	Q_CAPP_SMLF    	          	          	                    
          	               	1         	294B1     	PVCCFA_EHV_CPU1     
          	               	2         	294B1     	GND                 

PC1940    	Q_CAPP_SMLF    	          	          	                    
          	               	1         	297A2     	PVCCD_HV_CPU1       
          	               	2         	297A2     	GND                 

PC1990    	Q_CAPP_SMLF    	          	          	                    
          	               	1         	285A2     	PVCCIN_CPU1         
          	               	2         	285A2     	GND                 

PC2000    	Q_CAP_0402     	          	          	                    
          	               	1         	262A3     	P1V05_PCH_AUX_REF   
          	               	2         	262A3     	GND                 

PC2001    	Q_CAP_0402     	          	          	                    
          	               	1         	281A3     	PVPP_HBM_CPU0_REF   
          	               	2         	281A3     	GND                 

PC2002    	Q_CAP_0402     	          	          	                    
          	               	1         	299A3     	PVPP_HBM_CPU1_REF   
          	               	2         	299A3     	GND                 

PC2079    	Q_CAP_C0402    	          	          	                    
          	               	1         	156B3     	P12V_AUX            
          	               	2         	156B3     	GND                 

PC2080    	Q_CAP_C0805    	          	          	                    
          	               	1         	156B1     	P12V_OCP_SFF        
          	               	2         	156B1     	GND                 

PC2081    	Q_CAP_C0805    	          	          	                    
          	               	1         	156B1     	P3V3_OCP_SFF_R      
          	               	2         	156B1     	GND                 

PC2082    	Q_CAP_C0805    	          	          	                    
          	               	1         	156B1     	P12V_OCP_SFF        
          	               	2         	156B1     	GND                 

PC2085    	Q_CAP_C0402    	          	          	                    
          	               	1         	156B3     	P12V_OCP_VCC_1      
          	               	2         	156B3     	GND                 

PC2086    	Q_CAP_C0402    	          	          	                    
          	               	1         	156B3     	P3V3_OCP_VCC_1      
          	               	2         	156B3     	GND                 

PC2087    	Q_CAP_C0402    	          	          	                    
          	               	1         	156B3     	GND                 
          	               	2         	156B3     	P12V_OCP_REG_1      

PC2088    	Q_CAP_C0402    	          	          	                    
          	               	1         	156B2     	P12V_OCP_SFF        
          	               	2         	156B2     	P12V_OCP_GATE_1     

PC2089    	Q_CAP_C0402    	          	          	                    
          	               	1         	156B1     	P3V3_OCP_GATE_PU202_1
          	               	2         	156B1     	GND                 

PC2091    	Q_CAP_0402     	          	          	                    
          	               	1         	156B1     	P3V3_OCP_SFF_R      
          	               	2         	156B1     	GND                 

PC2092    	Q_CAP_0402     	          	          	                    
          	               	1         	156B1     	P12V_OCP_SFF        
          	               	2         	156B1     	GND                 

PC2093    	Q_CAP_C0402    	          	          	                    
          	               	1         	156B3     	GND                 
          	               	2         	156B3     	P3V3_OCP_REG_1      

PC2098    	Q_CAP_C0402    	          	          	                    
          	               	1         	162B3     	P12V_OCP_VCC_2      
          	               	2         	162B3     	GND                 

PC2103    	Q_CAP_C0402    	          	          	                    
          	               	1         	301B4     	HSC_VDD18           
          	               	2         	301B4     	AGND_HSC            

PC2137    	Q_CAP_0402     	          	          	                    
          	               	1         	162B1     	P3V3_OCP_V3_2_R     
          	               	2         	162B1     	GND                 

PC2139    	Q_CAP_C0402    	          	          	                    
          	               	1         	162B3     	P12V_AUX            
          	               	2         	162B3     	GND                 

PC2140    	Q_CAP_C0402    	          	          	                    
          	               	1         	162B3     	P3V3_AUX            
          	               	2         	162B3     	GND                 

PC2141    	Q_CAP_C0805    	          	          	                    
          	               	1         	162B1     	P12V_OCP_V3_2       
          	               	2         	162B1     	GND                 

PC2142    	Q_CAP_C0805    	          	          	                    
          	               	1         	162B1     	P3V3_OCP_V3_2_R     
          	               	2         	162B1     	GND                 

PC2143    	Q_CAP_C0805    	          	          	                    
          	               	1         	162B1     	P12V_OCP_V3_2       
          	               	2         	162B1     	GND                 

PC2144    	Q_CAP_C0402    	          	          	                    
          	               	1         	156B2     	P3V3_OCP_SFF_R      
          	               	2         	156B2     	P3V3_OCP_GATE_PU202_1

PC2146    	Q_CAP_C0402    	          	          	                    
          	               	1         	162B3     	GND                 
          	               	2         	162B3     	P12V_OCP_REG_2      

PC2147    	Q_CAP_C0402    	          	          	                    
          	               	1         	162B3     	GND                 
          	               	2         	162B3     	P3V3_OCP_REG_2      

PC2149    	Q_CAP_C0402    	          	          	                    
          	               	1         	162B2     	P3V3_OCP_V3_2_R     
          	               	2         	162B2     	P3V3_OCP_GATE_2     

PC2150    	Q_CAP_C0402    	          	          	                    
          	               	1         	162B1     	P12V_OCP_GATE_2     
          	               	2         	162B1     	GND                 

PC2151    	Q_CAP_C0402    	          	          	                    
          	               	1         	162B1     	P3V3_OCP_GATE_2     
          	               	2         	162B1     	GND                 

PC2152    	Q_CAP_0402     	          	          	                    
          	               	1         	162B1     	P12V_OCP_V3_2       
          	               	2         	162B1     	GND                 

PC2153    	Q_CAP_0402     	          	          	                    
          	               	1         	157A4     	P12V_OCP_TIMER_1    
          	               	2         	157A4     	GND                 

PC2154    	Q_CAP_C0402    	          	          	                    
          	               	1         	157A4     	P12V_AUX            
          	               	2         	157A4     	GND                 

PC2155    	Q_CAP_C0402    	          	          	                    
          	               	1         	157A4     	P12V_OCP_SS_1       
          	               	2         	157A4     	GND                 

PC2156    	Q_CAP_C0402    	          	          	                    
          	               	1         	157A3     	P12V_OCP_IMON_1     
          	               	2         	157A3     	GND                 

PC2157    	Q_CAP_C0402    	          	          	                    
          	               	1         	157B3     	P3V3_OCP_MODE_1     
          	               	2         	157B3     	GND                 

PC2158    	Q_CAP_C0603    	          	          	                    
          	               	1         	157A2     	P12V_OCP_AVIN_PD_1  
          	               	2         	157A2     	GND                 

PC2159    	Q_CAP_C0402    	          	          	                    
          	               	1         	157B2     	P3V3_AUX            
          	               	2         	157B2     	GND                 

PC2160    	Q_CAP_0402     	          	          	                    
          	               	1         	157A2     	P12V_OCP_SFF        
          	               	2         	157A2     	GND                 

PC2161    	Q_CAP_0402     	          	          	                    
          	               	1         	157B2     	P3V3_OCP_DVDT_1     
          	               	2         	157B2     	GND                 

PC2162    	Q_CAP_0402     	          	          	                    
          	               	1         	157B1     	P3V3_OCP_GATE_1     
          	               	2         	157B1     	GND                 

PC2163    	Q_CAP_C0805    	          	          	                    
          	               	1         	157B1     	P3V3_OCP_SFF_R      
          	               	2         	157B1     	GND                 

PC2164    	Q_CAP_0402     	          	          	                    
          	               	1         	163A4     	P12V_OCP_TIMER_2    
          	               	2         	163A4     	GND                 

PC2165    	Q_CAP_C0402    	          	          	                    
          	               	1         	163A4     	P12V_AUX            
          	               	2         	163A4     	GND                 

PC2166    	Q_CAP_C0402    	          	          	                    
          	               	1         	163A4     	P12V_OCP_SS_2       
          	               	2         	163A4     	GND                 

PC2167    	Q_CAP_0402     	          	          	                    
          	               	1         	163A3     	P12V_OCP_IMON_2     
          	               	2         	163A3     	GND                 

PC2168    	Q_CAP_C0402    	          	          	                    
          	               	1         	163B2     	P3V3_OCP_MODE_2     
          	               	2         	163B2     	GND                 

PC2169    	Q_CAP_C0402    	          	          	                    
          	               	1         	163B2     	P3V3_AUX            
          	               	2         	163B2     	GND                 

PC2170    	Q_CAPP_SMLF    	          	          	                    
          	               	1         	272B1     	PVCCFA_EHV_FIVRA_CPU0
          	               	2         	272B1     	GND                 

PC2171    	Q_CAPP_SMLF    	          	          	                    
          	               	1         	290B1     	PVCCFA_EHV_FIVRA_CPU1
          	               	2         	290B1     	GND                 

PC2172    	Q_CAPP_SMLF    	          	          	                    
          	               	1         	289A1     	PVCCFA_EHV_FIVRA_CPU1
          	               	2         	289A1     	GND                 

PC2173    	Q_CAP_C0805    	          	          	                    
          	               	1         	163B1     	P3V3_OCP_V3_2_R     
          	               	2         	163B1     	GND                 

PC2174    	Q_CAP_0402     	          	          	                    
          	               	1         	163A2     	P12V_OCP_V3_2       
          	               	2         	163A2     	GND                 

PC2180    	Q_CAPP_THLF    	          	          	                    
          	               	1         	276B1     	PVCCFA_EHV_CPU0     
          	               	2         	276B1     	GND                 

PC2181    	Q_CAP_C0402    	          	          	                    
          	               	1         	302A4     	HSC_VDD_R_2         
          	               	2         	302A4     	AGND_HSC            

PC2182    	Q_CAP_0402     	          	          	                    
          	               	1         	302B4     	HSC_ON              
          	               	2         	302B4     	AGND_HSC            

PC2183    	Q_CAP_0402     	          	          	                    
          	               	1         	302A4     	HSC_ON              
          	               	2         	302A4     	AGND_HSC            

PC2184    	Q_CAP_0402     	          	          	                    
          	               	1         	302B2     	HSC_SS              
          	               	2         	302B2     	AGND_HSC            

PC2185    	Q_CAP_0402     	          	          	                    
          	               	1         	302A2     	HSC_SS              
          	               	2         	302A2     	AGND_HSC            

PC2186    	Q_CAP_C0402    	          	          	                    
          	               	1         	301B4     	HSC_VDD_R           
          	               	2         	301B4     	AGND_HSC            

PC2187    	Q_CAP_C0402    	          	          	                    
          	               	1         	301B4     	HSC_VDD_R           
          	               	2         	301B4     	AGND_HSC            

PC2188    	Q_CAP_C0402    	          	          	                    
          	               	1         	301B4     	P12V_PSU            
          	               	2         	301B4     	GND                 

PC2189    	Q_CAP_C0402    	          	          	                    
          	               	1         	301B4     	HSC_VSENSE          
          	               	2         	301B4     	AGND_HSC            

PC2190    	Q_CAP_C0402    	          	          	                    
          	               	1         	301B2     	HSC_VOSEN           
          	               	2         	301B2     	AGND_HSC            

PC2191    	Q_CAP_0402     	          	          	                    
          	               	1         	301B2     	HSC_SS              
          	               	2         	301B2     	AGND_HSC            

PC2192    	Q_CAP_C0402    	          	          	                    
          	               	1         	301B2     	HSC_VTEMP           
          	               	2         	301B2     	AGND_HSC            

PC2193    	Q_CAP_C0402    	          	          	                    
          	               	1         	301B1     	HSC_IMON            
          	               	2         	301B1     	AGND_HSC            

PC2196    	Q_CAP_0402     	          	          	                    
          	               	1         	193B4     	P12V_E1S_TIMER_0    
          	               	2         	193B4     	GND                 

PC2197    	Q_CAP_C0402    	          	          	                    
          	               	1         	193A3     	P3V3_E1S_MODE_0     
          	               	2         	193A3     	GND                 

PC2198    	Q_CAP_C0402    	          	          	                    
          	               	1         	193B3     	P12V_AUX            
          	               	2         	193B3     	GND                 

PC2199    	Q_CAPP_THLF    	          	          	                    
          	               	1         	294B2     	PVCCFA_EHV_CPU1     
          	               	2         	294B2     	GND                 

PC2200    	Q_CAP_C0402    	          	          	                    
          	               	1         	193A3     	P3V3_AUX            
          	               	2         	193A3     	GND                 

PC2201    	Q_CAP_0402     	          	          	                    
          	               	1         	193A3     	P3V3_E1S_DVDT_0     
          	               	2         	193A3     	GND                 

PC2202    	Q_CAP_C0402    	          	          	                    
          	               	1         	193B2     	P12V_E1S_IMON_0     
          	               	2         	193B2     	GND                 

PC2203    	Q_CAP_0402     	          	          	                    
          	               	1         	193A2     	P3V3_E1S_GATE_0_PU293
          	               	2         	193A2     	GND                 

PC2204    	Q_CAP_C0805    	          	          	                    
          	               	1         	193A2     	P3V3_E1S_0_R        
          	               	2         	193A2     	GND                 

PC2205    	Q_CAP_C0603    	          	          	                    
          	               	1         	193B2     	P12V_E1S_AVIN_PD_0  
          	               	2         	193B2     	GND                 

PC2206    	Q_CAP_0402     	          	          	                    
          	               	1         	193B1     	P12V_E1S_0          
          	               	2         	193B1     	GND                 

PC2207    	Q_CAP_C0402    	          	          	                    
          	               	1         	192B3     	P12V_AUX            
          	               	2         	192B3     	GND                 

PC2208    	Q_CAP_C0402    	          	          	                    
          	               	1         	192A3     	P3V3_AUX            
          	               	2         	192A3     	GND                 

PC2209    	Q_CAP_C0402    	          	          	                    
          	               	1         	192B3     	P12V_E1S_VCC_0      
          	               	2         	192B3     	GND                 

PC2210    	Q_CAP_C0402    	          	          	                    
          	               	1         	192A3     	P3V3_E1S_VCC_0      
          	               	2         	192A3     	GND                 

PC2211    	Q_CAP_C0402    	          	          	                    
          	               	1         	192B3     	GND                 
          	               	2         	192B3     	P12V_E1S_REG_0      

PC2212    	Q_CAP_C0402    	          	          	                    
          	               	1         	192A3     	GND                 
          	               	2         	192A3     	P3V3_E1S_REG_0      

PC2213    	Q_CAP_C0402    	          	          	                    
          	               	1         	192A2     	P3V3_E1S_0_R        
          	               	2         	192A2     	P3V3_E1S_GATE_0     

PC2214    	Q_CAP_C0402    	          	          	                    
          	               	1         	192B2     	P12V_E1S_0          
          	               	2         	192B2     	P12V_E1S_GATE_0     

PC2215    	Q_CAP_C0402    	          	          	                    
          	               	1         	192B1     	P12V_E1S_GATE_0     
          	               	2         	192B1     	GND                 

PC2216    	Q_CAP_C0402    	          	          	                    
          	               	1         	192A1     	P3V3_E1S_GATE_0     
          	               	2         	192A1     	GND                 

PC2217    	Q_CAP_0402     	          	          	                    
          	               	1         	192B1     	P12V_E1S_0          
          	               	2         	192B1     	GND                 

PC2218    	Q_CAP_0402     	          	          	                    
          	               	1         	192B1     	P3V3_E1S_0_R        
          	               	2         	192A1     	GND                 

PC2219    	Q_CAP_C0805    	          	          	                    
          	               	1         	192B1     	P12V_E1S_0          
          	               	2         	192B1     	GND                 

PC2220    	Q_CAP_C0805    	          	          	                    
          	               	1         	192B1     	P3V3_E1S_0_R        
          	               	2         	192A1     	GND                 

PC2221    	Q_CAP_C0402    	          	          	                    
          	               	1         	282A4     	PVNN_MAIN_CPU0_VCC  
          	               	2         	282A4     	GND                 

PC2222    	Q_CAP_C0402    	          	          	                    
          	               	1         	300A4     	PVNN_MAIN_CPU1_VCC  
          	               	2         	300A4     	GND                 

PC2223    	Q_CAP_C0402    	          	          	                    
          	               	1         	303A4     	HSC_VDD_R_4         
          	               	2         	303A4     	AGND_HSC            

PC2224    	Q_CAP_0402     	          	          	                    
          	               	1         	303B4     	HSC_ON              
          	               	2         	303B4     	AGND_HSC            

PC2225    	Q_CAP_0402     	          	          	                    
          	               	1         	303A4     	HSC_ON              
          	               	2         	303A4     	AGND_HSC            

PC2226    	Q_CAP_0402     	          	          	                    
          	               	1         	303B2     	HSC_SS              
          	               	2         	303B2     	AGND_HSC            

PC2227    	Q_CAP_0402     	          	          	                    
          	               	1         	303A2     	HSC_SS              
          	               	2         	303A2     	AGND_HSC            

PC2229    	Q_CAP_0402     	          	          	                    
          	               	1         	242A3     	P12V_SCM_TIMER      
          	               	2         	242A3     	GND                 

PC2230    	Q_CAP_C0402    	          	          	                    
          	               	1         	242B3     	P12V_AUX            
          	               	2         	242B3     	GND                 

PC2231    	Q_CAP_C0402    	          	          	                    
          	               	1         	242B3     	P12V_AUX            
          	               	2         	242A3     	GND                 

PC2232    	Q_CAP_C0402    	          	          	                    
          	               	1         	242A3     	P12V_SCM_SS         
          	               	2         	242A3     	GND                 

PC2233    	Q_CAP_C0402    	          	          	                    
          	               	1         	242B3     	P12V_SCM_VCC        
          	               	2         	242B3     	GND                 

PC2234    	Q_CAP_C0402    	          	          	                    
          	               	1         	242B3     	GND                 
          	               	2         	242B2     	P12V_SCM_REG        

PC2235    	Q_CAP_C0402    	          	          	                    
          	               	1         	242A2     	P12V_SCM_IMON       
          	               	2         	242A2     	GND                 

PC2236    	Q_CAP_C0402    	          	          	                    
          	               	1         	242B2     	P12V_SCM_R          
          	               	2         	242B2     	P12V_SCM_GATE       

PC2237    	Q_CAP_C0402    	          	          	                    
          	               	1         	242B1     	P12V_SCM_GATE       
          	               	2         	242B1     	GND                 

PC2238    	Q_CAP_0402     	          	          	                    
          	               	1         	242B1     	P12V_SCM_R          
          	               	2         	242B1     	GND                 

PC2239    	Q_CAP_C0603    	          	          	                    
          	               	1         	242A1     	P12V_SCM_AVIN_PD    
          	               	2         	242A1     	GND                 

PC2240    	Q_CAP_C0805    	          	          	                    
          	               	1         	242B1     	P12V_SCM_R          
          	               	2         	242B1     	GND                 

PC2241    	Q_CAP_0402     	          	          	                    
          	               	1         	242B1     	P12V_SCM_R          
          	               	2         	242A1     	GND                 

PC2242    	Q_CAP_C0805    	          	          	                    
          	               	1         	242B1     	P12V_SCM_R          
          	               	2         	242B1     	GND                 

PC2260    	Q_CAP_C0805    	          	          	                    
          	               	1         	259B4     	SW_P3V3_AUX_FLT     
          	               	2         	259B4     	GND                 

PC2261    	Q_CAP_C0805    	          	          	                    
          	               	1         	259B4     	SW_P3V3_AUX_FLT     
          	               	2         	259B4     	GND                 

PC2262    	Q_CAP_C0805    	          	          	                    
          	               	1         	259B4     	SW_P3V3_AUX_FLT     
          	               	2         	259B4     	GND                 

PC2263    	Q_CAP_C0805    	          	          	                    
          	               	1         	259B4     	SW_P3V3_AUX_FLT     
          	               	2         	259B4     	GND                 

PC2277    	Q_CAP_0402     	          	          	                    
          	               	1         	300A1     	PVNN_MAIN_CPU1_FB_RC
          	               	2         	300A1     	GND                 

PC2279    	Q_CAP_0402     	          	          	                    
          	               	1         	262A1     	SH_P1V05_PCH_AUX_P  
          	               	2         	262A1     	SH_P1V05_PCH_AUX_N  

PC2280    	Q_CAP_C0805    	          	          	                    
          	               	1         	192B1     	P12V_E1S_0          
          	               	2         	192B1     	GND                 

PC2281    	Q_CAP_C0402    	          	          	                    
          	               	1         	193B3     	P12V_E1S_SS_0       
          	               	2         	193B3     	GND                 

PC2282    	Q_CAP_0402     	          	          	                    
          	               	1         	299A2     	SH_PVPP_HBM_CPU1_P  
          	               	2         	299A2     	SH_PVPP_HBM_CPU1_N  

PC2286    	Q_CAP_0402     	          	          	                    
          	               	1         	262B4     	FM_P1V05_PCH_AUX_R_EN
          	               	2         	262B4     	GND                 

PC2336    	Q_CAPP_SMLF    	          	          	                    
          	               	1         	267A2     	PVCCIN_CPU0         
          	               	2         	267A2     	GND                 

PC2340    	Q_CAP_C0402    	          	          	                    
          	               	1         	242A3     	P12V_SCM_ISET_R     
          	               	2         	242A3     	GND                 

PC2341    	Q_CAP_C0402    	          	          	                    
          	               	1         	193B4     	P12V_E1S_ISET_0_R   
          	               	2         	193B4     	GND                 

PC2342    	Q_CAP_C0805    	          	          	                    
          	               	1         	259B4     	SW_P3V3_AUX_FLT     
          	               	2         	259B4     	GND                 

PC2343    	Q_CAP_C0805    	          	          	                    
          	               	1         	259B4     	SW_P3V3_AUX_FLT     
          	               	2         	259B4     	GND                 

PC2344    	Q_CAP_C0805    	          	          	                    
          	               	1         	259B4     	SW_P3V3_AUX_FLT     
          	               	2         	259B4     	GND                 

PC2345    	Q_CAPP_THLF    	          	          	                    
          	               	1         	267B1     	SW_P12V_PVCCIN_CPU0_FLT
          	               	2         	267B1     	GND                 

PC2346    	Q_CAPP_THLF    	          	          	                    
          	               	1         	285B1     	SW_P12V_PVCCIN_CPU1_FLT
          	               	2         	285B1     	GND                 

PC2347    	Q_CAP_0402     	          	          	                    
          	               	1         	302B4     	HSC_OCREF           
          	               	2         	302B4     	AGND_HSC            

PC2348    	Q_CAP_0402     	          	          	                    
          	               	1         	302A4     	HSC_OCREF           
          	               	2         	302A4     	AGND_HSC            

PC2349    	Q_CAP_0402     	          	          	                    
          	               	1         	303A4     	HSC_OCREF           
          	               	2         	303A4     	AGND_HSC            

PC2350    	Q_CAP_0402     	          	          	                    
          	               	1         	303B4     	HSC_OCREF           
          	               	2         	303B4     	AGND_HSC            

PC2361    	Q_CAP_0402     	          	          	                    
          	               	1         	266B2     	PVCCIN_CPU0_VCC     
          	               	2         	266B2     	GND                 

PC2362    	Q_CAP_0402     	          	          	                    
          	               	1         	274B2     	PVCCINFAON_CPU0_VCC 
          	               	2         	274B2     	GND                 

PC2365    	Q_CAP_0402     	          	          	                    
          	               	1         	278B2     	PVCCD_HV_CPU0_VCC   
          	               	2         	278B2     	GND                 

PC2366    	Q_CAP_0402     	          	          	                    
          	               	1         	284B2     	PVCCIN_CPU1_VCC     
          	               	2         	284B2     	GND                 

PC2367    	Q_CAP_0402     	          	          	                    
          	               	1         	292B2     	PVCCINFAON_CPU1_VCC 
          	               	2         	292B2     	GND                 

PC2368    	Q_CAP_0402     	          	          	                    
          	               	1         	296B2     	PVCCD_HV_CPU1_VCC   
          	               	2         	296B2     	GND                 

PC2643    	Q_CAP_C0402    	          	          	                    
          	               	1         	281A4     	PVPP_HBM_CPU0_VCC   
          	               	2         	281A4     	GND                 

PC2645    	Q_CAPP_SMLF    	          	          	                    
          	               	1         	271B1     	PVCCFA_EHV_FIVRA_CPU0
          	               	2         	271A1     	GND                 

PC2946    	Q_CAP_C0402    	          	          	                    
          	               	1         	275B4     	PVCCFA_EHV_CPU0_PVCC
          	               	2         	275A4     	GND                 

PC2947    	Q_CAP_C0402    	          	          	                    
          	               	1         	275B4     	PVCCFA_EHV_CPU0_PVCC
          	               	2         	275B4     	GND                 

PC2948    	Q_CAP_C0402    	          	          	                    
          	               	1         	279B4     	PVCCFA_EHV_CPU0_PVCC
          	               	2         	279B4     	GND                 

PC2949    	Q_CAP_C0402    	          	          	                    
          	               	1         	293A4     	PVCCFA_EHV_CPU1_PVCC
          	               	2         	293A4     	GND                 

PC2950    	Q_CAP_C0402    	          	          	                    
          	               	1         	293B4     	PVCCFA_EHV_CPU1_PVCC
          	               	2         	293B4     	GND                 

PC2951    	Q_CAP_C0402    	          	          	                    
          	               	1         	297B4     	PVCCFA_EHV_CPU1_PVCC
          	               	2         	297B4     	GND                 

PC3272    	Q_CAP_C0402    	          	          	                    
          	               	1         	303B4     	HSC_VDD_R_3         
          	               	2         	303B4     	AGND_HSC            

PC4056    	Q_CAP_C0402    	          	          	                    
          	               	1         	156B1     	P12V_OCP_GATE_1     
          	               	2         	156B1     	GND                 

PC5328    	Q_CAP_C0402    	          	          	                    
          	               	1         	156B3     	P3V3_AUX            
          	               	2         	156B3     	GND                 

PD15      	ZENER_AC       	          	          	                    
          	               	A         	304B4     	GND                 
          	               	C         	304B4     	P12V_PSU_FUSE       

PD16      	ZENER_AC       	          	          	                    
          	               	A         	304B3     	GND                 
          	               	C         	304B3     	P12V_PSU_FUSE       

PD17      	SS15P3SM386A   	          	          	                    
          	               	1         	304A1     	GND                 
          	               	2         	304A1     	GND                 
          	               	K         	304B1     	P12V_AUX            

PD101     	DIODE_TVS      	          	          	                    
          	               	A         	156B3     	GND                 
          	               	C         	156B3     	P12V_AUX            

PD102     	SCHOTTKY_AC    	          	          	                    
          	               	A         	156B2     	GND                 
          	               	C         	156B2     	P12V_OCP_SFF        

PD103     	SCHOTTKY_AC    	          	          	                    
          	               	A         	156B1     	GND                 
          	               	C         	156B1     	P3V3_OCP_SFF_R      

PD107     	DIODE_TVS      	          	          	                    
          	               	A         	162B3     	GND                 
          	               	C         	162B3     	P12V_AUX            

PD108     	SCHOTTKY_AC    	          	          	                    
          	               	A         	162B1     	GND                 
          	               	C         	162B1     	P12V_OCP_V3_2       

PD109     	SCHOTTKY_AC    	          	          	                    
          	               	A         	162B1     	GND                 
          	               	C         	162B1     	P3V3_OCP_V3_2_R     

PD112     	SCHOTTKY_AC    	          	          	                    
          	               	A         	192B1     	GND                 
          	               	C         	192B1     	P12V_E1S_0          

PD113     	SCHOTTKY_AC    	          	          	                    
          	               	A         	192A1     	GND                 
          	               	C         	192B1     	P3V3_E1S_0_R        

PD114     	DIODE_TVS      	          	          	                    
          	               	A         	192B3     	GND                 
          	               	C         	192B3     	P12V_AUX            

PD115     	DIODE_TVS      	          	          	                    
          	               	A         	242B3     	GND                 
          	               	C         	242B3     	P12V_AUX            

PD116     	SCHOTTKY_AC    	          	          	                    
          	               	A         	242B1     	GND                 
          	               	C         	242B1     	P12V_SCM_R          

PJ42      	SCONN21_9193031121LF	          	          	                    
          	               	1         	305B2     	P12V_PSU            
          	               	2         	305B2     	P12V_HSC_SENSE1_P   
          	               	3         	305B2     	P12V_HSC_SENSE1_N   
          	               	4         	305B2     	P12V_HSC_SENSE2_P   
          	               	5         	305B2     	P12V_HSC_SENSE2_N   
          	               	6         	305B2     	P12V_HSC_ADC_N      
          	               	7         	305B2     	P12V_HSC_ADC_P      
          	               	8         	305B2     	P12V_HSC_GATE1      
          	               	9         	305B2     	P12V_HSC_GATE2      
          	               	10        	305B2     	P12V_AUX            
          	               	11        	305B2     	GND                 
          	               	12        	305B2     	P3V3_AUX            
          	               	13        	305B2     	IRQ_HSC_FAULT_N     
          	               	14        	305B2     	HSC_EN              
          	               	15        	305B2     	MB0_P12V_STBY_PWRGD 
          	               	16        	305B2     	HSC_CSOUT           
          	               	17        	305B2     	HSC_TYPE_ADC        
          	               	18        	305B2     	SMB_SML1_PMBUS_HSC_MODULE_SCL
          	               	19        	305B2     	SMB_SML1_PMBUS_HSC_MODULE_SDA
          	               	20        	305B2     	IRQ_SML1_PMBUS_ALERT_N
          	               	21        	305B2     	GND                 
          	               	G1        	305B2     	GND                 
          	               	G2        	305B2     	GND                 

PJ45      	Q_SHORT_SM     	          	          	                    
          	               	1         	274B4     	VSENSE_PVCCINFAON_CPU0_DP
          	               	2         	274B4     	SH_PVCCINFAON_CPU0  

PJ46      	Q_SHORT_SM     	          	          	                    
          	               	1         	274B4     	VSENSE_PVCCFA_EHV_CPU0_DP
          	               	2         	274B4     	SH_PVCCFA_EHV_CPU0  

PJ47      	Q_SHORT_SM     	          	          	                    
          	               	1         	266B4     	VSENSE_PVCCIN_CPU0_DP
          	               	2         	266B4     	SH_PVCCIN_CPU0      

PJ48      	Q_SHORT_SM     	          	          	                    
          	               	1         	296B4     	VSENSE_PVCCD_HV_CPU1_DP
          	               	2         	296B4     	SH_PVCCD_HV_CPU1    

PJ49      	Q_SHORT_SM     	          	          	                    
          	               	1         	284B4     	VSENSE_PVCCFA_EHV_FIVRA_CPU1_DP
          	               	2         	284B4     	SH_PVCCFA_EHV_FIVRA_CPU1

PJ50      	Q_SHORT_SM     	          	          	                    
          	               	1         	292B4     	VSENSE_PVCCINFAON_CPU1_DP
          	               	2         	292B4     	SH_PVCCINFAON_CPU1  

PJ51      	Q_SHORT_SM     	          	          	                    
          	               	1         	292B4     	VSENSE_PVCCFA_EHV_CPU1_DP
          	               	2         	292B4     	SH_PVCCFA_EHV_CPU1  

PJ52      	Q_SHORT_SM     	          	          	                    
          	               	1         	284B4     	VSENSE_PVCCIN_CPU1_DP
          	               	2         	284B4     	SH_PVCCIN_CPU1      

PJ53      	Q_SHORT_SM     	          	          	                    
          	               	1         	266B4     	VSENSE_PVCCFA_EHV_FIVRA_CPU0_DP
          	               	2         	266B4     	SH_PVCCFA_EHV_FIVRA_CPU0

PJ54      	Q_SHORT_SM     	          	          	                    
          	               	1         	278B4     	VSENSE_PVCCD_HV_CPU0_DP
          	               	2         	278B4     	SH_PVCCD_HV_CPU0    

PJ62      	Q_SHORT_SM     	          	          	                    
          	               	1         	262A1     	SH_P1V05_PCH_AUX_P  
          	               	2         	262A1     	P1V05_PCH_AUX       

PJ63      	Q_SHORT_SM     	          	          	                    
          	               	1         	262A1     	SH_P1V05_PCH_AUX_N  
          	               	2         	262A1     	GND                 

PJ64      	Q_SHORT_SM     	          	          	                    
          	               	1         	281A1     	SH_PVPP_HBM_CPU0_P  
          	               	2         	281A1     	PVPP_HBM_CPU0       

PJ65      	Q_SHORT_SM     	          	          	                    
          	               	1         	281A1     	SH_PVPP_HBM_CPU0_N  
          	               	2         	281A1     	GND                 

PJ66      	Q_SHORT_SM     	          	          	                    
          	               	1         	299B1     	SH_PVPP_HBM_CPU1_P  
          	               	2         	299B1     	PVPP_HBM_CPU1       

PJ67      	Q_SHORT_SM     	          	          	                    
          	               	1         	299A1     	SH_PVPP_HBM_CPU1_N  
          	               	2         	299A1     	GND                 

PJP1      	CONN3_210HP1030BR1	          	          	                    
          	               	1         	266B4     	SMB_VR_3V3AUX_SCL_R3
          	               	2         	266B4     	GND                 
          	               	3         	266B4     	SMB_VR_3V3AUX_SDA_R3

PL2       	Q_INDUCTOR_SMLF	          	          	                    
          	               	1         	272B2     	SW_PVCCFA_EHV_FIVRA_CPU0_SW3
          	               	2         	272B2     	PVCCFA_EHV_FIVRA_CPU0

PL3       	Q_INDUCTOR_SMLF	          	          	                    
          	               	1         	276B2     	SW_PVCCFA_EHV_CPU0_SW1
          	               	2         	276B2     	PVCCFA_EHV_CPU0     

PL4       	Q_INDUCTOR_SMLF	          	          	                    
          	               	1         	275B3     	SW_PVCCINFAON_CPU0_SW1
          	               	2         	275B3     	PVCCINFAON_CPU0     

PL5       	Q_INDUCTOR_SMLF	          	          	                    
          	               	1         	275A3     	SW_PVCCINFAON_CPU0_SW2
          	               	2         	275A3     	PVCCINFAON_CPU0     

PL6       	Q_INDUCTOR_SMLF	          	          	                    
          	               	1         	275B2     	P12V_AUX            
          	               	2         	275B2     	SW_P12V_PVCCINFAON_CPU0_FLT

PL7       	Q_INDUCTOR4P_14	          	          	                    
          	               	1         	270A2     	SW_PVCCIN_CPU0_SW8  
          	               	2         	270A2     	IND_P0_CPL8         
          	               	3         	270A2     	GND                 
          	               	4         	270A2     	PVCCIN_CPU0         

PL8       	Q_INDUCTOR4P_14	          	          	                    
          	               	1         	270B2     	SW_PVCCIN_CPU0_SW7  
          	               	2         	270B2     	IND_P0_CPL7         
          	               	3         	270B2     	IND_P0_CPL6         
          	               	4         	270B2     	PVCCIN_CPU0         

PL9       	Q_INDUCTOR4P_14	          	          	                    
          	               	1         	269A2     	SW_PVCCIN_CPU0_SW6  
          	               	2         	269A2     	IND_P0_CPL6         
          	               	3         	269A2     	IND_P0_CPL1         
          	               	4         	269A2     	PVCCIN_CPU0         

PL10      	Q_INDUCTOR4P_14	          	          	                    
          	               	1         	269B2     	SW_PVCCIN_CPU0_SW5  
          	               	2         	269B2     	IND_P0_CPL5         
          	               	3         	269B2     	IND_P0_CPL8         
          	               	4         	269B2     	PVCCIN_CPU0         

PL11      	Q_INDUCTOR4P_14	          	          	                    
          	               	1         	268A2     	SW_PVCCIN_CPU0_SW4  
          	               	2         	268A2     	IND_P0_CPL4         
          	               	3         	268A2     	IND_P0_CPL5         
          	               	4         	268A2     	PVCCIN_CPU0         

PL12      	Q_INDUCTOR_SMLF	          	          	                    
          	               	1         	290B3     	SW_PVCCFA_EHV_FIVRA_CPU1_SW3
          	               	2         	290B2     	PVCCFA_EHV_FIVRA_CPU1

PL13      	Q_INDUCTOR4P_14	          	          	                    
          	               	1         	267A3     	SW_PVCCIN_CPU0_SW2  
          	               	2         	267A3     	IND_P0_CPL2         
          	               	3         	267A2     	IND_P0_CPL3         
          	               	4         	267A2     	PVCCIN_CPU0         

PL14      	Q_INDUCTOR_SMLF	          	          	                    
          	               	1         	290B2     	P12V_AUX            
          	               	2         	290B2     	SW_P12V_PVCCFA_EHV_FIVRA_CPU1_R

PL15      	Q_INDUCTOR_SMLF	          	          	                    
          	               	1         	267B2     	P12V_AUX            
          	               	2         	267B2     	SW_P12V_PVCCIN_CPU0_FLT

PL16      	Q_INDUCTOR_SMLF	          	          	                    
          	               	1         	263B4     	P12V_AUX            
          	               	2         	263B4     	SW_P1V8_PCH_AUX_FLT 

PL17      	Q_INDUCTOR_SMLF	          	          	                    
          	               	1         	297B2     	SW_PVCCD_HV_CPU1_SW1
          	               	2         	297B2     	PVCCD_HV_CPU1       

PL18      	Q_INDUCTOR_SMLF	          	          	                    
          	               	1         	289B2     	SW_PVCCFA_EHV_FIVRA_CPU1_SW1
          	               	2         	289B2     	PVCCFA_EHV_FIVRA_CPU1

PL19      	Q_INDUCTOR_SMLF	          	          	                    
          	               	1         	289A2     	SW_PVCCFA_EHV_FIVRA_CPU1_SW2
          	               	2         	289A2     	PVCCFA_EHV_FIVRA_CPU1

PL20      	Q_INDUCTOR_SMLF	          	          	                    
          	               	1         	294B2     	SW_PVCCFA_EHV_CPU1_SW1
          	               	2         	294B2     	PVCCFA_EHV_CPU1     

PL21      	Q_INDUCTOR_SMLF	          	          	                    
          	               	1         	293B3     	SW_PVCCINFAON_CPU1_SW1
          	               	2         	293B3     	PVCCINFAON_CPU1     

PL22      	Q_INDUCTOR_SMLF	          	          	                    
          	               	1         	293A3     	SW_PVCCINFAON_CPU1_SW2
          	               	2         	293A3     	PVCCINFAON_CPU1     

PL23      	Q_INDUCTOR_SMLF	          	          	                    
          	               	1         	293B2     	P12V_AUX            
          	               	2         	293B2     	SW_P12V_PVCCINFAON_CPU1_FLT

PL24      	Q_INDUCTOR4P_14	          	          	                    
          	               	1         	288A2     	SW_PVCCIN_CPU1_SW8  
          	               	2         	288A2     	IND_P1_CPL8         
          	               	3         	288A2     	IND_P1_CPL5         
          	               	4         	288A2     	PVCCIN_CPU1         

PL25      	Q_INDUCTOR4P_14	          	          	                    
          	               	1         	288B2     	SW_PVCCIN_CPU1_SW7  
          	               	2         	288B2     	IND_P1_CPL7         
          	               	3         	288B2     	GND                 
          	               	4         	288B2     	PVCCIN_CPU1         

PL26      	Q_INDUCTOR4P_14	          	          	                    
          	               	1         	287A2     	SW_PVCCIN_CPU1_SW6  
          	               	2         	287A2     	IND_P1_CPL6         
          	               	3         	287A2     	IND_P1_CPL7         
          	               	4         	287A2     	PVCCIN_CPU1         

PL27      	Q_INDUCTOR4P_14	          	          	                    
          	               	1         	287B2     	SW_PVCCIN_CPU1_SW5  
          	               	2         	287B2     	IND_P1_CPL5         
          	               	3         	287B2     	IND_P1_CPL4         
          	               	4         	287B2     	PVCCIN_CPU1         

PL28      	Q_INDUCTOR4P_14	          	          	                    
          	               	1         	286A2     	SW_PVCCIN_CPU1_SW4  
          	               	2         	286A2     	IND_P1_CPL4         
          	               	3         	286A2     	IND_P1_CPL3         
          	               	4         	286A2     	PVCCIN_CPU1         

PL29      	Q_INDUCTOR4P_14	          	          	                    
          	               	1         	286B2     	SW_PVCCIN_CPU1_SW3  
          	               	2         	286B2     	IND_P1_CPL3         
          	               	3         	286B2     	IND_P1_CPL2         
          	               	4         	286B2     	PVCCIN_CPU1         

PL30      	Q_INDUCTOR4P_14	          	          	                    
          	               	1         	285A3     	SW_PVCCIN_CPU1_SW2  
          	               	2         	285A3     	IND_P1_CPL2         
          	               	3         	285A2     	IND_P1_CPL1         
          	               	4         	285A2     	PVCCIN_CPU1         

PL31      	Q_INDUCTOR4P_14	          	          	                    
          	               	1         	285B3     	SW_PVCCIN_CPU1_SW1  
          	               	2         	285B3     	IND_P1_CPL1         
          	               	3         	285B2     	IND_P1_CPL6         
          	               	4         	285B2     	PVCCIN_CPU1         

PL32      	Q_INDUCTOR_SMLF	          	          	                    
          	               	1         	285B2     	P12V_AUX            
          	               	2         	285B2     	SW_P12V_PVCCIN_CPU1_FLT

PL33      	Q_INDUCTOR_SMLF	          	          	                    
          	               	1         	271B2     	SW_PVCCFA_EHV_FIVRA_CPU0_SW1
          	               	2         	271B2     	PVCCFA_EHV_FIVRA_CPU0

PL34      	Q_INDUCTOR_SMLF	          	          	                    
          	               	1         	271A2     	SW_PVCCFA_EHV_FIVRA_CPU0_SW2
          	               	2         	271A2     	PVCCFA_EHV_FIVRA_CPU0

PL35      	Q_INDUCTOR_SMLF	          	          	                    
          	               	1         	279B3     	SW_PVCCD_HV_CPU0_SW1
          	               	2         	279B2     	PVCCD_HV_CPU0       

PL43      	Q_INDUCTOR_SMLF	          	          	                    
          	               	1         	289B2     	P12V_AUX            
          	               	2         	289B2     	SW_P12V_PVCCFA_EHV_FIVRA_CPU1_L

PL44      	Q_INDUCTOR_SMLF	          	          	                    
          	               	1         	271B2     	P12V_AUX            
          	               	2         	271B2     	SW_P12V_PVCCFA_EHV_FIVRA_CPU0_L

PL45      	Q_INDUCTOR_SMLF	          	          	                    
          	               	1         	259B4     	P12V_AUX            
          	               	2         	259B4     	SW_P3V3_AUX_FLT     

PL64      	Q_INDUCTOR_SMLF	          	          	                    
          	               	1         	258B4     	P12V_AUX            
          	               	2         	258B4     	SW_P5V_AUX_FLT      

PL65      	Q_INDUCTOR_SMLF	          	          	                    
          	               	1         	258B2     	SW_P5V_AUX_SW       
          	               	2         	258B2     	P5V_AUX             

PL66      	Q_INDUCTOR_SMLF	          	          	                    
          	               	1         	259B2     	SW_P3V3_AUX_SW      
          	               	2         	259B2     	P3V3_AUX            

PL101     	Q_INDUCTOR_SMLF	          	          	                    
          	               	1         	272B2     	P12V_AUX            
          	               	2         	272B2     	SW_P12V_PVCCFA_EHV_FIVRA_CPU0_R

PL105     	Q_INDUCTOR_SMLF	          	          	                    
          	               	1         	270B3     	IND_P0_CPL7         
          	               	2         	270B3     	GND                 

PL106     	Q_INDUCTOR_SMLF	          	          	                    
          	               	1         	288A3     	IND_P1_CPL8         
          	               	2         	288A3     	GND                 

PL110     	Q_INDUCTOR_SMLF	          	          	                    
          	               	1         	262B4     	P12V_AUX            
          	               	2         	262B4     	SW_P12V_AUX_P1V05_PCH_AUX_FLT

PL112     	Q_INDUCTOR4P_14	          	          	                    
          	               	1         	268B2     	SW_PVCCIN_CPU0_SW3  
          	               	2         	268B2     	IND_P0_CPL3         
          	               	3         	268B2     	IND_P0_CPL4         
          	               	4         	268B2     	PVCCIN_CPU0         

PL113     	Q_INDUCTOR_SMLF	          	          	                    
          	               	1         	290A3     	SW_PVCCFA_EHV_FIVRA_CPU1_SW4
          	               	2         	290A2     	PVCCFA_EHV_FIVRA_CPU1

PL114     	Q_INDUCTOR4P_14	          	          	                    
          	               	1         	267B3     	SW_PVCCIN_CPU0_SW1  
          	               	2         	267B3     	IND_P0_CPL1         
          	               	3         	267B2     	IND_P0_CPL2         
          	               	4         	267B2     	PVCCIN_CPU0         

PL118     	Q_INDUCTOR_SMLF	          	          	                    
          	               	1         	281B2     	SW_PVPP_HBM_CPU0_SW 
          	               	2         	281B2     	PVPP_HBM_CPU0       

PL119     	Q_INDUCTOR_SMLF	          	          	                    
          	               	1         	299B2     	SW_PVPP_HBM_CPU1_SW 
          	               	2         	299B2     	PVPP_HBM_CPU1       

PL120     	Q_INDUCTOR_SMLF	          	          	                    
          	               	1         	282B2     	SW_PVNN_MAIN_CPU0_SW
          	               	2         	282B2     	PVNN_MAIN_CPU0      

PL121     	Q_INDUCTOR_SMLF	          	          	                    
          	               	1         	300B2     	SW_PVNN_MAIN_CPU1_SW
          	               	2         	300B2     	PVNN_MAIN_CPU1      

PL150     	Q_INDUCTOR_SMLF	          	          	                    
          	               	1         	262B2     	SW_P1V05_PCH_AUX_SW 
          	               	2         	262B2     	P1V05_PCH_AUX       

PL170     	Q_INDUCTOR_SMLF	          	          	                    
          	               	1         	263B2     	SW_P1V8_PCH_AUX_SW  
          	               	2         	263B2     	P1V8_PCH_AUX        

PL210     	Q_INDUCTOR_SMLF	          	          	                    
          	               	1         	272A2     	SW_PVCCFA_EHV_FIVRA_CPU0_SW4
          	               	2         	272A2     	PVCCFA_EHV_FIVRA_CPU0

PPQ1      	MOSFET_NCH_1D3S	          	          	                    
          	               	1         	304B2     	P12V_AUX            
          	               	2         	304B2     	P12V_AUX            
          	               	3         	304B2     	P12V_AUX            
          	               	4         	304B2     	P12V_HSC_GATE_G5    
          	               	5         	304B2     	P12V_MAIN_R         

PPQ2      	MOSFET_NCH_1D3S	          	          	                    
          	               	1         	304B2     	P12V_AUX            
          	               	2         	304B2     	P12V_AUX            
          	               	3         	304B2     	P12V_AUX            
          	               	4         	304B2     	P12V_HSC_GATE_G6    
          	               	5         	304B2     	P12V_MAIN_R         

PPQ5      	MOSFET_NCH_1D3S	          	          	                    
          	               	1         	304B4     	P12V_AUX            
          	               	2         	304B4     	P12V_AUX            
          	               	3         	304B4     	P12V_AUX            
          	               	4         	304B4     	P12V_HSC_GATE_G1    
          	               	5         	304B4     	P12V_MAIN_R         

PPQ6      	MOSFET_NCH_1D3S	          	          	                    
          	               	1         	304B3     	P12V_AUX            
          	               	2         	304B3     	P12V_AUX            
          	               	3         	304B3     	P12V_AUX            
          	               	4         	304B3     	P12V_HSC_GATE_G2    
          	               	5         	304B3     	P12V_MAIN_R         

PPQ7      	MOSFET_NCH_1D3S	          	          	                    
          	               	1         	304B3     	P12V_AUX            
          	               	2         	304B3     	P12V_AUX            
          	               	3         	304B3     	P12V_AUX            
          	               	4         	304B3     	P12V_HSC_GATE_G3    
          	               	5         	304B3     	P12V_MAIN_R         

PPQ8      	MOSFET_NCH_1D3S	          	          	                    
          	               	1         	304B2     	P12V_AUX            
          	               	2         	304B2     	P12V_AUX            
          	               	3         	304B3     	P12V_AUX            
          	               	4         	304B3     	P12V_HSC_GATE_G4    
          	               	5         	304B2     	P12V_MAIN_R         

PPQ9      	MOSFET_NCH_1D3S	          	          	                    
          	               	1         	304B1     	P12V_AUX            
          	               	2         	304B1     	P12V_AUX            
          	               	3         	304B1     	P12V_AUX            
          	               	4         	304B1     	MB0_CM_GATE_G0      
          	               	5         	304B1     	P12V_MAIN_R_0       

PR1       	Q_RES_0402LF   	          	          	                    
          	               	1         	282A3     	GND                 
          	               	2         	282A2     	GND                 

PR2       	Q_RES_0402LF   	          	          	                    
          	               	1         	300A2     	GND                 
          	               	2         	300A2     	GND                 

PR3       	Q_RES_4P_12    	          	          	                    
          	               	1         	304B2     	P12V_PSU            
          	               	2         	304B2     	P12V_MAIN_R_0       
          	               	3         	304B2     	P12V_HSC_SENSE1_P   
          	               	4         	304B2     	P12V_HSC_SENSE1_N   

PR4       	Q_SP_RES4P     	          	          	                    
          	               	1A        	304B3     	P12V_PSU            
          	               	1B        	304B3     	P12V_HSC_SENSE2_R1_P
          	               	2A        	304B2     	P12V_MAIN_R         
          	               	2B        	304B2     	P12V_HSC_SENSE2_R1_N

PR50      	Q_RES_0402LF   	          	          	                    
          	               	1         	282A2     	PVNN_MAIN_CPU0_FB   
          	               	2         	282A2     	GND                 

PR51      	Q_RES_0402LF   	          	          	                    
          	               	1         	300A2     	PVNN_MAIN_CPU1_FB   
          	               	2         	300A2     	GND                 

PR73      	Q_RES_0402LF   	          	          	                    
          	               	1         	259B2     	P3V3_AUX            
          	               	2         	259B2     	PWRGD_P3V3_AUX      

PR89      	Q_RES_0402LF   	          	          	                    
          	               	1         	258A4     	P5V_AUX_CS          
          	               	2         	258A4     	GND                 

PR91      	Q_RES_0402LF   	          	          	                    
          	               	1         	258B3     	P5V_AUX_FB          
          	               	2         	258A3     	GND                 

PR92      	Q_RES_0402LF   	          	          	                    
          	               	1         	258A2     	P5V_AUX_FB          
          	               	2         	258A2     	P5V_AUX             

PR97      	Q_RES_0402LF   	          	          	                    
          	               	1         	276B4     	PVCCFA_EHV_CPU0_PVCC
          	               	2         	276B4     	PVCCFA_EHV_CPU0_VDD1

PR101     	Q_RES_0402LF   	          	          	                    
          	               	1         	275B4     	PVCCFA_EHV_CPU0_PVCC
          	               	2         	275B4     	PVCCINFAON_CPU0_VDD1

PR102     	Q_RES_0402LF   	          	          	                    
          	               	1         	275A4     	PVCCFA_EHV_CPU0_PVCC
          	               	2         	275A4     	PVCCINFAON_CPU0_VDD2

PR105     	Q_RES_0402LF   	          	          	                    
          	               	1         	274A4     	PVCCINFAON_CPU0_VREF
          	               	2         	274A4     	PVCCINFAON_CPU0_ADDR

PR106     	Q_RES_0402LF   	          	          	                    
          	               	1         	274A4     	PVCCINFAON_CPU0_ADDR
          	               	2         	274A4     	GND                 

PR107     	Q_RES_0402LF   	          	          	                    
          	               	1         	274A4     	P12V_AUX            
          	               	2         	274A4     	PVCCINFAON_CPU0_CSPIN

PR108     	Q_RES_0402LF   	          	          	                    
          	               	1         	274A4     	P12V_AUX            
          	               	2         	274A4     	PVCCINFAON_CPU0_VIN_CSNIN

PR120     	Q_RES_0402LF   	          	          	                    
          	               	1         	274B4     	SH_PVCCINFAON_CPU0  
          	               	2         	274B4     	SH_PVCCINFAON_CPU0_R

PR121     	Q_RES_0402LF   	          	          	                    
          	               	1         	274B4     	SH_PVCCFA_EHV_CPU0  
          	               	2         	274B4     	SH_PVCCFA_EHV_CPU0_R

PR123     	Q_RES_0402LF   	          	          	                    
          	               	1         	274A3     	PVCCINFAON_CPU0_VIN_CSNIN
          	               	2         	274A3     	GND                 

PR130     	Q_RES_0402LF   	          	          	                    
          	               	1         	274B2     	PVCCINFAON_CPU0_VCC 
          	               	2         	274B2     	P3V3_AUX            

PR132     	Q_RES_0402LF   	          	          	                    
          	               	1         	270A4     	PVCCIN_CPU0_LSET8   
          	               	2         	270A4     	GND                 

PR133     	Q_RES_0402LF   	          	          	                    
          	               	1         	270B4     	PVCCIN_CPU0_LSET7   
          	               	2         	270B4     	GND                 

PR134     	Q_RES_0402LF   	          	          	                    
          	               	1         	270B4     	PVCCIN_CPU0_PVCC    
          	               	2         	270B4     	PVCCIN_CPU0_VDD8    

PR135     	Q_RES_0402LF   	          	          	                    
          	               	1         	270B4     	PVCCIN_CPU0_PVCC    
          	               	2         	270B4     	PVCCIN_CPU0_VDD7    

PR136     	Q_RES_0402LF   	          	          	                    
          	               	1         	270A2     	PVCCIN_CPU0_VOS8    
          	               	2         	270A2     	PVCCIN_CPU0         

PR137     	Q_RES_0402LF   	          	          	                    
          	               	1         	270B2     	PVCCIN_CPU0_VOS7    
          	               	2         	270B2     	PVCCIN_CPU0         

PR138     	Q_RES_0402LF   	          	          	                    
          	               	1         	269A4     	PVCCIN_CPU0_LSET6   
          	               	2         	269A4     	GND                 

PR139     	Q_RES_0402LF   	          	          	                    
          	               	1         	269B4     	PVCCIN_CPU0_LSET5   
          	               	2         	269B4     	GND                 

PR140     	Q_RES_0402LF   	          	          	                    
          	               	1         	269B4     	PVCCIN_CPU0_PVCC    
          	               	2         	269A4     	PVCCIN_CPU0_VDD6    

PR141     	Q_RES_0402LF   	          	          	                    
          	               	1         	269B4     	PVCCIN_CPU0_PVCC    
          	               	2         	269B4     	PVCCIN_CPU0_VDD5    

PR142     	Q_RES_0402LF   	          	          	                    
          	               	1         	269A2     	PVCCIN_CPU0_VOS6    
          	               	2         	269A2     	PVCCIN_CPU0         

PR143     	Q_RES_0402LF   	          	          	                    
          	               	1         	269B2     	PVCCIN_CPU0_VOS5    
          	               	2         	269B2     	PVCCIN_CPU0         

PR144     	Q_RES_0402LF   	          	          	                    
          	               	1         	268A4     	PVCCIN_CPU0_LSET4   
          	               	2         	268A4     	GND                 

PR145     	Q_RES_0402LF   	          	          	                    
          	               	1         	268B4     	PVCCIN_CPU0_LSET3   
          	               	2         	268B4     	GND                 

PR146     	Q_RES_0402LF   	          	          	                    
          	               	1         	268B4     	PVCCIN_CPU0_PVCC    
          	               	2         	268B4     	PVCCIN_CPU0_VDD4    

PR147     	Q_RES_0402LF   	          	          	                    
          	               	1         	268B4     	PVCCIN_CPU0_PVCC    
          	               	2         	268B4     	PVCCIN_CPU0_VDD3    

PR148     	Q_RES_0402LF   	          	          	                    
          	               	1         	268A2     	PVCCIN_CPU0_VOS4    
          	               	2         	268A2     	PVCCIN_CPU0         

PR149     	Q_RES_0402LF   	          	          	                    
          	               	1         	268B2     	PVCCIN_CPU0_VOS3    
          	               	2         	268B2     	PVCCIN_CPU0         

PR150     	Q_RES_0402LF   	          	          	                    
          	               	1         	267A4     	PVCCIN_CPU0_LSET2   
          	               	2         	267A4     	GND                 

PR151     	Q_RES_0402LF   	          	          	                    
          	               	1         	267B4     	PVCCIN_CPU0_LSET1   
          	               	2         	267B4     	GND                 

PR152     	Q_RES_0402LF   	          	          	                    
          	               	1         	267B4     	PVCCIN_CPU0_PVCC    
          	               	2         	267A4     	PVCCIN_CPU0_VDD2    

PR153     	Q_RES_0402LF   	          	          	                    
          	               	1         	267B4     	PVCCIN_CPU0_PVCC    
          	               	2         	267B4     	PVCCIN_CPU0_VDD1    

PR154     	Q_RES_0402LF   	          	          	                    
          	               	1         	267A3     	PVCCIN_CPU0_VOS2    
          	               	2         	267A3     	PVCCIN_CPU0         

PR155     	Q_RES_0402LF   	          	          	                    
          	               	1         	267B3     	PVCCIN_CPU0_VOS1    
          	               	2         	267B3     	PVCCIN_CPU0         

PR156     	Q_RES_0402LF   	          	          	                    
          	               	1         	266A4     	P12V_AUX            
          	               	2         	266A4     	PVCCIN_CPU0_VIN_CSNIN

PR157     	Q_RES_0402LF   	          	          	                    
          	               	1         	266A4     	P12V_AUX            
          	               	2         	266A4     	PVCCIN_CPU0_CSPIN   

PR158     	Q_RES_0402LF   	          	          	                    
          	               	1         	266A4     	PVCCIN_CPU0_CSPIN   
          	               	2         	266A4     	GND                 

PR159     	Q_RES_0402LF   	          	          	                    
          	               	1         	266A4     	PVCCIN_CPU0_VREF    
          	               	2         	266A4     	PVCCIN_CPU0_ADDR    

PR166     	Q_RES_0402LF   	          	          	                    
          	               	1         	266A3     	PVCCIN_CPU0_VIN_CSNIN
          	               	2         	266A3     	GND                 

PR170     	Q_RES_0402LF   	          	          	                    
          	               	1         	266B4     	SH_PVCCIN_CPU0      
          	               	2         	266B4     	SH_PVCCIN_CPU0_R    

PR171     	Q_RES_0402LF   	          	          	                    
          	               	1         	266A4     	PVCCIN_CPU0_ADDR    
          	               	2         	266A4     	GND                 

PR176     	Q_RES_0402LF   	          	          	                    
          	               	1         	266B2     	PVCCIN_CPU0_VCC     
          	               	2         	266B2     	P3V3_AUX            

PR187     	Q_RES_0402LF   	          	          	                    
          	               	1         	262A2     	P1V05_PCH_AUX_FB    
          	               	2         	262A2     	SH_P1V05_PCH_AUX_N  

PR200     	Q_RES_0402LF   	          	          	                    
          	               	1         	297B4     	PVCCFA_EHV_CPU1_PVCC
          	               	2         	297B4     	PVCCD_HV_CPU1_VDD1  

PR202     	Q_RES_0402LF   	          	          	                    
          	               	1         	296A4     	PVCCD_HV_CPU1_VREF  
          	               	2         	296A4     	PVCCD_HV_CPU1_ADDR  

PR203     	Q_RES_0402LF   	          	          	                    
          	               	1         	296A4     	GND                 
          	               	2         	296A4     	PVCCD_HV_CPU1_ADDR  

PR214     	Q_RES_0402LF   	          	          	                    
          	               	1         	296A4     	PVCCD_HV_CPU1_ISENSE_P
          	               	2         	296A4     	GND                 

PR215     	Q_RES_0402LF   	          	          	                    
          	               	1         	296B4     	P3V3_AUX            
          	               	2         	296A4     	PVCCD_HV_CPU1_PIN_ALT

PR216     	Q_RES_0402LF   	          	          	                    
          	               	1         	296B4     	SH_PVCCD_HV_CPU1    
          	               	2         	296B4     	SH_PVCCD_HV_CPU1_R  

PR217     	Q_RES_0402LF   	          	          	                    
          	               	1         	296B4     	P3V3_AUX            
          	               	2         	296A4     	PVCCD_HV_CPU1_FAULT 

PR218     	Q_RES_0402LF   	          	          	                    
          	               	1         	296A3     	PVCCD_HV_CPU1_ISENSE_N
          	               	2         	296A3     	GND                 

PR220     	Q_RES_0402LF   	          	          	                    
          	               	1         	296B2     	PVCCD_HV_CPU1_VCC   
          	               	2         	296B2     	P3V3_AUX            

PR224     	Q_RES_0402LF   	          	          	                    
          	               	1         	289A4     	PVCCFA_EHV_FIVRA_CPU1_LSET2
          	               	2         	289A4     	GND                 

PR225     	Q_RES_0402LF   	          	          	                    
          	               	1         	289B4     	PVCCFA_EHV_FIVRA_CPU1_LSET1
          	               	2         	289B4     	GND                 

PR226     	Q_RES_0402LF   	          	          	                    
          	               	1         	289B4     	PVCCFA_EHV_FIVRA_CPU1_PVCC1
          	               	2         	289B4     	PVCCFA_EHV_FIVRA_CPU1_VDD1

PR227     	Q_RES_0402LF   	          	          	                    
          	               	1         	289A4     	PVCCFA_EHV_FIVRA_CPU1_PVCC2
          	               	2         	289A4     	PVCCFA_EHV_FIVRA_CPU1_VDD2

PR242     	Q_RES_0402LF   	          	          	                    
          	               	1         	284B4     	SH_PVCCFA_EHV_FIVRA_CPU1
          	               	2         	284B4     	SH_PVCCFA_EHV_FIVRA_CPU1_R

PR250     	Q_RES_0402LF   	          	          	                    
          	               	1         	294B4     	PVCCFA_EHV_CPU1_PVCC
          	               	2         	294B4     	PVCCFA_EHV_CPU1_VDD1

PR254     	Q_RES_0402LF   	          	          	                    
          	               	1         	293B4     	PVCCFA_EHV_CPU1_PVCC
          	               	2         	293B4     	PVCCINFAON_CPU1_VDD1

PR255     	Q_RES_0402LF   	          	          	                    
          	               	1         	293A4     	PVCCFA_EHV_CPU1_PVCC
          	               	2         	293A4     	PVCCINFAON_CPU1_VDD2

PR258     	Q_RES_0402LF   	          	          	                    
          	               	1         	292A4     	PVCCINFAON_CPU1_VREF
          	               	2         	292A4     	PVCCINFAON_CPU1_ADDR

PR259     	Q_RES_0402LF   	          	          	                    
          	               	1         	292A4     	PVCCINFAON_CPU1_ADDR
          	               	2         	292A4     	GND                 

PR260     	Q_RES_0402LF   	          	          	                    
          	               	1         	292A4     	P12V_AUX            
          	               	2         	292A4     	PVCCINFAON_CPU1_CSPIN

PR261     	Q_RES_0402LF   	          	          	                    
          	               	1         	292A4     	P12V_AUX            
          	               	2         	292A4     	PVCCINFAON_CPU1_VIN_CSNIN

PR273     	Q_RES_0402LF   	          	          	                    
          	               	1         	292B4     	SH_PVCCINFAON_CPU1  
          	               	2         	292B4     	SH_PVCCINFAON_CPU1_R

PR274     	Q_RES_0402LF   	          	          	                    
          	               	1         	292B4     	SH_PVCCFA_EHV_CPU1  
          	               	2         	292B4     	SH_PVCCFA_EHV_CPU1_R

PR275     	Q_RES_0402LF   	          	          	                    
          	               	1         	292A4     	PVCCINFAON_CPU1_CSPIN
          	               	2         	292A4     	GND                 

PR276     	Q_RES_0402LF   	          	          	                    
          	               	1         	292A3     	PVCCINFAON_CPU1_VIN_CSNIN
          	               	2         	292A3     	GND                 

PR283     	Q_RES_0402LF   	          	          	                    
          	               	1         	292B2     	PVCCINFAON_CPU1_VCC 
          	               	2         	292B2     	P3V3_AUX            

PR285     	Q_RES_0402LF   	          	          	                    
          	               	1         	288A4     	PVCCIN_CPU1_LSET8   
          	               	2         	288A4     	GND                 

PR286     	Q_RES_0402LF   	          	          	                    
          	               	1         	288B4     	PVCCIN_CPU1_LSET7   
          	               	2         	288B4     	GND                 

PR287     	Q_RES_0402LF   	          	          	                    
          	               	1         	288B4     	PVCCIN_CPU1_PVCC    
          	               	2         	288A4     	PVCCIN_CPU1_VDD8    

PR288     	Q_RES_0402LF   	          	          	                    
          	               	1         	288B4     	PVCCIN_CPU1_PVCC    
          	               	2         	288B4     	PVCCIN_CPU1_VDD7    

PR289     	Q_RES_0402LF   	          	          	                    
          	               	1         	288A2     	PVCCIN_CPU1_VOS8    
          	               	2         	288A2     	PVCCIN_CPU1         

PR290     	Q_RES_0402LF   	          	          	                    
          	               	1         	288B2     	PVCCIN_CPU1_VOS7    
          	               	2         	288B2     	PVCCIN_CPU1         

PR291     	Q_RES_0402LF   	          	          	                    
          	               	1         	287A4     	PVCCIN_CPU1_LSET6   
          	               	2         	287A4     	GND                 

PR292     	Q_RES_0402LF   	          	          	                    
          	               	1         	287B4     	PVCCIN_CPU1_LSET5   
          	               	2         	287B4     	GND                 

PR293     	Q_RES_0402LF   	          	          	                    
          	               	1         	287B4     	PVCCIN_CPU1_PVCC    
          	               	2         	287A4     	PVCCIN_CPU1_VDD6    

PR294     	Q_RES_0402LF   	          	          	                    
          	               	1         	287B4     	PVCCIN_CPU1_PVCC    
          	               	2         	287B4     	PVCCIN_CPU1_VDD5    

PR295     	Q_RES_0402LF   	          	          	                    
          	               	1         	287A2     	PVCCIN_CPU1_VOS6    
          	               	2         	287A2     	PVCCIN_CPU1         

PR296     	Q_RES_0402LF   	          	          	                    
          	               	1         	287B2     	PVCCIN_CPU1_VOS5    
          	               	2         	287B2     	PVCCIN_CPU1         

PR297     	Q_RES_0402LF   	          	          	                    
          	               	1         	286A4     	PVCCIN_CPU1_LSET4   
          	               	2         	286A4     	GND                 

PR298     	Q_RES_0402LF   	          	          	                    
          	               	1         	286B4     	PVCCIN_CPU1_LSET3   
          	               	2         	286B4     	GND                 

PR299     	Q_RES_0402LF   	          	          	                    
          	               	1         	286B4     	PVCCIN_CPU1_PVCC    
          	               	2         	286B4     	PVCCIN_CPU1_VDD4    

PR300     	Q_RES_0402LF   	          	          	                    
          	               	1         	286B4     	PVCCIN_CPU1_PVCC    
          	               	2         	286B4     	PVCCIN_CPU1_VDD3    

PR301     	Q_RES_0402LF   	          	          	                    
          	               	1         	286A2     	PVCCIN_CPU1_VOS4    
          	               	2         	286A2     	PVCCIN_CPU1         

PR302     	Q_RES_0402LF   	          	          	                    
          	               	1         	286B2     	PVCCIN_CPU1_VOS3    
          	               	2         	286B2     	PVCCIN_CPU1         

PR303     	Q_RES_0402LF   	          	          	                    
          	               	1         	284A4     	P12V_AUX            
          	               	2         	284A4     	PVCCIN_CPU1_VIN_CSNIN

PR304     	Q_RES_0402LF   	          	          	                    
          	               	1         	284A4     	P12V_AUX            
          	               	2         	284A4     	PVCCIN_CPU1_CSPIN   

PR305     	Q_RES_0402LF   	          	          	                    
          	               	1         	284A4     	PVCCIN_CPU1_CSPIN   
          	               	2         	284A4     	GND                 

PR306     	Q_RES_0402LF   	          	          	                    
          	               	1         	284A4     	PVCCIN_CPU1_VREF    
          	               	2         	284A4     	PVCCIN_CPU1_ADDR    

PR313     	Q_RES_0402LF   	          	          	                    
          	               	1         	284A3     	PVCCIN_CPU1_VIN_CSNIN
          	               	2         	284A3     	GND                 

PR317     	Q_RES_0402LF   	          	          	                    
          	               	1         	284B4     	SH_PVCCIN_CPU1      
          	               	2         	284B4     	SH_PVCCIN_CPU1_R    

PR318     	Q_RES_0402LF   	          	          	                    
          	               	1         	284A4     	PVCCIN_CPU1_ADDR    
          	               	2         	284A4     	GND                 

PR323     	Q_RES_0402LF   	          	          	                    
          	               	1         	284B2     	PVCCIN_CPU1_VCC     
          	               	2         	284B2     	P3V3_AUX            

PR325     	Q_RES_0402LF   	          	          	                    
          	               	1         	285A4     	PVCCIN_CPU1_LSET2   
          	               	2         	285A4     	GND                 

PR326     	Q_RES_0402LF   	          	          	                    
          	               	1         	285B4     	PVCCIN_CPU1_LSET1   
          	               	2         	285B4     	GND                 

PR327     	Q_RES_0402LF   	          	          	                    
          	               	1         	285B4     	PVCCIN_CPU1_PVCC    
          	               	2         	285A4     	PVCCIN_CPU1_VDD2    

PR328     	Q_RES_0402LF   	          	          	                    
          	               	1         	285B4     	PVCCIN_CPU1_PVCC    
          	               	2         	285B4     	PVCCIN_CPU1_VDD1    

PR329     	Q_RES_0402LF   	          	          	                    
          	               	1         	285A3     	PVCCIN_CPU1_VOS2    
          	               	2         	285A3     	PVCCIN_CPU1         

PR330     	Q_RES_0402LF   	          	          	                    
          	               	1         	285B3     	PVCCIN_CPU1_VOS1    
          	               	2         	285B3     	PVCCIN_CPU1         

PR338     	Q_RES_0402LF   	          	          	                    
          	               	1         	262B3     	P1V05_PCH_AUX_MODE  
          	               	2         	262B3     	GND                 

PR345     	Q_RES_0402LF   	          	          	                    
          	               	1         	266B4     	SH_PVCCFA_EHV_FIVRA_CPU0
          	               	2         	266B4     	SH_PVCCFA_EHV_FIVRA_CPU0_R

PR353     	Q_RES_0402LF   	          	          	                    
          	               	1         	271A4     	PVCCFA_EHV_FIVRA_CPU0_LSET2
          	               	2         	271A4     	GND                 

PR354     	Q_RES_0402LF   	          	          	                    
          	               	1         	271B4     	PVCCFA_EHV_FIVRA_CPU0_LSET1
          	               	2         	271B4     	GND                 

PR355     	Q_RES_0402LF   	          	          	                    
          	               	1         	271B4     	PVCCFA_EHV_FIVRA_CPU0_PVCC1
          	               	2         	271B4     	PVCCFA_EHV_FIVRA_CPU0_VDD1

PR356     	Q_RES_0402LF   	          	          	                    
          	               	1         	271A4     	PVCCFA_EHV_FIVRA_CPU0_PVCC2
          	               	2         	271A4     	PVCCFA_EHV_FIVRA_CPU0_VDD2

PR357     	Q_RES_0402LF   	          	          	                    
          	               	1         	278A4     	PVCCD_HV_CPU0_VREF  
          	               	2         	278A4     	PVCCD_HV_CPU0_ADDR  

PR358     	Q_RES_0402LF   	          	          	                    
          	               	1         	278A4     	GND                 
          	               	2         	278A4     	PVCCD_HV_CPU0_ADDR  

PR369     	Q_RES_0402LF   	          	          	                    
          	               	1         	278A4     	PVCCD_HV_CPU0_ISENSE_P
          	               	2         	278A4     	GND                 

PR370     	Q_RES_0402LF   	          	          	                    
          	               	1         	278B4     	P3V3_AUX            
          	               	2         	278A4     	PVCCD_HV_CPU0_PIN_ALT

PR371     	Q_RES_0402LF   	          	          	                    
          	               	1         	278B4     	SH_PVCCD_HV_CPU0    
          	               	2         	278B4     	SH_PVCCD_HV_CPU0_R  

PR372     	Q_RES_0402LF   	          	          	                    
          	               	1         	278B4     	P3V3_AUX            
          	               	2         	278A4     	PVCCD_HV_CPU0_FAULT 

PR373     	Q_RES_0402LF   	          	          	                    
          	               	1         	278A3     	PVCCD_HV_CPU0_ISENSE_N
          	               	2         	278A3     	GND                 

PR375     	Q_RES_0402LF   	          	          	                    
          	               	1         	278B2     	PVCCD_HV_CPU0_VCC   
          	               	2         	278B2     	P3V3_AUX            

PR380     	Q_RES_0402LF   	          	          	                    
          	               	1         	279B4     	PVCCFA_EHV_CPU0_PVCC
          	               	2         	279B4     	PVCCD_HV_CPU0_VDD1  

PR389     	Q_RES_0402LF   	          	          	                    
          	               	1         	259B4     	P3V3_AUX_VDRV       
          	               	2         	259B4     	P3V3_AUX_VCC        

PR395     	Q_RES_0402LF   	          	          	                    
          	               	1         	263A4     	P3V3_AUX            
          	               	2         	263A4     	PVCC1_AUX           

PR396     	Q_RES_0402LF   	          	          	                    
          	               	1         	263A4     	P5V_AUX             
          	               	2         	263A4     	PVCC1_AUX           

PR400     	Q_RES_0402LF   	          	          	                    
          	               	1         	266A2     	PVCCIN_CPU0_ATSEN   
          	               	2         	266A2     	GND                 

PR402     	Q_RES_0402LF   	          	          	                    
          	               	1         	267B4     	P5V                 
          	               	2         	267B4     	PVCCIN_CPU0_PVCC    

PR403     	Q_RES_0402LF   	          	          	                    
          	               	1         	267B4     	P3V3                
          	               	2         	267B4     	PVCCIN_CPU0_PVCC    

PR409     	Q_RES_0402LF   	          	          	                    
          	               	1         	278A1     	PVCCD_HV_CPU0_ISYS_R
          	               	2         	278A1     	PVCCD_HV_CPU0_NVDIMM_ISENSE

PR410     	Q_RES_0402LF   	          	          	                    
          	               	1         	296A2     	PVCCD_HV_CPU1_ISYS_R
          	               	2         	296A1     	PVCCD_HV_CPU1_NVDIMM_ISENSE

PR435     	Q_RES_0402LF   	          	          	                    
          	               	1         	274A2     	PVCCINFAON_CPU0_ATSEN
          	               	2         	274A2     	GND                 

PR436     	Q_RES_0402LF   	          	          	                    
          	               	1         	274A1     	PVCCFA_EHV_CPU0_BTSEN
          	               	2         	274A1     	GND                 

PR442     	Q_RES_0402LF   	          	          	                    
          	               	1         	276B4     	P5V                 
          	               	2         	276B4     	PVCCFA_EHV_CPU0_PVCC

PR443     	Q_RES_0402LF   	          	          	                    
          	               	1         	276B4     	P3V3                
          	               	2         	276B4     	PVCCFA_EHV_CPU0_PVCC

PR444     	Q_RES_0402LF   	          	          	                    
          	               	1         	271B4     	P5V                 
          	               	2         	271B4     	PVCCFA_EHV_FIVRA_CPU0_PVCC1

PR447     	Q_RES_0402LF   	          	          	                    
          	               	1         	271B4     	P5V                 
          	               	2         	271B4     	PVCCFA_EHV_FIVRA_CPU0_PVCC2

PR451     	Q_RES_0402LF   	          	          	                    
          	               	1         	266A1     	PVCCFA_EHV_FIVRA_CPU0_BTSEN
          	               	2         	266A1     	GND                 

PR453     	Q_RES_0402LF   	          	          	                    
          	               	1         	284A1     	PVCCFA_EHV_FIVRA_CPU1_BTSEN
          	               	2         	284A1     	GND                 

PR501     	Q_RES_0402LF   	          	          	                    
          	               	1         	282A2     	PVNN_MAIN_CPU0_FB   
          	               	2         	282A2     	PVNN_MAIN_CPU0_FB_RC

PR502     	Q_RES_0402LF   	          	          	                    
          	               	1         	300A2     	PVNN_MAIN_CPU1_FB   
          	               	2         	300A2     	PVNN_MAIN_CPU1_FB_RC

PR519     	Q_RES_0402LF   	          	          	                    
          	               	1         	274B4     	VSENSE_PVCCINFAON_CPU0_DN
          	               	2         	274B4     	GND                 

PR520     	Q_RES_0402LF   	          	          	                    
          	               	1         	274B4     	VSENSE_PVCCFA_EHV_CPU0_DN
          	               	2         	274B4     	GND                 

PR521     	Q_RES_0402LF   	          	          	                    
          	               	1         	274B4     	VSENSE_PVCCINFAON_CPU0_DP
          	               	2         	274B4     	PVCCINFAON_CPU0     

PR522     	Q_RES_0402LF   	          	          	                    
          	               	1         	274B4     	VSENSE_PVCCFA_EHV_CPU0_DP
          	               	2         	274B4     	PVCCFA_EHV_CPU0     

PR527     	Q_RES_0402LF   	          	          	                    
          	               	1         	266B4     	VSENSE_PVCCIN_CPU0_DN
          	               	2         	266B4     	GND                 

PR531     	Q_RES_0402LF   	          	          	                    
          	               	1         	266B4     	VSENSE_PVCCIN_CPU0_DP
          	               	2         	266B4     	PVCCIN_CPU0         

PR558     	Q_RES_0402LF   	          	          	                    
          	               	1         	296B4     	VSENSE_PVCCD_HV_CPU1_DN
          	               	2         	296B4     	GND                 

PR559     	Q_RES_0402LF   	          	          	                    
          	               	1         	296B4     	VSENSE_PVCCD_HV_CPU1_DP
          	               	2         	296B4     	PVCCD_HV_CPU1       

PR560     	Q_RES_0402LF   	          	          	                    
          	               	1         	284B4     	VSENSE_PVCCFA_EHV_FIVRA_CPU1_DN
          	               	2         	284B4     	GND                 

PR561     	Q_RES_0402LF   	          	          	                    
          	               	1         	284B4     	VSENSE_PVCCFA_EHV_FIVRA_CPU1_DP
          	               	2         	284B4     	PVCCFA_EHV_FIVRA_CPU1

PR566     	Q_RES_0402LF   	          	          	                    
          	               	1         	292B4     	VSENSE_PVCCINFAON_CPU1_DN
          	               	2         	292B4     	GND                 

PR567     	Q_RES_0402LF   	          	          	                    
          	               	1         	292B4     	VSENSE_PVCCFA_EHV_CPU1_DN
          	               	2         	292B4     	GND                 

PR568     	Q_RES_0402LF   	          	          	                    
          	               	1         	292B4     	VSENSE_PVCCINFAON_CPU1_DP
          	               	2         	292B4     	PVCCINFAON_CPU1     

PR569     	Q_RES_0402LF   	          	          	                    
          	               	1         	292B4     	VSENSE_PVCCFA_EHV_CPU1_DP
          	               	2         	292B4     	PVCCFA_EHV_CPU1     

PR574     	Q_RES_0402LF   	          	          	                    
          	               	1         	284B4     	VSENSE_PVCCIN_CPU1_DN
          	               	2         	284B4     	GND                 

PR578     	Q_RES_0402LF   	          	          	                    
          	               	1         	284B4     	VSENSE_PVCCIN_CPU1_DP
          	               	2         	284B4     	PVCCIN_CPU1         

PR586     	Q_RES_0402LF   	          	          	                    
          	               	1         	266B4     	VSENSE_PVCCFA_EHV_FIVRA_CPU0_DN
          	               	2         	266B4     	GND                 

PR587     	Q_RES_0402LF   	          	          	                    
          	               	1         	266B4     	VSENSE_PVCCFA_EHV_FIVRA_CPU0_DP
          	               	2         	266B4     	PVCCFA_EHV_FIVRA_CPU0

PR591     	Q_RES_0402LF   	          	          	                    
          	               	1         	278B4     	VSENSE_PVCCD_HV_CPU0_DN
          	               	2         	278B4     	GND                 

PR592     	Q_RES_0402LF   	          	          	                    
          	               	1         	278B4     	VSENSE_PVCCD_HV_CPU0_DP
          	               	2         	278B4     	PVCCD_HV_CPU0       

PR632     	Q_RES_0402LF   	          	          	                    
          	               	1         	271B4     	P3V3                
          	               	2         	271B4     	PVCCFA_EHV_FIVRA_CPU0_PVCC1

PR633     	Q_RES_0402LF   	          	          	                    
          	               	1         	271B4     	P3V3                
          	               	2         	271B4     	PVCCFA_EHV_FIVRA_CPU0_PVCC2

PR634     	Q_RES_0402LF   	          	          	                    
          	               	1         	278A2     	PVCCD_HV_CPU0_ATSEN 
          	               	2         	278A2     	GND                 

PR637     	Q_RES_0402LF   	          	          	                    
          	               	1         	284A2     	PVCCIN_CPU1_ATSEN   
          	               	2         	284A2     	GND                 

PR639     	Q_RES_0402LF   	          	          	                    
          	               	1         	285B4     	P5V                 
          	               	2         	285B4     	PVCCIN_CPU1_PVCC    

PR640     	Q_RES_0402LF   	          	          	                    
          	               	1         	285B4     	P3V3                
          	               	2         	285B4     	PVCCIN_CPU1_PVCC    

PR665     	Q_RES_0402LF   	          	          	                    
          	               	1         	292A2     	PVCCINFAON_CPU1_ATSEN
          	               	2         	292A2     	GND                 

PR667     	Q_RES_0402LF   	          	          	                    
          	               	1         	292A1     	PVCCFA_EHV_CPU1_BTSEN
          	               	2         	292A1     	GND                 

PR678     	Q_RES_0402LF   	          	          	                    
          	               	1         	294B4     	P5V                 
          	               	2         	294B4     	PVCCFA_EHV_CPU1_PVCC

PR699     	Q_RES_0402LF   	          	          	                    
          	               	1         	294B4     	P3V3                
          	               	2         	294B4     	PVCCFA_EHV_CPU1_PVCC

PR701     	Q_RES_0402LF   	          	          	                    
          	               	1         	289B4     	P5V                 
          	               	2         	289B4     	PVCCFA_EHV_FIVRA_CPU1_PVCC1

PR702     	Q_RES_0402LF   	          	          	                    
          	               	1         	289B4     	P5V                 
          	               	2         	289B4     	PVCCFA_EHV_FIVRA_CPU1_PVCC2

PR703     	Q_RES_0402LF   	          	          	                    
          	               	1         	289B4     	P3V3                
          	               	2         	289B4     	PVCCFA_EHV_FIVRA_CPU1_PVCC1

PR704     	Q_RES_0402LF   	          	          	                    
          	               	1         	289B4     	P3V3                
          	               	2         	289B4     	PVCCFA_EHV_FIVRA_CPU1_PVCC2

PR705     	Q_RES_0402LF   	          	          	                    
          	               	1         	296A1     	PVCCD_HV_CPU1_ATSEN 
          	               	2         	296A1     	GND                 

PR830     	Q_RES_0402LF   	          	          	                    
          	               	1         	259A2     	P3V3_AUX_FB         
          	               	2         	259A2     	GND                 

PR831     	Q_RES_0402LF   	          	          	                    
          	               	1         	259A2     	P3V3_AUX_FB         
          	               	2         	259A2     	P3V3_AUX            

PR832     	Q_RES_0402LF   	          	          	                    
          	               	1         	259A4     	P3V3_AUX_MODE       
          	               	2         	259A4     	GND                 

PR833     	Q_RES_0402LF   	          	          	                    
          	               	1         	259A4     	P3V3_AUX_SS         
          	               	2         	259A4     	GND                 

PR834     	Q_RES_0402LF   	          	          	                    
          	               	1         	259A3     	P3V3_AUX_ILIM       
          	               	2         	259A3     	GND                 

PR835     	Q_RES_0402LF   	          	          	                    
          	               	1         	259B2     	SW_P3V3_AUX_BOOT    
          	               	2         	259B2     	SW_P3V3_AUX_BOOT_R  

PR836     	Q_RES_0402LF   	          	          	                    
          	               	1         	259A2     	P3V3_AUX_VOS        
          	               	2         	259A2     	P3V3_AUX            

PR1101    	Q_RES_0402LF   	          	          	                    
          	               	1         	302A3     	HSC_IMON            
          	               	2         	302A3     	AGND_HSC            

PR1131    	Q_RES_0402LF   	          	          	                    
          	               	1         	301B2     	HSC_CS              
          	               	2         	301B2     	AGND_HSC            

PR1133    	Q_RES_0402LF   	          	          	                    
          	               	1         	301B1     	HSC_IMON            
          	               	2         	301B1     	AGND_HSC            

PR1134    	Q_RES_0402LF   	          	          	                    
          	               	1         	302B4     	AGND_HSC            
          	               	2         	302B4     	HSC_MODE_1          

PR1297    	Q_RES_0402LF   	          	          	                    
          	               	1         	272A4     	PVCCFA_EHV_FIVRA_CPU0_LSET4
          	               	2         	272A4     	GND                 

PR1298    	Q_RES_0402LF   	          	          	                    
          	               	1         	272B4     	PVCCFA_EHV_FIVRA_CPU0_LSET3
          	               	2         	272B4     	GND                 

PR1299    	Q_RES_0402LF   	          	          	                    
          	               	1         	272B4     	PVCCFA_EHV_FIVRA_CPU0_PVCC1
          	               	2         	272B4     	PVCCFA_EHV_FIVRA_CPU0_VDD3

PR1300    	Q_RES_0402LF   	          	          	                    
          	               	1         	272B4     	PVCCFA_EHV_FIVRA_CPU0_PVCC2
          	               	2         	272B4     	PVCCFA_EHV_FIVRA_CPU0_VDD4

PR1301    	Q_RES_0402LF   	          	          	                    
          	               	1         	282A4     	PVNN_MAIN_CPU0_MODE 
          	               	2         	282A4     	GND                 

PR1303    	Q_RES_0402LF   	          	          	                    
          	               	1         	282A4     	PVNN_MAIN_CPU0_CS   
          	               	2         	282A4     	GND                 

PR1304    	Q_RES_0402LF   	          	          	                    
          	               	1         	290A4     	PVCCFA_EHV_FIVRA_CPU1_LSET4
          	               	2         	290A4     	GND                 

PR1305    	Q_RES_0402LF   	          	          	                    
          	               	1         	290B4     	PVCCFA_EHV_FIVRA_CPU1_LSET3
          	               	2         	290B4     	GND                 

PR1306    	Q_RES_0402LF   	          	          	                    
          	               	1         	290B4     	PVCCFA_EHV_FIVRA_CPU1_PVCC1
          	               	2         	290B4     	PVCCFA_EHV_FIVRA_CPU1_VDD3

PR1307    	Q_RES_0402LF   	          	          	                    
          	               	1         	290B4     	PVCCFA_EHV_FIVRA_CPU1_PVCC2
          	               	2         	290B4     	PVCCFA_EHV_FIVRA_CPU1_VDD4

PR1310    	Q_RES_0402LF   	          	          	                    
          	               	1         	281A2     	PVPP_HBM_CPU0_FB    
          	               	2         	281A2     	SH_PVPP_HBM_CPU0_N  

PR1311    	Q_RES_0402LF   	          	          	                    
          	               	1         	278A2     	PVCCD_HV_CPU0_ISYS_R
          	               	2         	278A1     	GND                 

PR1314    	Q_RES_0402LF   	          	          	                    
          	               	1         	299A3     	PVPP_HBM_CPU1_FB    
          	               	2         	299A3     	SH_PVPP_HBM_CPU1_N  

PR1315    	Q_RES_0402LF   	          	          	                    
          	               	1         	296A2     	PVCCD_HV_CPU1_ISYS_R
          	               	2         	296A1     	GND                 

PR1322    	Q_RES_0402LF   	          	          	                    
          	               	1         	271B2     	PVCCFA_EHV_FIVRA_CPU0_VOS1
          	               	2         	271B2     	PVCCFA_EHV_FIVRA_CPU0

PR1323    	Q_RES_0402LF   	          	          	                    
          	               	1         	271A2     	PVCCFA_EHV_FIVRA_CPU0_VOS2
          	               	2         	271A2     	PVCCFA_EHV_FIVRA_CPU0

PR1324    	Q_RES_0402LF   	          	          	                    
          	               	1         	272B2     	PVCCFA_EHV_FIVRA_CPU0_VOS3
          	               	2         	272B2     	PVCCFA_EHV_FIVRA_CPU0

PR1325    	Q_RES_0402LF   	          	          	                    
          	               	1         	272A2     	PVCCFA_EHV_FIVRA_CPU0_VOS4
          	               	2         	272A2     	PVCCFA_EHV_FIVRA_CPU0

PR1326    	Q_RES_0402LF   	          	          	                    
          	               	1         	262A4     	P3V3_AUX            
          	               	2         	262A4     	P1V05_PCH_AUX_VCC   

PR1327    	Q_RES_0402LF   	          	          	                    
          	               	1         	262A4     	P1V05_PCH_AUX_CS    
          	               	2         	262A4     	GND                 

PR1328    	Q_RES_0402LF   	          	          	                    
          	               	1         	262A2     	P1V05_PCH_AUX_FB    
          	               	2         	262A2     	SH_P1V05_PCH_AUX_P  

PR1329    	Q_RES_0402LF   	          	          	                    
          	               	1         	263B4     	PVCC1_AUX           
          	               	2         	263A4     	P1V8_PCH_AUX_VCC    

PR1330    	Q_RES_0402LF   	          	          	                    
          	               	1         	263A4     	P1V8_PCH_AUX_MODE   
          	               	2         	263A4     	GND                 

PR1331    	Q_RES_0402LF   	          	          	                    
          	               	1         	289B2     	PVCCFA_EHV_FIVRA_CPU1_VOS1
          	               	2         	289B2     	PVCCFA_EHV_FIVRA_CPU1

PR1332    	Q_RES_0402LF   	          	          	                    
          	               	1         	289A2     	PVCCFA_EHV_FIVRA_CPU1_VOS2
          	               	2         	289A2     	PVCCFA_EHV_FIVRA_CPU1

PR1333    	Q_RES_0402LF   	          	          	                    
          	               	1         	290B3     	PVCCFA_EHV_FIVRA_CPU1_VOS3
          	               	2         	290B2     	PVCCFA_EHV_FIVRA_CPU1

PR1334    	Q_RES_0402LF   	          	          	                    
          	               	1         	290A3     	PVCCFA_EHV_FIVRA_CPU1_VOS4
          	               	2         	290A2     	PVCCFA_EHV_FIVRA_CPU1

PR1335    	Q_RES_0402LF   	          	          	                    
          	               	1         	281A4     	P3V3_AUX            
          	               	2         	281A4     	PVPP_HBM_CPU0_VCC   

PR1336    	Q_RES_0402LF   	          	          	                    
          	               	1         	281A4     	PVPP_HBM_CPU0_CS    
          	               	2         	281A4     	GND                 

PR1337    	Q_RES_0402LF   	          	          	                    
          	               	1         	281A2     	PVPP_HBM_CPU0_FB    
          	               	2         	281A2     	SH_PVPP_HBM_CPU0_P  

PR1338    	Q_RES_0402LF   	          	          	                    
          	               	1         	299B4     	P3V3_AUX            
          	               	2         	299B4     	PVPP_HBM_CPU1_VCC   

PR1339    	Q_RES_0402LF   	          	          	                    
          	               	1         	299A4     	PVPP_HBM_CPU1_CS    
          	               	2         	299A4     	GND                 

PR1340    	Q_RES_0402LF   	          	          	                    
          	               	1         	299B2     	PVPP_HBM_CPU1_FB    
          	               	2         	299B2     	SH_PVPP_HBM_CPU1_P  

PR1380    	Q_RES_0402LF   	          	          	                    
          	               	1         	278A4     	P12V_AUX_CPU0_DIMM_ISEN_P
          	               	2         	278A4     	PVCCD_HV_CPU0_ISENSE_P

PR1390    	Q_RES_0402LF   	          	          	                    
          	               	1         	278A4     	P12V_AUX_CPU0_DIMM_ISEN_N
          	               	2         	278A4     	PVCCD_HV_CPU0_ISENSE_N

PR1400    	Q_RES_0402LF   	          	          	                    
          	               	1         	296A4     	P12V_AUX_CPU1_DIMM_ISEN_P
          	               	2         	296A4     	PVCCD_HV_CPU1_ISENSE_P

PR1410    	Q_RES_0402LF   	          	          	                    
          	               	1         	296A4     	P12V_AUX_CPU1_DIMM_ISEN_N
          	               	2         	296A4     	PVCCD_HV_CPU1_ISENSE_N

PR1647    	Q_RES_0402LF   	          	          	                    
          	               	1         	262B4     	P3V3_AUX            
          	               	2         	262B4     	FM_P1V05_PCH_AUX_R_EN

PR1649    	Q_RES_0402LF   	          	          	                    
          	               	1         	262B4     	FM_P1V05_PCH_AUX_R_EN
          	               	2         	262B4     	GND                 

PR1653    	Q_RES_0402LF   	          	          	                    
          	               	1         	263B1     	P1V8_PCH_AUX        
          	               	2         	263B1     	GND                 

PR1707    	Q_RES_0402LF   	          	          	                    
          	               	1         	275A4     	PVCCINFAON_CPU0_LSET2
          	               	2         	275A4     	GND                 

PR1708    	Q_RES_0402LF   	          	          	                    
          	               	1         	275B4     	PVCCINFAON_CPU0_LSET1
          	               	2         	275B4     	GND                 

PR1709    	Q_RES_0402LF   	          	          	                    
          	               	1         	276B4     	PVCCFA_EHV_CPU0_LSET1
          	               	2         	276B4     	GND                 

PR1726    	Q_RES_0402LF   	          	          	                    
          	               	1         	293B4     	PVCCINFAON_CPU1_LSET1
          	               	2         	293B4     	GND                 

PR1727    	Q_RES_0402LF   	          	          	                    
          	               	1         	293A4     	PVCCINFAON_CPU1_LSET2
          	               	2         	293A4     	GND                 

PR1728    	Q_RES_0402LF   	          	          	                    
          	               	1         	294B4     	PVCCFA_EHV_CPU1_LSET1
          	               	2         	294A4     	GND                 

PR1746    	Q_RES_0402LF   	          	          	                    
          	               	1         	297B4     	PVCCD_HV_CPU1_LSET1 
          	               	2         	297B4     	GND                 

PR1766    	Q_RES_0402LF   	          	          	                    
          	               	1         	285A3     	SW_PVCCIN_CPU1_BOOT2
          	               	2         	285A3     	SW_PVCCIN_CPU1_BOOT2_R

PR1767    	Q_RES_0402LF   	          	          	                    
          	               	1         	285B3     	SW_PVCCIN_CPU1_BOOT1
          	               	2         	285B3     	SW_PVCCIN_CPU1_BOOT1_R

PR1768    	Q_RES_0402LF   	          	          	                    
          	               	1         	268A3     	SW_PVCCIN_CPU0_BOOT4
          	               	2         	268A3     	SW_PVCCIN_CPU0_BOOT4_R

PR1769    	Q_RES_0402LF   	          	          	                    
          	               	1         	268B3     	SW_PVCCIN_CPU0_BOOT3
          	               	2         	268B3     	SW_PVCCIN_CPU0_BOOT3_R

PR1770    	Q_RES_0402LF   	          	          	                    
          	               	1         	269A3     	SW_PVCCIN_CPU0_BOOT6
          	               	2         	269A3     	SW_PVCCIN_CPU0_BOOT6_R

PR1771    	Q_RES_0402LF   	          	          	                    
          	               	1         	269B3     	SW_PVCCIN_CPU0_BOOT5
          	               	2         	269B3     	SW_PVCCIN_CPU0_BOOT5_R

PR1772    	Q_RES_0402LF   	          	          	                    
          	               	1         	270A3     	SW_PVCCIN_CPU0_BOOT8
          	               	2         	270A3     	SW_PVCCIN_CPU0_BOOT8_R

PR1773    	Q_RES_0402LF   	          	          	                    
          	               	1         	270B3     	SW_PVCCIN_CPU0_BOOT7
          	               	2         	270B3     	SW_PVCCIN_CPU0_BOOT7_R

PR1774    	Q_RES_0402LF   	          	          	                    
          	               	1         	275B3     	SW_PVCCINFAON_CPU0_BOOT1
          	               	2         	275B3     	SW_PVCCINFAON_CPU0_BOOT1_R

PR1775    	Q_RES_0402LF   	          	          	                    
          	               	1         	275A3     	SW_PVCCINFAON_CPU0_BOOT2
          	               	2         	275A3     	SW_PVCCINFAON_CPU0_BOOT2_R

PR1776    	Q_RES_0402LF   	          	          	                    
          	               	1         	275B3     	PVCCINFAON_CPU0_VOS1
          	               	2         	275B3     	PVCCINFAON_CPU0     

PR1777    	Q_RES_0402LF   	          	          	                    
          	               	1         	275A3     	PVCCINFAON_CPU0_VOS2
          	               	2         	275A3     	PVCCINFAON_CPU0     

PR1778    	Q_RES_0402LF   	          	          	                    
          	               	1         	276B3     	SW_PVCCFA_EHV_CPU0_BOOT1
          	               	2         	276B3     	SW_PVCCFA_EHV_CPU0_BOOT1_R

PR1779    	Q_RES_0402LF   	          	          	                    
          	               	1         	276B3     	PVCCFA_EHV_CPU0_NC1 
          	               	2         	276B3     	PVCCFA_EHV_CPU0_VDD1

PR1780    	Q_RES_0402LF   	          	          	                    
          	               	1         	271B3     	SW_PVCCFA_EHV_FIVRA_CPU0_BOOT1
          	               	2         	271B3     	SW_PVCCFA_EHV_FIVRA_CPU0_BOOT1_

PR1781    	Q_RES_0402LF   	          	          	                    
          	               	1         	271A3     	SW_PVCCFA_EHV_FIVRA_CPU0_BOOT2
          	               	2         	271A3     	SW_PVCCFA_EHV_FIVRA_CPU0_BOOT2_

PR1782    	Q_RES_0402LF   	          	          	                    
          	               	1         	272B3     	SW_PVCCFA_EHV_FIVRA_CPU0_BOOT3
          	               	2         	272B3     	SW_PVCCFA_EHV_FIVRA_CPU0_BOOT3_

PR1783    	Q_RES_0402LF   	          	          	                    
          	               	1         	272A3     	SW_PVCCFA_EHV_FIVRA_CPU0_BOOT4
          	               	2         	272A3     	SW_PVCCFA_EHV_FIVRA_CPU0_BOOT4_

PR1784    	Q_RES_0402LF   	          	          	                    
          	               	1         	279B3     	SW_PVCCD_HV_CPU0_BOOT1
          	               	2         	279B3     	SW_PVCCD_HV_CPU0_BOOT1_R

PR1785    	Q_RES_0402LF   	          	          	                    
          	               	1         	279B3     	PVCCD_HV_CPU0_VOS   
          	               	2         	279B3     	PVCCD_HV_CPU0       

PR1786    	Q_RES_0402LF   	          	          	                    
          	               	1         	267A3     	SW_PVCCIN_CPU0_BOOT2
          	               	2         	267A3     	SW_PVCCIN_CPU0_BOOT2_R

PR1787    	Q_RES_0402LF   	          	          	                    
          	               	1         	267B3     	SW_PVCCIN_CPU0_BOOT1
          	               	2         	267B3     	SW_PVCCIN_CPU0_BOOT1_R

PR1788    	Q_RES_0402LF   	          	          	                    
          	               	1         	286A3     	SW_PVCCIN_CPU1_BOOT4
          	               	2         	286A3     	SW_PVCCIN_CPU1_BOOT4_R

PR1789    	Q_RES_0402LF   	          	          	                    
          	               	1         	286B3     	SW_PVCCIN_CPU1_BOOT3
          	               	2         	286B3     	SW_PVCCIN_CPU1_BOOT3_R

PR1790    	Q_RES_0402LF   	          	          	                    
          	               	1         	287A3     	SW_PVCCIN_CPU1_BOOT6
          	               	2         	287A3     	SW_PVCCIN_CPU1_BOOT6_R

PR1791    	Q_RES_0402LF   	          	          	                    
          	               	1         	287B3     	SW_PVCCIN_CPU1_BOOT5
          	               	2         	287B3     	SW_PVCCIN_CPU1_BOOT5_R

PR1792    	Q_RES_0402LF   	          	          	                    
          	               	1         	288A3     	SW_PVCCIN_CPU1_BOOT8
          	               	2         	288A3     	SW_PVCCIN_CPU1_BOOT8_R

PR1793    	Q_RES_0402LF   	          	          	                    
          	               	1         	288B3     	SW_PVCCIN_CPU1_BOOT7
          	               	2         	288B3     	SW_PVCCIN_CPU1_BOOT7_R

PR1794    	Q_RES_0402LF   	          	          	                    
          	               	1         	293B3     	SW_PVCCINFAON_CPU1_BOOT1
          	               	2         	293B3     	SW_PVCCINFAON_CPU1_BOOT1_R

PR1795    	Q_RES_0402LF   	          	          	                    
          	               	1         	293A3     	SW_PVCCINFAON_CPU1_BOOT2
          	               	2         	293A3     	SW_PVCCINFAON_CPU1_BOOT2_R

PR1796    	Q_RES_0402LF   	          	          	                    
          	               	1         	293B3     	PVCCINFAON_CPU1_VOS1
          	               	2         	293B3     	PVCCINFAON_CPU1     

PR1797    	Q_RES_0402LF   	          	          	                    
          	               	1         	293A3     	PVCCINFAON_CPU1_VOS2
          	               	2         	293A3     	PVCCINFAON_CPU1     

PR1798    	Q_RES_0402LF   	          	          	                    
          	               	1         	294B3     	SW_PVCCFA_EHV_CPU1_BOOT1
          	               	2         	294B3     	SW_PVCCFA_EHV_CPU1_BOOT1_R

PR1799    	Q_RES_0402LF   	          	          	                    
          	               	1         	294B3     	PVCCFA_EHV_CPU1_NC1 
          	               	2         	294B3     	PVCCFA_EHV_CPU1_VDD1

PR1800    	Q_RES_0402LF   	          	          	                    
          	               	1         	289B3     	SW_PVCCFA_EHV_FIVRA_CPU1_BOOT1
          	               	2         	289B3     	SW_PVCCFA_EHV_FIVRA_CPU1_BOOT1_

PR1801    	Q_RES_0402LF   	          	          	                    
          	               	1         	289A3     	SW_PVCCFA_EHV_FIVRA_CPU1_BOOT2
          	               	2         	289A3     	SW_PVCCFA_EHV_FIVRA_CPU1_BOOT2_

PR1802    	Q_RES_0402LF   	          	          	                    
          	               	1         	290B3     	SW_PVCCFA_EHV_FIVRA_CPU1_BOOT3
          	               	2         	290B3     	SW_PVCCFA_EHV_FIVRA_CPU1_BOOT3_

PR1803    	Q_RES_0402LF   	          	          	                    
          	               	1         	290A3     	SW_PVCCFA_EHV_FIVRA_CPU1_BOOT4
          	               	2         	290A3     	SW_PVCCFA_EHV_FIVRA_CPU1_BOOT4_

PR1804    	Q_RES_0402LF   	          	          	                    
          	               	1         	297B3     	SW_PVCCD_HV_CPU1_BOOT1
          	               	2         	297B3     	SW_PVCCD_HV_CPU1_BOOT1_R

PR1805    	Q_RES_0402LF   	          	          	                    
          	               	1         	297B3     	PVCCD_HV_CPU1_VOS   
          	               	2         	297B3     	PVCCD_HV_CPU1       

PR1850    	Q_RES_0402LF   	          	          	                    
          	               	1         	263B4     	GND                 
          	               	2         	263B4     	FM_PCH_P1V8_AUX_EN_R

PR2106    	Q_RES_0402LF   	          	          	                    
          	               	1         	301B4     	HSC_VDD             
          	               	2         	301B4     	HSC_VIN_UVW_N       

PR2149    	Q_RES_0402LF   	          	          	                    
          	               	1         	301B4     	HSC_VDD_R           
          	               	2         	301B4     	HSC_VDD             

PR2220    	Q_RES_0402LF   	          	          	                    
          	               	1         	300A4     	PVNN_MAIN_CPU1_MODE 
          	               	2         	300A4     	GND                 

PR2222    	Q_RES_0402LF   	          	          	                    
          	               	1         	300A4     	PVNN_MAIN_CPU1_CS   
          	               	2         	300A4     	GND                 

PR2336    	Q_RES_0402LF   	          	          	                    
          	               	1         	281A2     	PVPP_HBM_CPU0_FB    
          	               	2         	281A2     	FM_HBM_VPP_SEL_CPU0_D

PR2381    	Q_RES_0402LF   	          	          	                    
          	               	1         	299A2     	PVPP_HBM_CPU1_FB    
          	               	2         	299A2     	FM_HBM_VPP_SEL_CPU1_D

PR2510    	Q_RES_0402LF   	          	          	                    
          	               	1         	304B4     	P12V_HSC_ADC_P      
          	               	2         	304B4     	P12V_HSC_SENSE2_R1_P

PR2511    	Q_RES_0402LF   	          	          	                    
          	               	1         	304B4     	P12V_HSC_ADC_P      
          	               	2         	304B4     	P12V_HSC_SENSE2_R2_P

PR2512    	Q_RES_0402LF   	          	          	                    
          	               	1         	304B4     	P12V_HSC_ADC_P      
          	               	2         	304B4     	P12V_HSC_SENSE2_R3_P

PR2513    	Q_RES_0402LF   	          	          	                    
          	               	1         	304B4     	P12V_HSC_ADC_P      
          	               	2         	304B4     	P12V_HSC_SENSE2_R4_P

PR2514    	Q_RES_0402LF   	          	          	                    
          	               	1         	304B4     	P12V_HSC_ADC_P      
          	               	2         	304B4     	P12V_HSC_SENSE1_P   

PR2515    	Q_RES_0402LF   	          	          	                    
          	               	1         	304B4     	P12V_HSC_ADC_N      
          	               	2         	304B4     	P12V_HSC_SENSE2_R1_N

PR2516    	Q_RES_0402LF   	          	          	                    
          	               	1         	304B4     	P12V_HSC_ADC_N      
          	               	2         	304B4     	P12V_HSC_SENSE2_R2_N

PR2517    	Q_RES_0402LF   	          	          	                    
          	               	1         	304B4     	P12V_HSC_ADC_N      
          	               	2         	304B4     	P12V_HSC_SENSE2_R3_N

PR2518    	Q_RES_0402LF   	          	          	                    
          	               	1         	304B4     	P12V_HSC_ADC_N      
          	               	2         	304B4     	P12V_HSC_SENSE2_R4_N

PR2519    	Q_RES_0402LF   	          	          	                    
          	               	1         	304B4     	P12V_HSC_ADC_N      
          	               	2         	304B4     	P12V_HSC_SENSE1_N   

PR2520    	Q_RES_0402LF   	          	          	                    
          	               	1         	304B4     	P12V_HSC_SENSE2_P   
          	               	2         	304B4     	P12V_HSC_SENSE2_R1_P

PR2521    	Q_RES_0402LF   	          	          	                    
          	               	1         	304B4     	P12V_HSC_SENSE2_P   
          	               	2         	304B4     	P12V_HSC_SENSE2_R2_P

PR2522    	Q_RES_0402LF   	          	          	                    
          	               	1         	304B4     	P12V_HSC_SENSE2_P   
          	               	2         	304B4     	P12V_HSC_SENSE2_R3_P

PR2523    	Q_RES_0402LF   	          	          	                    
          	               	1         	304B4     	P12V_HSC_SENSE2_P   
          	               	2         	304B4     	P12V_HSC_SENSE2_R4_P

PR2524    	Q_RES_0402LF   	          	          	                    
          	               	1         	304B4     	P12V_HSC_SENSE2_N   
          	               	2         	304B4     	P12V_HSC_SENSE2_R1_N

PR2525    	Q_RES_0402LF   	          	          	                    
          	               	1         	304B4     	P12V_HSC_SENSE2_N   
          	               	2         	304B4     	P12V_HSC_SENSE2_R2_N

PR2526    	Q_RES_0402LF   	          	          	                    
          	               	1         	304B4     	P12V_HSC_SENSE2_N   
          	               	2         	304B4     	P12V_HSC_SENSE2_R3_N

PR2527    	Q_RES_0402LF   	          	          	                    
          	               	1         	304B4     	P12V_HSC_SENSE2_N   
          	               	2         	304B4     	P12V_HSC_SENSE2_R4_N

PR2528    	Q_RES_0402LF   	          	          	                    
          	               	1         	304A4     	P12V_HSC_GATE_G1    
          	               	2         	304A4     	P12V_HSC_GATE2      

PR2529    	Q_RES_0402LF   	          	          	                    
          	               	1         	304A4     	P12V_HSC_GATE_G2    
          	               	2         	304A4     	P12V_HSC_GATE2      

PR2530    	Q_RES_0402LF   	          	          	                    
          	               	1         	304A3     	P12V_HSC_GATE_G3    
          	               	2         	304A3     	P12V_HSC_GATE2      

PR2531    	Q_RES_0402LF   	          	          	                    
          	               	1         	304A3     	P12V_HSC_GATE_G4    
          	               	2         	304A3     	P12V_HSC_GATE2      

PR2532    	Q_SP_RES4P     	          	          	                    
          	               	1A        	304B3     	P12V_PSU            
          	               	1B        	304B3     	P12V_HSC_SENSE2_R2_P
          	               	2A        	304B2     	P12V_MAIN_R         
          	               	2B        	304B2     	P12V_HSC_SENSE2_R2_N

PR2533    	Q_SP_RES4P     	          	          	                    
          	               	1A        	304B3     	P12V_PSU            
          	               	1B        	304B3     	P12V_HSC_SENSE2_R3_P
          	               	2A        	304B2     	P12V_MAIN_R         
          	               	2B        	304B2     	P12V_HSC_SENSE2_R3_N

PR2534    	Q_SP_RES4P     	          	          	                    
          	               	1A        	304B3     	P12V_PSU            
          	               	1B        	304B3     	P12V_HSC_SENSE2_R4_P
          	               	2A        	304B2     	P12V_MAIN_R         
          	               	2B        	304B2     	P12V_HSC_SENSE2_R4_N

PR2535    	Q_RES_0402LF   	          	          	                    
          	               	1         	304A2     	P12V_HSC_GATE_G5    
          	               	2         	304A2     	P12V_HSC_GATE2      

PR2536    	Q_RES_0402LF   	          	          	                    
          	               	1         	304A2     	P12V_HSC_GATE_G6    
          	               	2         	304A2     	P12V_HSC_GATE2      

PR2537    	Q_RES_0402LF   	          	          	                    
          	               	1         	304B1     	P12V_AUX            
          	               	2         	304A1     	P12V_HSC_GATE_RC    

PR2538    	Q_RES_0402LF   	          	          	                    
          	               	1         	304B1     	MB0_CM_GATE_G0      
          	               	2         	304B1     	P12V_HSC_GATE1      

PR2554    	Q_RES_2512LF   	          	          	                    
          	               	1         	267B2     	P12V_AUX            
          	               	2         	267B2     	SW_P12V_PVCCIN_CPU0_FLT

PR2556    	Q_RES_2512LF   	          	          	                    
          	               	1         	285B2     	P12V_AUX            
          	               	2         	285B2     	SW_P12V_PVCCIN_CPU1_FLT

PR2718    	Q_RES_0402LF   	          	          	                    
          	               	1         	279B4     	PVCCD_HV_CPU0_LSET1 
          	               	2         	279B4     	GND                 

PR3002    	Q_RES_0402LF   	          	          	                    
          	               	1         	301A3     	GND                 
          	               	2         	301A3     	AGND_HSC            

PR3335    	Q_RES_0402LF   	          	          	                    
          	               	1         	281B4     	PVPP_HBM_CPU0_MODE  
          	               	2         	281B4     	GND                 

PR3336    	Q_RES_0402LF   	          	          	                    
          	               	1         	299B4     	PVPP_HBM_CPU1_MODE  
          	               	2         	299B4     	GND                 

PR3337    	Q_RES_0402LF   	          	          	                    
          	               	1         	258B4     	P5V_AUX_MODE        
          	               	2         	258B4     	GND                 

PR3338    	Q_RES_0402LF   	          	          	                    
          	               	1         	300A4     	P3V3_AUX            
          	               	2         	300A4     	PVNN_MAIN_CPU1_VCC  

PR3339    	Q_RES_0402LF   	          	          	                    
          	               	1         	282B4     	P3V3_AUX            
          	               	2         	282A4     	PVNN_MAIN_CPU0_VCC  

PR3780    	Q_RES_0402LF   	          	          	                    
          	               	1         	156B2     	P3V3_OCP_CB_1       
          	               	2         	156B2     	GND                 

PR3781    	Q_RES_0402LF   	          	          	                    
          	               	1         	156B2     	P12V_OCP_SENSE_1    
          	               	2         	156A2     	GND                 

PR3782    	Q_RES_0402LF   	          	          	                    
          	               	1         	162B3     	P3V3_AUX            
          	               	2         	162B3     	P3V3_OCP_VCC_2      

PR3786    	Q_RES_0402LF   	          	          	                    
          	               	1         	156B3     	P12V_AUX            
          	               	2         	156B3     	P12V_OCP_UV_1       

PR3787    	Q_RES_0402LF   	          	          	                    
          	               	1         	156B3     	P12V_OCP_UV_1       
          	               	2         	156B3     	P12V_OCP_OV_1       

PR3788    	Q_RES_0402LF   	          	          	                    
          	               	1         	156A3     	P12V_OCP_OV_1       
          	               	2         	156A3     	GND                 

PR3789    	Q_RES_0402LF   	          	          	                    
          	               	1         	156B3     	P3V3_AUX            
          	               	2         	156B3     	P3V3_OCP_UV_1       

PR3790    	Q_RES_0402LF   	          	          	                    
          	               	1         	156B3     	P3V3_OCP_UV_1       
          	               	2         	156B3     	P3V3_OCP_OV_1       

PR3791    	Q_RES_0402LF   	          	          	                    
          	               	1         	156B3     	P3V3_OCP_OV_1       
          	               	2         	156B3     	GND                 

PR3792    	Q_RES_0402LF   	          	          	                    
          	               	1         	156B3     	P12V_AUX            
          	               	2         	156B3     	P12V_OCP_VCC_1      

PR3795    	Q_RES_0402LF   	          	          	                    
          	               	1         	162B3     	P3V3_AUX            
          	               	2         	162B3     	P3V3_OCP_UV_2       

PR3798    	Q_RES_0402LF   	          	          	                    
          	               	1         	156B3     	P3V3_AUX            
          	               	2         	156B3     	P3V3_OCP_VCC_1      

PR3805    	Q_RES_0402LF   	          	          	                    
          	               	1         	162B3     	P12V_AUX            
          	               	2         	162B3     	P12V_OCP_UV_2       

PR3806    	Q_RES_0402LF   	          	          	                    
          	               	1         	162B3     	P12V_OCP_UV_2       
          	               	2         	162B3     	P12V_OCP_OV_2       

PR3812    	Q_RES_0402LF   	          	          	                    
          	               	1         	162B3     	P3V3_OCP_OV_2       
          	               	2         	162B3     	GND                 

PR3821    	Q_RES_0402LF   	          	          	                    
          	               	1         	162A2     	P12V_OCP_CB_2       
          	               	2         	162A2     	GND                 

PR3822    	Q_RES_0402LF   	          	          	                    
          	               	1         	162B2     	P3V3_OCP_CB_2       
          	               	2         	162B2     	GND                 

PR3823    	Q_RES_0402LF   	          	          	                    
          	               	1         	162B2     	P12V_OCP_SENSE_2    
          	               	2         	162A2     	GND                 

PR3824    	Q_RES_0402LF   	          	          	                    
          	               	1         	162B2     	P3V3_OCP_SENSE_2    
          	               	2         	162B2     	GND                 

PR3828    	Q_RES_0402LF   	          	          	                    
          	               	1         	162A3     	P12V_OCP_OV_2       
          	               	2         	162A3     	GND                 

PR3829    	Q_RES_0402LF   	          	          	                    
          	               	1         	162B3     	P3V3_OCP_UV_2       
          	               	2         	162B3     	P3V3_OCP_OV_2       

PR3830    	Q_RES_0402LF   	          	          	                    
          	               	1         	162B3     	P12V_AUX            
          	               	2         	162B3     	P12V_OCP_VCC_2      

PR3835    	Q_RES_0402LF   	          	          	                    
          	               	1         	157A4     	P12V_OCP_ISET_1     
          	               	2         	157A4     	GND                 

PR3837    	Q_RES_0402LF   	          	          	                    
          	               	1         	157A3     	P12V_OCP_IMON_1     
          	               	2         	157A3     	GND                 

PR3838    	Q_RES_0402LF   	          	          	                    
          	               	1         	157A3     	P12V_OCP_SFF        
          	               	2         	157A3     	P12V_OCP_AVIN_PD_1  

PR3839    	Q_RES_0402LF   	          	          	                    
          	               	1         	157A3     	P12V_OCP_FLTB_1     
          	               	2         	157A3     	P3V3_AUX            

PR3840    	Q_RES_0402LF   	          	          	                    
          	               	1         	157A3     	P12V_OCP_SFF        
          	               	2         	157A3     	P12V_OCP_OV_FB_1    

PR3841    	Q_RES_0402LF   	          	          	                    
          	               	1         	157A3     	P12V_AUX            
          	               	2         	157A3     	P12V_OCP_OV_FB_1    

PR3842    	Q_RES_0402LF   	          	          	                    
          	               	1         	157A3     	P12V_OCP_OV_FB_1    
          	               	2         	157A3     	GND                 

PR3843    	Q_RES_0603LF   	          	          	                    
          	               	1         	157A2     	P12V_AUX            
          	               	2         	157A2     	P12V_OCP_AVIN_PD_1  

PR3844    	Q_RES_0402LF   	          	          	                    
          	               	1         	157B2     	P3V3_OCP_MODE_1     
          	               	2         	157B2     	GND                 

PR3846    	Q_RES_0402LF   	          	          	                    
          	               	1         	157B2     	GND                 
          	               	2         	157B2     	P3V3_OCP_ILIMIT_1   

PR3847    	Q_RES_0402LF   	          	          	                    
          	               	1         	163A4     	P12V_OCP_ISET_2     
          	               	2         	163A4     	GND                 

PR3849    	Q_RES_0402LF   	          	          	                    
          	               	1         	163A3     	P12V_OCP_IMON_2     
          	               	2         	163A3     	GND                 

PR3850    	Q_RES_0402LF   	          	          	                    
          	               	1         	163A3     	P12V_OCP_V3_2       
          	               	2         	163A3     	P12V_OCP_AVIN_PD_2  

PR3851    	Q_RES_0402LF   	          	          	                    
          	               	1         	163A3     	P12V_OCP_FLTB_2     
          	               	2         	163A3     	P3V3_AUX            

PR3852    	Q_RES_0402LF   	          	          	                    
          	               	1         	163A3     	P12V_OCP_V3_2       
          	               	2         	163A3     	P12V_OCP_OV_FB_2    

PR3853    	Q_RES_0402LF   	          	          	                    
          	               	1         	163A3     	P12V_AUX            
          	               	2         	163A3     	P12V_OCP_OV_FB_2    

PR3854    	Q_RES_0402LF   	          	          	                    
          	               	1         	163A3     	P12V_OCP_OV_FB_2    
          	               	2         	163A3     	GND                 

PR3855    	Q_RES_0402LF   	          	          	                    
          	               	1         	163B2     	P3V3_OCP_MODE_2     
          	               	2         	163B2     	GND                 

PR3856    	Q_RES_0402LF   	          	          	                    
          	               	1         	163B2     	GND                 
          	               	2         	163B2     	P3V3_OCP_ILIMIT_2   

PR3857    	Q_RES_0603LF   	          	          	                    
          	               	1         	163A2     	P12V_AUX            
          	               	2         	163A2     	P12V_OCP_AVIN_PD_2  

PR3910    	Q_RES_0402LF   	          	          	                    
          	               	1         	302B4     	HSC_VDD_R_1         
          	               	2         	302B4     	HSC_VDD             

PR3911    	Q_RES_0402LF   	          	          	                    
          	               	1         	302A4     	HSC_VDD_R_2         
          	               	2         	302A4     	HSC_VDD             

PR3912    	Q_RES_0402LF   	          	          	                    
          	               	1         	302A4     	AGND_HSC            
          	               	2         	302A4     	HSC_MODE_2          

PR3914    	Q_RES_0402LF   	          	          	                    
          	               	1         	302B4     	HSC_CS_1            
          	               	2         	302B4     	AGND_HSC            

PR3915    	Q_RES_0402LF   	          	          	                    
          	               	1         	302A4     	HSC_CS_2            
          	               	2         	302A4     	AGND_HSC            

PR3916    	Q_RES_0402LF   	          	          	                    
          	               	1         	302B4     	HSC_SCREF           
          	               	2         	302B3     	HSC_SCREF_1         

PR3917    	Q_RES_0402LF   	          	          	                    
          	               	1         	302A4     	HSC_SCREF           
          	               	2         	302A3     	HSC_SCREF_2         

PR3918    	Q_RES_0402LF   	          	          	                    
          	               	1         	302B3     	HSC_IMON            
          	               	2         	302B3     	AGND_HSC            

PR3919    	Q_RES_0402LF   	          	          	                    
          	               	1         	302B2     	HSC_D_OC_1          
          	               	2         	302B2     	HSC_D_OC_R          

PR3920    	Q_RES_0402LF   	          	          	                    
          	               	1         	302B2     	HSC_FLT_TYPE_1      
          	               	2         	302B2     	HSC_FLT_TYPE        

PR3921    	Q_RES_0402LF   	          	          	                    
          	               	1         	302A2     	HSC_D_OC_2          
          	               	2         	302A2     	HSC_D_OC_R          

PR3922    	Q_RES_0402LF   	          	          	                    
          	               	1         	302A2     	HSC_FLT_TYPE_2      
          	               	2         	302A2     	HSC_FLT_TYPE        

PR3926    	Q_RES_0402LF   	          	          	                    
          	               	1         	301B4     	P12V_PSU            
          	               	2         	301B4     	HSC_VSENSE          

PR3927    	Q_RES_0402LF   	          	          	                    
          	               	1         	301B4     	HSC_VSENSE          
          	               	2         	301B4     	AGND_HSC            

PR3928    	Q_RES_0402LF   	          	          	                    
          	               	1         	301B4     	HSC_ON              
          	               	2         	301B4     	HSC_ON_R            

PR3929    	Q_RES_0402LF   	          	          	                    
          	               	1         	301B3     	HSC_ADDR            
          	               	2         	301B3     	HSC_VDD18           

PR3930    	Q_RES_0402LF   	          	          	                    
          	               	1         	301B3     	AGND_HSC            
          	               	2         	301B3     	HSC_ADDR            

PR3931    	Q_RES_0402LF   	          	          	                    
          	               	1         	301B2     	P12V_AUX            
          	               	2         	301B2     	HSC_VOSEN           

PR3932    	Q_RES_0402LF   	          	          	                    
          	               	1         	301B2     	HSC_VOSEN           
          	               	2         	301B2     	AGND_HSC            

PR3935    	Q_RES_0402LF   	          	          	                    
          	               	1         	301B1     	HSC_VTEMP           
          	               	2         	301B1     	AGND_HSC            

PR3937    	Q_RES_0402LF   	          	          	                    
          	               	1         	301B1     	HSC_MODE            
          	               	2         	301B1     	AGND_HSC            

PR3944    	Q_RES_0402LF   	          	          	                    
          	               	1         	193B4     	P12V_E1S_ISET_0     
          	               	2         	193B4     	GND                 

PR3945    	Q_RES_0402LF   	          	          	                    
          	               	1         	193A3     	P3V3_E1S_MODE_0     
          	               	2         	193A3     	GND                 

PR3947    	Q_RES_0402LF   	          	          	                    
          	               	1         	193A3     	GND                 
          	               	2         	193A3     	P3V3_E1S_ILIMIT_0   

PR3949    	Q_RES_0402LF   	          	          	                    
          	               	1         	193B3     	P12V_E1S_IMON_0     
          	               	2         	193B3     	GND                 

PR3950    	Q_RES_0402LF   	          	          	                    
          	               	1         	193B2     	P12V_E1S_0          
          	               	2         	193B2     	P12V_E1S_AVIN_PD_0  

PR3951    	Q_RES_0402LF   	          	          	                    
          	               	1         	193B2     	P12V_E1S_FLTB_0     
          	               	2         	193B2     	P3V3_AUX            

PR3952    	Q_RES_0402LF   	          	          	                    
          	               	1         	193B2     	P12V_E1S_0          
          	               	2         	193B2     	P12V_E1S_OV_FB_0    

PR3953    	Q_RES_0402LF   	          	          	                    
          	               	1         	193B2     	P12V_AUX            
          	               	2         	193B2     	P12V_E1S_OV_FB_0    

PR3954    	Q_RES_0402LF   	          	          	                    
          	               	1         	193B2     	P12V_E1S_OV_FB_0    
          	               	2         	193B2     	GND                 

PR3957    	Q_RES_0603LF   	          	          	                    
          	               	1         	193B2     	P12V_AUX            
          	               	2         	193B2     	P12V_E1S_AVIN_PD_0  

PR3960    	Q_RES_0402LF   	          	          	                    
          	               	1         	192B3     	P12V_AUX            
          	               	2         	192B3     	P12V_E1S_UV_0       

PR3961    	Q_RES_0402LF   	          	          	                    
          	               	1         	192B3     	P12V_E1S_UV_0       
          	               	2         	192B3     	P12V_E1S_OV_0       

PR3962    	Q_RES_0402LF   	          	          	                    
          	               	1         	192B3     	P12V_E1S_OV_0       
          	               	2         	192B3     	GND                 

PR3963    	Q_RES_0402LF   	          	          	                    
          	               	1         	192A3     	P3V3_AUX            
          	               	2         	192A3     	P3V3_E1S_UV_0       

PR3964    	Q_RES_0402LF   	          	          	                    
          	               	1         	192A3     	P3V3_E1S_UV_0       
          	               	2         	192A3     	P3V3_E1S_OV_0       

PR3965    	Q_RES_0402LF   	          	          	                    
          	               	1         	192A3     	P3V3_E1S_OV_0       
          	               	2         	192A3     	GND                 

PR3966    	Q_RES_0402LF   	          	          	                    
          	               	1         	192B3     	P12V_AUX            
          	               	2         	192B3     	P12V_E1S_VCC_0      

PR3967    	Q_RES_0402LF   	          	          	                    
          	               	1         	192A3     	P3V3_AUX            
          	               	2         	192A3     	P3V3_E1S_VCC_0      

PR3968    	Q_RES_0402LF   	          	          	                    
          	               	1         	192B2     	P12V_E1S_CB_0       
          	               	2         	192B2     	GND                 

PR3969    	Q_RES_0402LF   	          	          	                    
          	               	1         	192A2     	P3V3_E1S_CB_0       
          	               	2         	192A2     	GND                 

PR3970    	Q_RES_0402LF   	          	          	                    
          	               	1         	192B2     	P12V_E1S_SENSE_0    
          	               	2         	192B2     	GND                 

PR3971    	Q_RES_0402LF   	          	          	                    
          	               	1         	192A2     	P3V3_E1S_SENSE_0    
          	               	2         	192A2     	GND                 

PR3980    	Q_RES_0402LF   	          	          	                    
          	               	1         	303B4     	HSC_VDD_R_3         
          	               	2         	303B4     	HSC_VDD             

PR3981    	Q_RES_0402LF   	          	          	                    
          	               	1         	303A4     	HSC_VDD_R_4         
          	               	2         	303B4     	HSC_VDD             

PR3982    	Q_RES_0402LF   	          	          	                    
          	               	1         	303B4     	AGND_HSC            
          	               	2         	303B4     	HSC_MODE_3          

PR3984    	Q_RES_0402LF   	          	          	                    
          	               	1         	303A4     	AGND_HSC            
          	               	2         	303A4     	HSC_MODE_4          

PR3986    	Q_RES_0402LF   	          	          	                    
          	               	1         	303B4     	HSC_CS_3            
          	               	2         	303B4     	AGND_HSC            

PR3987    	Q_RES_0402LF   	          	          	                    
          	               	1         	303A4     	HSC_CS_4            
          	               	2         	303A4     	AGND_HSC            

PR3988    	Q_RES_0402LF   	          	          	                    
          	               	1         	303B4     	HSC_SCREF           
          	               	2         	303B3     	HSC_SCREF_3         

PR3989    	Q_RES_0402LF   	          	          	                    
          	               	1         	303A4     	HSC_SCREF           
          	               	2         	303A3     	HSC_SCREF_4         

PR3990    	Q_RES_0402LF   	          	          	                    
          	               	1         	303B3     	HSC_IMON            
          	               	2         	303B3     	AGND_HSC            

PR3991    	Q_RES_0402LF   	          	          	                    
          	               	1         	303A3     	HSC_IMON            
          	               	2         	303A3     	AGND_HSC            

PR3992    	Q_RES_0402LF   	          	          	                    
          	               	1         	303B2     	HSC_D_OC_3          
          	               	2         	303B2     	HSC_D_OC_R          

PR3993    	Q_RES_0402LF   	          	          	                    
          	               	1         	303B2     	HSC_FLT_TYPE_3      
          	               	2         	303B2     	HSC_FLT_TYPE        

PR3994    	Q_RES_0402LF   	          	          	                    
          	               	1         	303A2     	HSC_D_OC_4          
          	               	2         	303A2     	HSC_D_OC_R          

PR3995    	Q_RES_0402LF   	          	          	                    
          	               	1         	303A2     	HSC_FLT_TYPE_4      
          	               	2         	303A2     	HSC_FLT_TYPE        

PR3999    	Q_RES_0402LF   	          	          	                    
          	               	1         	242A3     	P12V_SCM_ISET       
          	               	2         	242A3     	GND                 

PR4000    	Q_RES_0402LF   	          	          	                    
          	               	1         	242B3     	P12V_AUX            
          	               	2         	242B3     	P12V_SCM_UV         

PR4001    	Q_RES_0402LF   	          	          	                    
          	               	1         	242B3     	P12V_SCM_UV         
          	               	2         	242B3     	P12V_SCM_OV         

PR4002    	Q_RES_0402LF   	          	          	                    
          	               	1         	242B3     	P12V_SCM_OV         
          	               	2         	242B3     	GND                 

PR4003    	Q_RES_0402LF   	          	          	                    
          	               	1         	242B3     	P12V_AUX            
          	               	2         	242B3     	P12V_SCM_VCC        

PR4004    	Q_RES_0402LF   	          	          	                    
          	               	1         	242B2     	P12V_SCM_CB         
          	               	2         	242B2     	GND                 

PR4005    	Q_RES_0402LF   	          	          	                    
          	               	1         	242A2     	P12V_SCM_IMON       
          	               	2         	242A2     	GND                 

PR4006    	Q_RES_0402LF   	          	          	                    
          	               	1         	242A2     	P12V_SCM_R          
          	               	2         	242A2     	P12V_SCM_AVIN_PD    

PR4007    	Q_RES_0402LF   	          	          	                    
          	               	1         	242A2     	P12V_SCM_FLTB_N     
          	               	2         	242A2     	P3V3_AUX            

PR4008    	Q_RES_0402LF   	          	          	                    
          	               	1         	242B2     	P12V_SCM_SENSE      
          	               	2         	242B2     	GND                 

PR4009    	Q_RES_0402LF   	          	          	                    
          	               	1         	242A2     	P12V_SCM_R          
          	               	2         	242A2     	P12V_SCM_OV_FB      

PR4010    	Q_RES_0402LF   	          	          	                    
          	               	1         	242A1     	P12V_AUX            
          	               	2         	242A1     	P12V_SCM_OV_FB      

PR4011    	Q_RES_0402LF   	          	          	                    
          	               	1         	242A1     	P12V_SCM_OV_FB      
          	               	2         	242A1     	GND                 

PR4012    	Q_RES_0402LF   	          	          	                    
          	               	1         	242B1     	P12V_SCM_PWRGD      
          	               	2         	242B1     	HP_LVC3_SCM_HSC_PWRGD

PR4014    	Q_RES_0603LF   	          	          	                    
          	               	1         	242A1     	P12V_AUX            
          	               	2         	242A1     	P12V_SCM_AVIN_PD    

PR4217    	Q_RES_0402LF   	          	          	                    
          	               	1         	266B2     	PVCCFA_EHV_FIVRA_CPU0_IMON4
          	               	2         	266B2     	GND                 

PR4218    	Q_RES_0402LF   	          	          	                    
          	               	1         	266A2     	PVCCFA_EHV_FIVRA_CPU0_IMON3
          	               	2         	266A2     	GND                 

PR4219    	Q_RES_0402LF   	          	          	                    
          	               	1         	267A1     	PVCCIN_CPU0         
          	               	2         	267A1     	GND                 

PR4220    	Q_RES_0402LF   	          	          	                    
          	               	1         	274A4     	PVCCINFAON_CPU0_CSPIN
          	               	2         	274A4     	GND                 

PR4221    	Q_RES_0402LF   	          	          	                    
          	               	1         	274B2     	NC_PVCCINFAON_CPU0_ACSP3
          	               	2         	274B2     	GND                 

PR4222    	Q_RES_0402LF   	          	          	                    
          	               	1         	274B2     	NC_PVCCINFAON_CPU0_ACSP4
          	               	2         	274B2     	GND                 

PR4223    	Q_RES_0402LF   	          	          	                    
          	               	1         	274B2     	NC_PVCCINFAON_CPU0_ACSP5
          	               	2         	274B2     	GND                 

PR4224    	Q_RES_0402LF   	          	          	                    
          	               	1         	274B2     	NC_PVCCINFAON_CPU0_ACSP6
          	               	2         	274B2     	GND                 

PR4225    	Q_RES_0402LF   	          	          	                    
          	               	1         	274A2     	NC_PVCCINFAON_CPU0_ACSP7
          	               	2         	274A2     	GND                 

PR4226    	Q_RES_0402LF   	          	          	                    
          	               	1         	275A2     	PVCCINFAON_CPU0     
          	               	2         	275A2     	GND                 

PR4227    	Q_RES_0402LF   	          	          	                    
          	               	1         	276B4     	PVCCFA_EHV_CPU0_VDD1
          	               	2         	276B4     	PVCCFA_EHV_CPU0_NC2 

PR4228    	Q_RES_0402LF   	          	          	                    
          	               	1         	276B3     	PVCCFA_EHV_CPU0_FAULT
          	               	2         	276B3     	GND                 

PR4229    	Q_RES_0402LF   	          	          	                    
          	               	1         	276B1     	PVCCFA_EHV_CPU0     
          	               	2         	276B1     	GND                 

PR4230    	Q_RES_0402LF   	          	          	                    
          	               	1         	278B2     	NC_PVCCD_HV_CPU0_ACSP2
          	               	2         	278B2     	GND                 

PR4231    	Q_RES_0402LF   	          	          	                    
          	               	1         	278B2     	NC_PVCCD_HV_CPU0_ACSP3
          	               	2         	278B2     	GND                 

PR4232    	Q_RES_0402LF   	          	          	                    
          	               	1         	278B2     	NC_PVCCD_HV_CPU0_ACSP4
          	               	2         	278B2     	GND                 

PR4233    	Q_RES_0402LF   	          	          	                    
          	               	1         	278B2     	NC_PVCCD_HV_CPU0_ACSP5
          	               	2         	278B2     	GND                 

PR4234    	Q_RES_0402LF   	          	          	                    
          	               	1         	278B2     	NC_PVCCD_HV_CPU0_ACSP6
          	               	2         	278B2     	GND                 

PR4235    	Q_RES_0402LF   	          	          	                    
          	               	1         	278A2     	NC_PVCCD_HV_CPU0_ACSP7
          	               	2         	278A2     	GND                 

PR4236    	Q_RES_0402LF   	          	          	                    
          	               	1         	278A2     	NC_PVCCD_HV_CPU0_ACSP8
          	               	2         	278A2     	GND                 

PR4237    	Q_RES_0402LF   	          	          	                    
          	               	1         	279B1     	PVCCD_HV_CPU0       
          	               	2         	279B1     	GND                 

PR4238    	Q_RES_0402LF   	          	          	                    
          	               	1         	284B2     	PVCCFA_EHV_FIVRA_CPU1_IMON4
          	               	2         	284B2     	GND                 

PR4239    	Q_RES_0402LF   	          	          	                    
          	               	1         	284A2     	PVCCFA_EHV_FIVRA_CPU1_IMON3
          	               	2         	284A2     	GND                 

PR4240    	Q_RES_0402LF   	          	          	                    
          	               	1         	285A1     	PVCCIN_CPU1         
          	               	2         	285A1     	GND                 

PR4241    	Q_RES_0402LF   	          	          	                    
          	               	1         	289A1     	PVCCFA_EHV_FIVRA_CPU1
          	               	2         	289A1     	GND                 

PR4242    	Q_RES_0402LF   	          	          	                    
          	               	1         	292B2     	NC_PVCCINFAON_CPU1_ACSP3
          	               	2         	292B2     	GND                 

PR4243    	Q_RES_0402LF   	          	          	                    
          	               	1         	292B2     	NC_PVCCINFAON_CPU1_ACSP4
          	               	2         	292B2     	GND                 

PR4244    	Q_RES_0402LF   	          	          	                    
          	               	1         	292B2     	NC_PVCCINFAON_CPU1_ACSP5
          	               	2         	292B2     	GND                 

PR4245    	Q_RES_0402LF   	          	          	                    
          	               	1         	292B2     	NC_PVCCINFAON_CPU1_ACSP6
          	               	2         	292B2     	GND                 

PR4246    	Q_RES_0402LF   	          	          	                    
          	               	1         	292B2     	NC_PVCCINFAON_CPU1_ACSP7
          	               	2         	292B2     	GND                 

PR4247    	Q_RES_0402LF   	          	          	                    
          	               	1         	293A2     	PVCCINFAON_CPU1     
          	               	2         	293A2     	GND                 

PR4248    	Q_RES_0402LF   	          	          	                    
          	               	1         	294B4     	PVCCFA_EHV_CPU1_NC2 
          	               	2         	294B4     	PVCCFA_EHV_CPU1_VDD1

PR4249    	Q_RES_0402LF   	          	          	                    
          	               	1         	294B3     	PVCCFA_EHV_CPU1_FAULT
          	               	2         	294B3     	GND                 

PR4250    	Q_RES_0402LF   	          	          	                    
          	               	1         	294B1     	PVCCFA_EHV_CPU1     
          	               	2         	294B1     	GND                 

PR4251    	Q_RES_0402LF   	          	          	                    
          	               	1         	296B2     	NC_PVCCD_HV_CPU1_ACSP2
          	               	2         	296B2     	GND                 

PR4252    	Q_RES_0402LF   	          	          	                    
          	               	1         	296B2     	NC_PVCCD_HV_CPU1_ACSP3
          	               	2         	296B2     	GND                 

PR4253    	Q_RES_0402LF   	          	          	                    
          	               	1         	296B2     	NC_PVCCD_HV_CPU1_ACSP4
          	               	2         	296B2     	GND                 

PR4254    	Q_RES_0402LF   	          	          	                    
          	               	1         	296B2     	NC_PVCCD_HV_CPU1_ACSP5
          	               	2         	296B2     	GND                 

PR4255    	Q_RES_0402LF   	          	          	                    
          	               	1         	296B2     	NC_PVCCD_HV_CPU1_ACSP6
          	               	2         	296B2     	GND                 

PR4256    	Q_RES_0402LF   	          	          	                    
          	               	1         	296A2     	NC_PVCCD_HV_CPU1_ACSP7
          	               	2         	296A2     	GND                 

PR4257    	Q_RES_0402LF   	          	          	                    
          	               	1         	296A2     	NC_PVCCD_HV_CPU1_ACSP8
          	               	2         	296A2     	GND                 

PR4258    	Q_RES_0402LF   	          	          	                    
          	               	1         	297B1     	PVCCD_HV_CPU1       
          	               	2         	297B1     	GND                 

PR4265    	Q_RES_0402LF   	          	          	                    
          	               	1         	271A1     	PVCCFA_EHV_FIVRA_CPU0
          	               	2         	271A1     	GND                 

PR4271    	Q_RES_0402LF   	          	          	                    
          	               	1         	282B3     	SW_PVNN_MAIN_CPU0_BST
          	               	2         	282B3     	SW_PVNN_MAIN_CPU0_BST_R

PR4272    	Q_RES_0402LF   	          	          	                    
          	               	1         	300B2     	SW_PVNN_MAIN_CPU1_BST
          	               	2         	300B2     	SW_PVNN_MAIN_CPU1_BST_R

PR4522    	Q_RES_0402LF   	          	          	                    
          	               	1         	162B2     	P12V_OCP_V3_2       
          	               	2         	162B2     	P12V_OCP_GATE_2     

PR4523    	Q_RES_0402LF   	          	          	                    
          	               	1         	162B1     	P3V3_OCP_V3_2_R     
          	               	2         	162B1     	P3V3_OCP_GATE_2     

PR4524    	Q_RES_0402LF   	          	          	                    
          	               	1         	156B2     	P12V_OCP_SFF        
          	               	2         	156B2     	P12V_OCP_GATE_1     

PR4525    	Q_RES_0402LF   	          	          	                    
          	               	1         	156B1     	P3V3_OCP_SFF_R      
          	               	2         	156B1     	P3V3_OCP_GATE_PU202_1

PR4526    	Q_RES_0402LF   	          	          	                    
          	               	1         	242B1     	P12V_SCM_R          
          	               	2         	242B1     	P12V_SCM_GATE       

PR4527    	Q_RES_0402LF   	          	          	                    
          	               	1         	192A2     	P3V3_E1S_0_R        
          	               	2         	192A2     	P3V3_E1S_GATE_0     

PR4528    	Q_RES_0402LF   	          	          	                    
          	               	1         	192B2     	P12V_E1S_0          
          	               	2         	192B2     	P12V_E1S_GATE_0     

PR4540    	Q_RES_0402LF   	          	          	                    
          	               	1         	242A3     	P12V_SCM_ISET       
          	               	2         	242A3     	P12V_SCM_ISET_R     

PR4541    	Q_RES_0402LF   	          	          	                    
          	               	1         	193B4     	P12V_E1S_ISET_0     
          	               	2         	193B4     	P12V_E1S_ISET_0_R   

PR4683    	Q_RES_0402LF   	          	          	                    
          	               	1         	282A1     	PVNN_MAIN_CPU0_FB_RC
          	               	2         	282A1     	PVNN_MAIN_CPU0      

PR4698    	Q_RES_0402LF   	          	          	                    
          	               	1         	282A1     	PVNN_MAIN_CPU0_FB_RC
          	               	2         	282A1     	PVNN_MAIN_CPU0      

PR4699    	Q_RES_0402LF   	          	          	                    
          	               	1         	300A1     	PVNN_MAIN_CPU1_FB_RC
          	               	2         	300A1     	PVNN_MAIN_CPU1      

PR4700    	Q_RES_0402LF   	          	          	                    
          	               	1         	300A1     	PVNN_MAIN_CPU1_FB_RC
          	               	2         	300A1     	PVNN_MAIN_CPU1      

PR5481    	Q_RES_0402LF   	          	          	                    
          	               	1         	156B2     	P3V3_OCP_SENSE_1    
          	               	2         	156B2     	GND                 

PR5484    	Q_RES_0402LF   	          	          	                    
          	               	1         	156A3     	P12V_OCP_CB_1       
          	               	2         	156A3     	GND                 

PU5       	ISL69260IRAZT  	          	          	                    
          	               	1         	274A2     	PVCCFA_EHV_CPU0_BPWM1
          	               	2         	274B2     	NC_PVCCINFAON_CPU0_APWM7
          	               	3         	274B2     	NC_PVCCINFAON_CPU0_APWM6
          	               	4         	274B2     	NC_PVCCINFAON_CPU0_APWM5
          	               	5         	274B2     	NC_PVCCINFAON_CPU0_APWM4
          	               	6         	274B2     	NC_PVCCINFAON_CPU0_APWM3
          	               	7         	274B2     	PVCCINFAON_CPU0_APWM2
          	               	8         	274B2     	PVCCINFAON_CPU0_APWM1
          	               	9         	274B3     	SMB_DIO_PVCCINFAON_CPU0
          	               	10        	274B3     	SMB_CLK_PVCCINFAON_CPU0
          	               	11        	274B3     	NC_PVCCINFAON_CPU0_SMB_ALERT
          	               	12        	274B3     	PWRGD_PVCCINFAON_CPU0_R
          	               	13        	274B3     	PVCCINFAON_CPU0_EN_R
          	               	14        	274A2     	IRQ_PVCCFA_CPU0_VRHOT_N
          	               	15        	274A3     	PVCCINFAON_CPU0_PIN_ALERT
          	               	16        	274A3     	PWRGD_PVCCFA_EHV_CPU0_R
          	               	17        	274B3     	SVID_CLK_PVCCINFAON_CPU0_R
          	               	18        	274B3     	SVID_DIO_PVCCINFAON_CPU0_R
          	               	19        	274B3     	SVID_ALERT_PVCCINFAON_CPU0_R
          	               	20        	274A3     	PVCCFA_EHV_CPU0_EN_R
          	               	21        	274B3     	SH_PVCCINFAON_CPU0_R
          	               	22        	274B3     	VSENSE_PVCCINFAON_CPU0_DN
          	               	23        	274B2     	PVCCINFAON_CPU0_ACSP1
          	               	24        	274B2     	PVCCINFAON_CPU0_ACSP2
          	               	25        	274B2     	NC_PVCCINFAON_CPU0_ACSP3
          	               	26        	274B2     	NC_PVCCINFAON_CPU0_ACSP4
          	               	27        	274B2     	NC_PVCCINFAON_CPU0_ACSP5
          	               	28        	274B2     	NC_PVCCINFAON_CPU0_ACSP6
          	               	29        	274A2     	NC_PVCCINFAON_CPU0_ACSP7
          	               	30        	274A2     	PVCCFA_EHV_CPU0_BCSP1
          	               	31        	274B3     	VSENSE_PVCCFA_EHV_CPU0_DN
          	               	32        	274B3     	SH_PVCCFA_EHV_CPU0_R
          	               	33        	274A3     	PVCCINFAON_CPU0_VR_FAULT
          	               	34        	274A3     	PVCCINFAON_CPU0_ADDR
          	               	35        	274A2     	PVCCINFAON_CPU0_ATSEN
          	               	36        	274A2     	PVCCFA_EHV_CPU0_BTSEN
          	               	37        	274A3     	PVCCINFAON_CPU0_CSPIN
          	               	38        	274A3     	PVCCINFAON_CPU0_VIN_CSNIN
          	               	39        	274B2     	PVCCINFAON_CPU0_VCC 
          	               	40        	274B2     	PVCCINFAON_CPU0_VREF
          	               	TH        	274A3     	GND                 

PU6_P0_8  	ISL99390FRZTR5935	          	          	                    
          	               	1         	270A3     	PVCCIN_CPU0_VOS8    
          	               	2         	270A3     	GND                 
          	               	3         	270A4     	PVCCIN_CPU0_VDD8    
          	               	4         	270A4     	PVCCIN_CPU0_PVCC    
          	               	5         	270A3     	GND                 
          	               	6         	270A3     	NC                  
          	               	7_9-20_24 	270A3     	GND                 
          	               	10_19     	270A3     	SW_PVCCIN_CPU0_SW8  
          	               	25_29     	270A3     	SW_P12V_PVCCIN_CPU0_FLT
          	               	30        	270A3     	SW_P12V_PVCCIN_CPU0_FLT
          	               	31        	270A4     	NC                  
          	               	32        	270A3     	SW_PVCCIN_CPU0_BOOTR8
          	               	33        	270A3     	SW_PVCCIN_CPU0_BOOT8
          	               	34        	270A4     	PVCCIN_CPU0_PWM8    
          	               	35        	270A4     	PVCCIN_CPU0_VDD8    
          	               	36        	270A4     	PVCCIN_CPU0_ATSEN   
          	               	37        	270A4     	PVCCIN_CPU0_LSET8   
          	               	38        	270A4     	PVCCIN_CPU0_IMON8   
          	               	39        	270A4     	PVCCIN_CPU0_VREF    
          	               	40        	270A3     	GND                 
          	               	41        	270A3     	NC                  

PU7_P0_7  	ISL99390FRZTR5935	          	          	                    
          	               	1         	270B3     	PVCCIN_CPU0_VOS7    
          	               	2         	270B3     	GND                 
          	               	3         	270B4     	PVCCIN_CPU0_VDD7    
          	               	4         	270B4     	PVCCIN_CPU0_PVCC    
          	               	5         	270B3     	GND                 
          	               	6         	270B3     	NC                  
          	               	7_9-20_24 	270B3     	GND                 
          	               	10_19     	270B3     	SW_PVCCIN_CPU0_SW7  
          	               	25_29     	270B3     	SW_P12V_PVCCIN_CPU0_FLT
          	               	30        	270B3     	SW_P12V_PVCCIN_CPU0_FLT
          	               	31        	270B4     	NC                  
          	               	32        	270B3     	SW_PVCCIN_CPU0_BOOTR7
          	               	33        	270B3     	SW_PVCCIN_CPU0_BOOT7
          	               	34        	270B4     	PVCCIN_CPU0_PWM7    
          	               	35        	270B4     	PVCCIN_CPU0_VDD7    
          	               	36        	270B4     	PVCCIN_CPU0_ATSEN   
          	               	37        	270B4     	PVCCIN_CPU0_LSET7   
          	               	38        	270B4     	PVCCIN_CPU0_IMON7   
          	               	39        	270B4     	PVCCIN_CPU0_VREF    
          	               	40        	270B3     	GND                 
          	               	41        	270B3     	NC                  

PU8_P0_6  	ISL99390FRZTR5935	          	          	                    
          	               	1         	269A3     	PVCCIN_CPU0_VOS6    
          	               	2         	269A3     	GND                 
          	               	3         	269A3     	PVCCIN_CPU0_VDD6    
          	               	4         	269A3     	PVCCIN_CPU0_PVCC    
          	               	5         	269A3     	GND                 
          	               	6         	269A3     	NC                  
          	               	7_9-20_24 	269A3     	GND                 
          	               	10_19     	269A3     	SW_PVCCIN_CPU0_SW6  
          	               	25_29     	269A3     	SW_P12V_PVCCIN_CPU0_FLT
          	               	30        	269A3     	SW_P12V_PVCCIN_CPU0_FLT
          	               	31        	269A3     	NC                  
          	               	32        	269A3     	SW_PVCCIN_CPU0_BOOTR6
          	               	33        	269A3     	SW_PVCCIN_CPU0_BOOT6
          	               	34        	269A3     	PVCCIN_CPU0_PWM6    
          	               	35        	269A3     	PVCCIN_CPU0_VDD6    
          	               	36        	269A3     	PVCCIN_CPU0_ATSEN   
          	               	37        	269A3     	PVCCIN_CPU0_LSET6   
          	               	38        	269A3     	PVCCIN_CPU0_IMON6   
          	               	39        	269A3     	PVCCIN_CPU0_VREF    
          	               	40        	269A3     	GND                 
          	               	41        	269A3     	NC                  

PU9       	IR3889MTRPBF   	          	          	                    
          	               	1         	259A3     	P3V3_AUX_ILIM       
          	               	2         	259B3     	PWRGD_P3V3_AUX      
          	               	3         	259B3     	P12V_AUX            
          	               	4         	259B3     	P3V3_AUX_VCC        
          	               	5         	259B3     	P3V3_AUX_VDRV       
          	               	6         	259B3     	NC_PU9_3            
          	               	7_10-19   	259A3     	GND                 
          	               	11_18     	259B3     	SW_P3V3_AUX_SW      
          	               	20_24     	259B3     	SW_P3V3_AUX_FLT     
          	               	25        	259B3     	SW_P3V3_AUX_BOOTR   
          	               	26        	259B3     	SW_P3V3_AUX_BOOT    
          	               	27        	259B3     	P3V3_AUX_EN         
          	               	28        	259A3     	P3V3_AUX_VOS        
          	               	29        	259A3     	P3V3_AUX_SS         
          	               	30        	259A3     	P3V3_AUX_FB         
          	               	31        	259A3     	GND                 
          	               	32        	259A3     	GND                 
          	               	33        	259A3     	NC_PU9_1            
          	               	34        	259A3     	NC_PU9_2            
          	               	35        	259B3     	NC_HICCUP           
          	               	36        	259A3     	P3V3_AUX_MODE       
          	               	37        	259B3     	NC_PU9_4            

PU9_P0_5  	ISL99390FRZTR5935	          	          	                    
          	               	1         	269B3     	PVCCIN_CPU0_VOS5    
          	               	2         	269B3     	GND                 
          	               	3         	269B3     	PVCCIN_CPU0_VDD5    
          	               	4         	269B3     	PVCCIN_CPU0_PVCC    
          	               	5         	269B3     	GND                 
          	               	6         	269B3     	NC                  
          	               	7_9-20_24 	269B3     	GND                 
          	               	10_19     	269B3     	SW_PVCCIN_CPU0_SW5  
          	               	25_29     	269B3     	SW_P12V_PVCCIN_CPU0_FLT
          	               	30        	269B3     	SW_P12V_PVCCIN_CPU0_FLT
          	               	31        	269B3     	NC                  
          	               	32        	269B3     	SW_PVCCIN_CPU0_BOOTR5
          	               	33        	269B3     	SW_PVCCIN_CPU0_BOOT5
          	               	34        	269B3     	PVCCIN_CPU0_PWM5    
          	               	35        	269B3     	PVCCIN_CPU0_VDD5    
          	               	36        	269B3     	PVCCIN_CPU0_ATSEN   
          	               	37        	269B3     	PVCCIN_CPU0_LSET5   
          	               	38        	269B3     	PVCCIN_CPU0_IMON5   
          	               	39        	269B3     	PVCCIN_CPU0_VREF    
          	               	40        	269B3     	GND                 
          	               	41        	269B3     	NC                  

PU10_P0_4 	ISL99390FRZTR5935	          	          	                    
          	               	1         	268A3     	PVCCIN_CPU0_VOS4    
          	               	2         	268A3     	GND                 
          	               	3         	268A3     	PVCCIN_CPU0_VDD4    
          	               	4         	268A3     	PVCCIN_CPU0_PVCC    
          	               	5         	268A3     	GND                 
          	               	6         	268A3     	NC                  
          	               	7_9-20_24 	268A3     	GND                 
          	               	10_19     	268A3     	SW_PVCCIN_CPU0_SW4  
          	               	25_29     	268A3     	SW_P12V_PVCCIN_CPU0_FLT
          	               	30        	268A3     	SW_P12V_PVCCIN_CPU0_FLT
          	               	31        	268A3     	NC                  
          	               	32        	268A3     	SW_PVCCIN_CPU0_BOOTR4
          	               	33        	268A3     	SW_PVCCIN_CPU0_BOOT4
          	               	34        	268A3     	PVCCIN_CPU0_PWM4    
          	               	35        	268A3     	PVCCIN_CPU0_VDD4    
          	               	36        	268A3     	PVCCIN_CPU0_ATSEN   
          	               	37        	268A3     	PVCCIN_CPU0_LSET4   
          	               	38        	268A3     	PVCCIN_CPU0_IMON4   
          	               	39        	268A3     	PVCCIN_CPU0_VREF    
          	               	40        	268A3     	GND                 
          	               	41        	268A3     	NC                  

PU11_P0_3 	ISL99390FRZTR5935	          	          	                    
          	               	1         	268B3     	PVCCIN_CPU0_VOS3    
          	               	2         	268B3     	GND                 
          	               	3         	268B3     	PVCCIN_CPU0_VDD3    
          	               	4         	268B3     	PVCCIN_CPU0_PVCC    
          	               	5         	268B3     	GND                 
          	               	6         	268B3     	NC                  
          	               	7_9-20_24 	268B3     	GND                 
          	               	10_19     	268B3     	SW_PVCCIN_CPU0_SW3  
          	               	25_29     	268B3     	SW_P12V_PVCCIN_CPU0_FLT
          	               	30        	268B3     	SW_P12V_PVCCIN_CPU0_FLT
          	               	31        	268B3     	NC                  
          	               	32        	268B3     	SW_PVCCIN_CPU0_BOOTR3
          	               	33        	268B3     	SW_PVCCIN_CPU0_BOOT3
          	               	34        	268B3     	PVCCIN_CPU0_PWM3    
          	               	35        	268B3     	PVCCIN_CPU0_VDD3    
          	               	36        	268B3     	PVCCIN_CPU0_ATSEN   
          	               	37        	268B3     	PVCCIN_CPU0_LSET3   
          	               	38        	268B3     	PVCCIN_CPU0_IMON3   
          	               	39        	268B3     	PVCCIN_CPU0_VREF    
          	               	40        	268B3     	GND                 
          	               	41        	268B3     	NC                  

PU12_P0_2 	ISL99390FRZTR5935	          	          	                    
          	               	1         	267A4     	PVCCIN_CPU0_VOS2    
          	               	2         	267A4     	GND                 
          	               	3         	267A4     	PVCCIN_CPU0_VDD2    
          	               	4         	267A4     	PVCCIN_CPU0_PVCC    
          	               	5         	267A4     	GND                 
          	               	6         	267A4     	NC                  
          	               	7_9-20_24 	267A4     	GND                 
          	               	10_19     	267A4     	SW_PVCCIN_CPU0_SW2  
          	               	25_29     	267A4     	SW_P12V_PVCCIN_CPU0_FLT
          	               	30        	267A4     	SW_P12V_PVCCIN_CPU0_FLT
          	               	31        	267A4     	NC                  
          	               	32        	267A4     	SW_PVCCIN_CPU0_BOOTR2
          	               	33        	267A4     	SW_PVCCIN_CPU0_BOOT2
          	               	34        	267A4     	PVCCIN_CPU0_PWM2    
          	               	35        	267A4     	PVCCIN_CPU0_VDD2    
          	               	36        	267A4     	PVCCIN_CPU0_ATSEN   
          	               	37        	267A4     	PVCCIN_CPU0_LSET2   
          	               	38        	267A4     	PVCCIN_CPU0_IMON2   
          	               	39        	267A4     	PVCCIN_CPU0_VREF    
          	               	40        	267A4     	GND                 
          	               	41        	267A4     	NC                  

PU13_P0_1 	ISL99390FRZTR5935	          	          	                    
          	               	1         	267B4     	PVCCIN_CPU0_VOS1    
          	               	2         	267B4     	GND                 
          	               	3         	267B4     	PVCCIN_CPU0_VDD1    
          	               	4         	267B4     	PVCCIN_CPU0_PVCC    
          	               	5         	267B4     	GND                 
          	               	6         	267B4     	NC                  
          	               	7_9-20_24 	267B4     	GND                 
          	               	10_19     	267B4     	SW_PVCCIN_CPU0_SW1  
          	               	25_29     	267B4     	SW_P12V_PVCCIN_CPU0_FLT
          	               	30        	267B4     	SW_P12V_PVCCIN_CPU0_FLT
          	               	31        	267B4     	NC                  
          	               	32        	267B4     	SW_PVCCIN_CPU0_BOOTR1
          	               	33        	267B4     	SW_PVCCIN_CPU0_BOOT1
          	               	34        	267B4     	PVCCIN_CPU0_PWM1    
          	               	35        	267B4     	PVCCIN_CPU0_VDD1    
          	               	36        	267B4     	PVCCIN_CPU0_ATSEN   
          	               	37        	267B4     	PVCCIN_CPU0_LSET1   
          	               	38        	267B4     	PVCCIN_CPU0_IMON1   
          	               	39        	267B4     	PVCCIN_CPU0_VREF    
          	               	40        	267B4     	GND                 
          	               	41        	267B4     	NC                  

PU14      	RAA229126GNPHA0	          	          	                    
          	               	1         	266A2     	PVCCFA_EHV_FIVRA_CPU0_PWM1
          	               	2         	266A2     	PVCCFA_EHV_FIVRA_CPU0_PWM2
          	               	3         	266B2     	PVCCFA_EHV_FIVRA_CPU0_PWM3
          	               	4         	266B2     	PVCCFA_EHV_FIVRA_CPU0_PWM4
          	               	5         	266B2     	PVCCIN_CPU0_PWM8    
          	               	6         	266B2     	PVCCIN_CPU0_PWM7    
          	               	7         	266B2     	PVCCIN_CPU0_PWM6    
          	               	8         	266B2     	PVCCIN_CPU0_PWM5    
          	               	9         	266B2     	PVCCIN_CPU0_PWM4    
          	               	10        	266B2     	PVCCIN_CPU0_PWM3    
          	               	11        	266B2     	PVCCIN_CPU0_PWM2    
          	               	12        	266B2     	PVCCIN_CPU0_PWM1    
          	               	13        	266B3     	SMB_DIO_PVCCIN_CPU0 
          	               	14        	266B3     	SMB_CLK_PVCCIN_CPU0 
          	               	15        	266B3     	NC_PVCCIN_CPU0_SMB_ALERT
          	               	16        	266B3     	PWRGD_PVCCIN_CPU0_R 
          	               	17        	266B3     	PVCCIN_CPU0_EN_R    
          	               	18        	266A3     	IRQ_PVCCIN_CPU0_VRHOT_N
          	               	19        	266A3     	PVCCIN_CPU0_PIN_ALERT
          	               	20        	266A3     	PWRGD_PVCCFA_EHV_FIVRA_CPU0_R
          	               	21        	266B3     	SVID_CLK_PVCCIN_CPU0_R
          	               	22        	266B3     	SVID_DIO_PVCCIN_CPU0_R
          	               	23        	266B3     	SVID_ALERT_PVCCIN_CPU0_R
          	               	24        	266A3     	PVCCFA_EHV_FIVRA_CPU0_EN_R
          	               	25        	266B3     	SH_PVCCIN_CPU0_R    
          	               	26        	266B3     	VSENSE_PVCCIN_CPU0_DN
          	               	27        	266B2     	PVCCIN_CPU0_IMON1   
          	               	28        	266B2     	PVCCIN_CPU0_IMON2   
          	               	29        	266B2     	PVCCIN_CPU0_IMON3   
          	               	30        	266B2     	PVCCIN_CPU0_IMON4   
          	               	31        	266B2     	PVCCIN_CPU0_IMON5   
          	               	32        	266B2     	PVCCIN_CPU0_IMON6   
          	               	33        	266B2     	PVCCIN_CPU0_IMON7   
          	               	34        	266B2     	PVCCIN_CPU0_IMON8   
          	               	35        	266B2     	PVCCFA_EHV_FIVRA_CPU0_IMON4
          	               	36        	266A2     	PVCCFA_EHV_FIVRA_CPU0_IMON3
          	               	37        	266A2     	PVCCFA_EHV_FIVRA_CPU0_IMON2
          	               	38        	266A2     	PVCCFA_EHV_FIVRA_CPU0_IMON1
          	               	39        	266B3     	VSENSE_PVCCFA_EHV_FIVRA_CPU0_DN
          	               	40        	266B3     	SH_PVCCFA_EHV_FIVRA_CPU0_R
          	               	41        	266A3     	PVCCIN_CPU0_VR_FAULT
          	               	42        	266A3     	PVCCIN_CPU0_ADDR    
          	               	43        	266A2     	PVCCIN_CPU0_ATSEN   
          	               	44        	266A2     	PVCCFA_EHV_FIVRA_CPU0_BTSEN
          	               	45        	266A3     	PVCCIN_CPU0_CSPIN   
          	               	46        	266A3     	PVCCIN_CPU0_VIN_CSNIN
          	               	47        	266B2     	PVCCIN_CPU0_VCC     
          	               	48        	266B2     	PVCCIN_CPU0_VREF    
          	               	TH        	266A3     	GND                 

PU17      	ISL99390FRZTR5935	          	          	                    
          	               	1         	297B3     	PVCCD_HV_CPU1_VOS   
          	               	2         	297B3     	GND                 
          	               	3         	297B4     	PVCCD_HV_CPU1_VDD1  
          	               	4         	297B4     	PVCCFA_EHV_CPU1_PVCC
          	               	5         	297B3     	GND                 
          	               	6         	297B3     	NC                  
          	               	7_9-20_24 	297B3     	GND                 
          	               	10_19     	297B3     	SW_PVCCD_HV_CPU1_SW1
          	               	25_29     	297B3     	SW_P12V_PVCCINFAON_CPU1_FLT
          	               	30        	297B3     	SW_P12V_PVCCINFAON_CPU1_FLT
          	               	31        	297B4     	NC                  
          	               	32        	297B3     	SW_PVCCD_HV_CPU1_BOOTR1
          	               	33        	297B3     	SW_PVCCD_HV_CPU1_BOOT1
          	               	34        	297B4     	PVCCD_HV_CPU1_APWM1 
          	               	35        	297B4     	PVCCD_HV_CPU1_VDD1  
          	               	36        	297B4     	PVCCD_HV_CPU1_ATSEN 
          	               	37        	297B4     	PVCCD_HV_CPU1_LSET1 
          	               	38        	297B4     	PVCCD_HV_CPU1_ACSP1 
          	               	39        	297B4     	PVCCD_HV_CPU1_VREF  
          	               	40        	297B3     	GND                 
          	               	41        	297B3     	NC                  

PU18      	ISL69260IRAZT  	          	          	                    
          	               	1         	296A2     	NC_PVCCD_HV_CPU1_APWM8
          	               	2         	296A2     	NC_PVCCD_HV_CPU1_APWM7
          	               	3         	296B2     	NC_PVCCD_HV_CPU1_APWM6
          	               	4         	296B2     	NC_PVCCD_HV_CPU1_APWM5
          	               	5         	296B2     	NC_PVCCD_HV_CPU1_APWM4
          	               	6         	296B2     	NC_PVCCD_HV_CPU1_APWM3
          	               	7         	296B2     	NC_PVCCD_HV_CPU1_APWM2
          	               	8         	296B2     	PVCCD_HV_CPU1_APWM1 
          	               	9         	296B3     	SMB_DIO_PVCCD_HV_CPU1
          	               	10        	296B3     	SMB_CLK_PVCCD_HV_CPU1
          	               	11        	296B3     	NC_PVCCD_HV_CPU1_SMB_ALERT
          	               	12        	296B3     	PWRGD_PVCCD_HV_CPU1_R
          	               	13        	296B3     	PVCCD_HV_CPU1_EN_R  
          	               	14        	296A2     	IRQ_PVCCD_CPU1_VRHOT_LVC3_R_N
          	               	15        	296A3     	PVCCD_HV_CPU1_PIN_ALT
          	               	16        	296A3     	NC_PVCCD_HV_CPU1_BVR_RDY
          	               	17        	296B3     	SVID_CLK_PVCCD_HV_CPU1_R
          	               	18        	296B3     	SVID_DIO_PVCCD_HV_CPU1_R
          	               	19        	296B3     	SVID_ALERT_PVCCD_HV_CPU1_R
          	               	20        	296A3     	GND                 
          	               	21        	296B3     	SH_PVCCD_HV_CPU1_R  
          	               	22        	296B3     	VSENSE_PVCCD_HV_CPU1_DN
          	               	23        	296B2     	PVCCD_HV_CPU1_ACSP1 
          	               	24        	296B2     	NC_PVCCD_HV_CPU1_ACSP2
          	               	25        	296B2     	NC_PVCCD_HV_CPU1_ACSP3
          	               	26        	296B2     	NC_PVCCD_HV_CPU1_ACSP4
          	               	27        	296B2     	NC_PVCCD_HV_CPU1_ACSP5
          	               	28        	296B2     	NC_PVCCD_HV_CPU1_ACSP6
          	               	29        	296A2     	NC_PVCCD_HV_CPU1_ACSP7
          	               	30        	296A2     	NC_PVCCD_HV_CPU1_ACSP8
          	               	31        	296B3     	GND                 
          	               	32        	296B3     	GND                 
          	               	33        	296A3     	PVCCD_HV_CPU1_FAULT 
          	               	34        	296A3     	PVCCD_HV_CPU1_ADDR  
          	               	35        	296A2     	PVCCD_HV_CPU1_ATSEN 
          	               	36        	296A2     	PVCCD_HV_CPU1_ISYS_R
          	               	37        	296A3     	PVCCD_HV_CPU1_ISENSE_P
          	               	38        	296A3     	PVCCD_HV_CPU1_ISENSE_N
          	               	39        	296B2     	PVCCD_HV_CPU1_VCC   
          	               	40        	296B2     	PVCCD_HV_CPU1_VREF  
          	               	TH        	296A3     	GND                 

PU22      	ISL69260IRAZT  	          	          	                    
          	               	1         	292A2     	PVCCFA_EHV_CPU1_BPWM1
          	               	2         	292B2     	NC_PVCCINFAON_CPU1_APWM7
          	               	3         	292B2     	NC_PVCCINFAON_CPU1_APWM6
          	               	4         	292B2     	NC_PVCCINFAON_CPU1_APWM5
          	               	5         	292B2     	NC_PVCCINFAON_CPU1_APWM4
          	               	6         	292B2     	NC_PVCCINFAON_CPU1_APWM3
          	               	7         	292B2     	PVCCINFAON_CPU1_APWM2
          	               	8         	292B2     	PVCCINFAON_CPU1_APWM1
          	               	9         	292B3     	SMB_DIO_PVCCINFAON_CPU1
          	               	10        	292B3     	SMB_CLK_PVCCINFAON_CPU1
          	               	11        	292B3     	NC_PVCCINFAON_CPU1_SMB_ALERT
          	               	12        	292B3     	PWRGD_PVCCINFAON_CPU1_R
          	               	13        	292B3     	PVCCINFAON_CPU1_EN_R
          	               	14        	292A2     	IRQ_PVCCFA_CPU1_VRHOT_N
          	               	15        	292A3     	PVCCINFAON_CPU1_PIN_ALERT
          	               	16        	292A3     	PWRGD_PVCCFA_EHV_CPU1_R
          	               	17        	292B3     	SVID_CLK_PVCCINFAON_CPU1_R
          	               	18        	292B3     	SVID_DIO_PVCCINFAON_CPU1_R
          	               	19        	292B3     	SVID_ALERT_PVCCINFAON_CPU1_R
          	               	20        	292A3     	PVCCFA_EHV_CPU1_EN_R
          	               	21        	292B3     	SH_PVCCINFAON_CPU1_R
          	               	22        	292B3     	VSENSE_PVCCINFAON_CPU1_DN
          	               	23        	292B2     	PVCCINFAON_CPU1_ACSP1
          	               	24        	292B2     	PVCCINFAON_CPU1_ACSP2
          	               	25        	292B2     	NC_PVCCINFAON_CPU1_ACSP3
          	               	26        	292B2     	NC_PVCCINFAON_CPU1_ACSP4
          	               	27        	292B2     	NC_PVCCINFAON_CPU1_ACSP5
          	               	28        	292B2     	NC_PVCCINFAON_CPU1_ACSP6
          	               	29        	292B2     	NC_PVCCINFAON_CPU1_ACSP7
          	               	30        	292A2     	PVCCFA_EHV_CPU1_BCSP1
          	               	31        	292B3     	VSENSE_PVCCFA_EHV_CPU1_DN
          	               	32        	292B3     	SH_PVCCFA_EHV_CPU1_R
          	               	33        	292A3     	PVCCINFAON_CPU1_VR_FAULT
          	               	34        	292A3     	PVCCINFAON_CPU1_ADDR
          	               	35        	292A2     	PVCCINFAON_CPU1_ATSEN
          	               	36        	292A2     	PVCCFA_EHV_CPU1_BTSEN
          	               	37        	292A3     	PVCCINFAON_CPU1_CSPIN
          	               	38        	292A3     	PVCCINFAON_CPU1_VIN_CSNIN
          	               	39        	292B2     	PVCCINFAON_CPU1_VCC 
          	               	40        	292B2     	PVCCINFAON_CPU1_VREF
          	               	TH        	292A3     	GND                 

PU23_P1_8 	ISL99390FRZTR5935	          	          	                    
          	               	1         	288A3     	PVCCIN_CPU1_VOS8    
          	               	2         	288A3     	GND                 
          	               	3         	288A4     	PVCCIN_CPU1_VDD8    
          	               	4         	288A4     	PVCCIN_CPU1_PVCC    
          	               	5         	288A3     	GND                 
          	               	6         	288A3     	NC                  
          	               	7_9-20_24 	288A3     	GND                 
          	               	10_19     	288A3     	SW_PVCCIN_CPU1_SW8  
          	               	25_29     	288A3     	SW_P12V_PVCCIN_CPU1_FLT
          	               	30        	288A3     	SW_P12V_PVCCIN_CPU1_FLT
          	               	31        	288A4     	NC                  
          	               	32        	288A3     	SW_PVCCIN_CPU1_BOOTR8
          	               	33        	288A3     	SW_PVCCIN_CPU1_BOOT8
          	               	34        	288A4     	PVCCIN_CPU1_PWM8    
          	               	35        	288A4     	PVCCIN_CPU1_VDD8    
          	               	36        	288A4     	PVCCIN_CPU1_ATSEN   
          	               	37        	288A4     	PVCCIN_CPU1_LSET8   
          	               	38        	288A4     	PVCCIN_CPU1_IMON8   
          	               	39        	288A4     	PVCCIN_CPU1_VREF    
          	               	40        	288A3     	GND                 
          	               	41        	288A3     	NC                  

PU24_P1_7 	ISL99390FRZTR5935	          	          	                    
          	               	1         	288B3     	PVCCIN_CPU1_VOS7    
          	               	2         	288B3     	GND                 
          	               	3         	288B4     	PVCCIN_CPU1_VDD7    
          	               	4         	288B4     	PVCCIN_CPU1_PVCC    
          	               	5         	288B3     	GND                 
          	               	6         	288B3     	NC                  
          	               	7_9-20_24 	288B3     	GND                 
          	               	10_19     	288B3     	SW_PVCCIN_CPU1_SW7  
          	               	25_29     	288B3     	SW_P12V_PVCCIN_CPU1_FLT
          	               	30        	288B3     	SW_P12V_PVCCIN_CPU1_FLT
          	               	31        	288B4     	NC                  
          	               	32        	288B3     	SW_PVCCIN_CPU1_BOOTR7
          	               	33        	288B3     	SW_PVCCIN_CPU1_BOOT7
          	               	34        	288B4     	PVCCIN_CPU1_PWM7    
          	               	35        	288B4     	PVCCIN_CPU1_VDD7    
          	               	36        	288B4     	PVCCIN_CPU1_ATSEN   
          	               	37        	288B4     	PVCCIN_CPU1_LSET7   
          	               	38        	288B4     	PVCCIN_CPU1_IMON7   
          	               	39        	288B4     	PVCCIN_CPU1_VREF    
          	               	40        	288B3     	GND                 
          	               	41        	288B3     	NC                  

PU25_P1_6 	ISL99390FRZTR5935	          	          	                    
          	               	1         	287A3     	PVCCIN_CPU1_VOS6    
          	               	2         	287A3     	GND                 
          	               	3         	287A4     	PVCCIN_CPU1_VDD6    
          	               	4         	287A4     	PVCCIN_CPU1_PVCC    
          	               	5         	287A3     	GND                 
          	               	6         	287A3     	NC                  
          	               	7_9-20_24 	287A3     	GND                 
          	               	10_19     	287A3     	SW_PVCCIN_CPU1_SW6  
          	               	25_29     	287A3     	SW_P12V_PVCCIN_CPU1_FLT
          	               	30        	287A3     	SW_P12V_PVCCIN_CPU1_FLT
          	               	31        	287A4     	NC                  
          	               	32        	287A3     	SW_PVCCIN_CPU1_BOOTR6
          	               	33        	287A3     	SW_PVCCIN_CPU1_BOOT6
          	               	34        	287A4     	PVCCIN_CPU1_PWM6    
          	               	35        	287A4     	PVCCIN_CPU1_VDD6    
          	               	36        	287A4     	PVCCIN_CPU1_ATSEN   
          	               	37        	287A4     	PVCCIN_CPU1_LSET6   
          	               	38        	287A4     	PVCCIN_CPU1_IMON6   
          	               	39        	287A4     	PVCCIN_CPU1_VREF    
          	               	40        	287A3     	GND                 
          	               	41        	287A3     	NC                  

PU26_P1_5 	ISL99390FRZTR5935	          	          	                    
          	               	1         	287B3     	PVCCIN_CPU1_VOS5    
          	               	2         	287B3     	GND                 
          	               	3         	287B4     	PVCCIN_CPU1_VDD5    
          	               	4         	287B4     	PVCCIN_CPU1_PVCC    
          	               	5         	287B3     	GND                 
          	               	6         	287B3     	NC                  
          	               	7_9-20_24 	287B3     	GND                 
          	               	10_19     	287B3     	SW_PVCCIN_CPU1_SW5  
          	               	25_29     	287B3     	SW_P12V_PVCCIN_CPU1_FLT
          	               	30        	287B3     	SW_P12V_PVCCIN_CPU1_FLT
          	               	31        	287B4     	NC                  
          	               	32        	287B3     	SW_PVCCIN_CPU1_BOOTR5
          	               	33        	287B3     	SW_PVCCIN_CPU1_BOOT5
          	               	34        	287B4     	PVCCIN_CPU1_PWM5    
          	               	35        	287B4     	PVCCIN_CPU1_VDD5    
          	               	36        	287B4     	PVCCIN_CPU1_ATSEN   
          	               	37        	287B4     	PVCCIN_CPU1_LSET5   
          	               	38        	287B4     	PVCCIN_CPU1_IMON5   
          	               	39        	287B4     	PVCCIN_CPU1_VREF    
          	               	40        	287B3     	GND                 
          	               	41        	287B3     	NC                  

PU27_P1_4 	ISL99390FRZTR5935	          	          	                    
          	               	1         	286A3     	PVCCIN_CPU1_VOS4    
          	               	2         	286A3     	GND                 
          	               	3         	286A3     	PVCCIN_CPU1_VDD4    
          	               	4         	286B3     	PVCCIN_CPU1_PVCC    
          	               	5         	286A3     	GND                 
          	               	6         	286A3     	NC                  
          	               	7_9-20_24 	286A3     	GND                 
          	               	10_19     	286A3     	SW_PVCCIN_CPU1_SW4  
          	               	25_29     	286B3     	SW_P12V_PVCCIN_CPU1_FLT
          	               	30        	286A3     	SW_P12V_PVCCIN_CPU1_FLT
          	               	31        	286A3     	NC                  
          	               	32        	286A3     	SW_PVCCIN_CPU1_BOOTR4
          	               	33        	286A3     	SW_PVCCIN_CPU1_BOOT4
          	               	34        	286A3     	PVCCIN_CPU1_PWM4    
          	               	35        	286A3     	PVCCIN_CPU1_VDD4    
          	               	36        	286A3     	PVCCIN_CPU1_ATSEN   
          	               	37        	286A3     	PVCCIN_CPU1_LSET4   
          	               	38        	286A3     	PVCCIN_CPU1_IMON4   
          	               	39        	286A3     	PVCCIN_CPU1_VREF    
          	               	40        	286A3     	GND                 
          	               	41        	286A3     	NC                  

PU28_P1_3 	ISL99390FRZTR5935	          	          	                    
          	               	1         	286B3     	PVCCIN_CPU1_VOS3    
          	               	2         	286B3     	GND                 
          	               	3         	286B3     	PVCCIN_CPU1_VDD3    
          	               	4         	286B3     	PVCCIN_CPU1_PVCC    
          	               	5         	286B3     	GND                 
          	               	6         	286B3     	NC                  
          	               	7_9-20_24 	286B3     	GND                 
          	               	10_19     	286B3     	SW_PVCCIN_CPU1_SW3  
          	               	25_29     	286B3     	SW_P12V_PVCCIN_CPU1_FLT
          	               	30        	286B3     	SW_P12V_PVCCIN_CPU1_FLT
          	               	31        	286B3     	NC                  
          	               	32        	286B3     	SW_PVCCIN_CPU1_BOOTR3
          	               	33        	286B3     	SW_PVCCIN_CPU1_BOOT3
          	               	34        	286B3     	PVCCIN_CPU1_PWM3    
          	               	35        	286B3     	PVCCIN_CPU1_VDD3    
          	               	36        	286B3     	PVCCIN_CPU1_ATSEN   
          	               	37        	286B3     	PVCCIN_CPU1_LSET3   
          	               	38        	286B3     	PVCCIN_CPU1_IMON3   
          	               	39        	286B3     	PVCCIN_CPU1_VREF    
          	               	40        	286B3     	GND                 
          	               	41        	286B3     	NC                  

PU29      	RAA229126GNPHA0	          	          	                    
          	               	1         	284A2     	PVCCFA_EHV_FIVRA_CPU1_PWM1
          	               	2         	284A2     	PVCCFA_EHV_FIVRA_CPU1_PWM2
          	               	3         	284B2     	PVCCFA_EHV_FIVRA_CPU1_PWM3
          	               	4         	284B2     	PVCCFA_EHV_FIVRA_CPU1_PWM4
          	               	5         	284B2     	PVCCIN_CPU1_PWM8    
          	               	6         	284B2     	PVCCIN_CPU1_PWM7    
          	               	7         	284B2     	PVCCIN_CPU1_PWM6    
          	               	8         	284B2     	PVCCIN_CPU1_PWM5    
          	               	9         	284B2     	PVCCIN_CPU1_PWM4    
          	               	10        	284B2     	PVCCIN_CPU1_PWM3    
          	               	11        	284B2     	PVCCIN_CPU1_PWM2    
          	               	12        	284B2     	PVCCIN_CPU1_PWM1    
          	               	13        	284B3     	SMB_DIO_PVCCIN_CPU1 
          	               	14        	284B3     	SMB_CLK_PVCCIN_CPU1 
          	               	15        	284B3     	NC_PVCCIN_CPU1_SMB_ALERT
          	               	16        	284B3     	PWRGD_PVCCIN_CPU1_R 
          	               	17        	284B3     	PVCCIN_CPU1_EN_R    
          	               	18        	284A3     	IRQ_PVCCIN_CPU1_VRHOT_N
          	               	19        	284A3     	PVCCIN_CPU1_PIN_ALERT
          	               	20        	284A3     	PWRGD_PVCCFA_EHV_FIVRA_CPU1_R
          	               	21        	284B3     	SVID_CLK_PVCCIN_CPU1_R
          	               	22        	284B3     	SVID_DIO_PVCCIN_CPU1_R
          	               	23        	284B3     	SVID_ALERT_PVCCIN_CPU1_R
          	               	24        	284A3     	PVCCFA_EHV_FIVRA_CPU1_EN_R
          	               	25        	284B3     	SH_PVCCIN_CPU1_R    
          	               	26        	284B3     	VSENSE_PVCCIN_CPU1_DN
          	               	27        	284B2     	PVCCIN_CPU1_IMON1   
          	               	28        	284B2     	PVCCIN_CPU1_IMON2   
          	               	29        	284B2     	PVCCIN_CPU1_IMON3   
          	               	30        	284B2     	PVCCIN_CPU1_IMON4   
          	               	31        	284B2     	PVCCIN_CPU1_IMON5   
          	               	32        	284B2     	PVCCIN_CPU1_IMON6   
          	               	33        	284B2     	PVCCIN_CPU1_IMON7   
          	               	34        	284B2     	PVCCIN_CPU1_IMON8   
          	               	35        	284B2     	PVCCFA_EHV_FIVRA_CPU1_IMON4
          	               	36        	284A2     	PVCCFA_EHV_FIVRA_CPU1_IMON3
          	               	37        	284A2     	PVCCFA_EHV_FIVRA_CPU1_IMON2
          	               	38        	284A2     	PVCCFA_EHV_FIVRA_CPU1_IMON1
          	               	39        	284B3     	VSENSE_PVCCFA_EHV_FIVRA_CPU1_DN
          	               	40        	284B3     	SH_PVCCFA_EHV_FIVRA_CPU1_R
          	               	41        	284A3     	PVCCIN_CPU1_VR_FAULT
          	               	42        	284A3     	PVCCIN_CPU1_ADDR    
          	               	43        	284A2     	PVCCIN_CPU1_ATSEN   
          	               	44        	284A2     	PVCCFA_EHV_FIVRA_CPU1_BTSEN
          	               	45        	284A3     	PVCCIN_CPU1_CSPIN   
          	               	46        	284A3     	PVCCIN_CPU1_VIN_CSNIN
          	               	47        	284B2     	PVCCIN_CPU1_VCC     
          	               	48        	284B2     	PVCCIN_CPU1_VREF    
          	               	TH        	284A3     	GND                 

PU30_P1_2 	ISL99390FRZTR5935	          	          	                    
          	               	1         	285A4     	PVCCIN_CPU1_VOS2    
          	               	2         	285A4     	GND                 
          	               	3         	285A4     	PVCCIN_CPU1_VDD2    
          	               	4         	285A4     	PVCCIN_CPU1_PVCC    
          	               	5         	285A4     	GND                 
          	               	6         	285A4     	NC                  
          	               	7_9-20_24 	285A4     	GND                 
          	               	10_19     	285A4     	SW_PVCCIN_CPU1_SW2  
          	               	25_29     	285A4     	SW_P12V_PVCCIN_CPU1_FLT
          	               	30        	285A4     	SW_P12V_PVCCIN_CPU1_FLT
          	               	31        	285A4     	NC                  
          	               	32        	285A4     	SW_PVCCIN_CPU1_BOOTR2
          	               	33        	285A4     	SW_PVCCIN_CPU1_BOOT2
          	               	34        	285A4     	PVCCIN_CPU1_PWM2    
          	               	35        	285A4     	PVCCIN_CPU1_VDD2    
          	               	36        	285A4     	PVCCIN_CPU1_ATSEN   
          	               	37        	285A4     	PVCCIN_CPU1_LSET2   
          	               	38        	285A4     	PVCCIN_CPU1_IMON2   
          	               	39        	285A4     	PVCCIN_CPU1_VREF    
          	               	40        	285A4     	GND                 
          	               	41        	285A4     	NC                  

PU31_P1_1 	ISL99390FRZTR5935	          	          	                    
          	               	1         	285B4     	PVCCIN_CPU1_VOS1    
          	               	2         	285B4     	GND                 
          	               	3         	285B4     	PVCCIN_CPU1_VDD1    
          	               	4         	285B4     	PVCCIN_CPU1_PVCC    
          	               	5         	285B4     	GND                 
          	               	6         	285B4     	NC                  
          	               	7_9-20_24 	285B4     	GND                 
          	               	10_19     	285B4     	SW_PVCCIN_CPU1_SW1  
          	               	25_29     	285B4     	SW_P12V_PVCCIN_CPU1_FLT
          	               	30        	285B4     	SW_P12V_PVCCIN_CPU1_FLT
          	               	31        	285B4     	NC                  
          	               	32        	285B4     	SW_PVCCIN_CPU1_BOOTR1
          	               	33        	285B4     	SW_PVCCIN_CPU1_BOOT1
          	               	34        	285B4     	PVCCIN_CPU1_PWM1    
          	               	35        	285B4     	PVCCIN_CPU1_VDD1    
          	               	36        	285B4     	PVCCIN_CPU1_ATSEN   
          	               	37        	285B4     	PVCCIN_CPU1_LSET1   
          	               	38        	285B4     	PVCCIN_CPU1_IMON1   
          	               	39        	285B4     	PVCCIN_CPU1_VREF    
          	               	40        	285B4     	GND                 
          	               	41        	285B4     	NC                  

PU35      	ISL69260IRAZT  	          	          	                    
          	               	1         	278A2     	NC_PVCCD_HV_CPU0_APWM8
          	               	2         	278A2     	NC_PVCCD_HV_CPU0_APWM7
          	               	3         	278B2     	NC_PVCCD_HV_CPU0_APWM6
          	               	4         	278B2     	NC_PVCCD_HV_CPU0_APWM5
          	               	5         	278B2     	NC_PVCCD_HV_CPU0_APWM4
          	               	6         	278B2     	NC_PVCCD_HV_CPU0_APWM3
          	               	7         	278B2     	NC_PVCCD_HV_CPU0_APWM2
          	               	8         	278B2     	PVCCD_HV_CPU0_APWM1 
          	               	9         	278B3     	SMB_DIO_PVCCD_HV_CPU0
          	               	10        	278B3     	SMB_CLK_PVCCD_HV_CPU0
          	               	11        	278B3     	NC_PVCCD_HV_CPU0_SMB_ALERT
          	               	12        	278B3     	PWRGD_PVCCD_HV_CPU0_R
          	               	13        	278B3     	PVCCD_HV_CPU0_EN_R  
          	               	14        	278A2     	IRQ_PVCCD_CPU0_VRHOT_LVC3_R_N
          	               	15        	278A3     	PVCCD_HV_CPU0_PIN_ALT
          	               	16        	278A3     	NC_PVCCD_HV_CPU0_BVR_RDY
          	               	17        	278B3     	SVID_CLK_PVCCD_HV_CPU0_R
          	               	18        	278B3     	SVID_DIO_PVCCD_HV_CPU0_R
          	               	19        	278B3     	SVID_ALERT_PVCCD_HV_CPU0_R
          	               	20        	278A3     	GND                 
          	               	21        	278B3     	SH_PVCCD_HV_CPU0_R  
          	               	22        	278B3     	VSENSE_PVCCD_HV_CPU0_DN
          	               	23        	278B2     	PVCCD_HV_CPU0_ACSP1 
          	               	24        	278B2     	NC_PVCCD_HV_CPU0_ACSP2
          	               	25        	278B2     	NC_PVCCD_HV_CPU0_ACSP3
          	               	26        	278B2     	NC_PVCCD_HV_CPU0_ACSP4
          	               	27        	278B2     	NC_PVCCD_HV_CPU0_ACSP5
          	               	28        	278B2     	NC_PVCCD_HV_CPU0_ACSP6
          	               	29        	278A2     	NC_PVCCD_HV_CPU0_ACSP7
          	               	30        	278A2     	NC_PVCCD_HV_CPU0_ACSP8
          	               	31        	278B3     	GND                 
          	               	32        	278B3     	GND                 
          	               	33        	278A3     	PVCCD_HV_CPU0_FAULT 
          	               	34        	278A3     	PVCCD_HV_CPU0_ADDR  
          	               	35        	278A2     	PVCCD_HV_CPU0_ATSEN 
          	               	36        	278A2     	PVCCD_HV_CPU0_ISYS_R
          	               	37        	278A3     	PVCCD_HV_CPU0_ISENSE_P
          	               	38        	278A3     	PVCCD_HV_CPU0_ISENSE_N
          	               	39        	278B2     	PVCCD_HV_CPU0_VCC   
          	               	40        	278B2     	PVCCD_HV_CPU0_VREF  
          	               	TH        	278A3     	GND                 

PU36      	ISL99390FRZTR5935	          	          	                    
          	               	1         	279B4     	PVCCD_HV_CPU0_VOS   
          	               	2         	279B4     	GND                 
          	               	3         	279B4     	PVCCD_HV_CPU0_VDD1  
          	               	4         	279B4     	PVCCFA_EHV_CPU0_PVCC
          	               	5         	279B4     	GND                 
          	               	6         	279B4     	NC                  
          	               	7_9-20_24 	279B4     	GND                 
          	               	10_19     	279B4     	SW_PVCCD_HV_CPU0_SW1
          	               	25_29     	279B4     	SW_P12V_PVCCINFAON_CPU0_FLT
          	               	30        	279B4     	SW_P12V_PVCCINFAON_CPU0_FLT
          	               	31        	279B4     	NC                  
          	               	32        	279B4     	SW_PVCCD_HV_CPU0_BOOTR1
          	               	33        	279B4     	SW_PVCCD_HV_CPU0_BOOT1
          	               	34        	279B4     	PVCCD_HV_CPU0_APWM1 
          	               	35        	279B4     	PVCCD_HV_CPU0_VDD1  
          	               	36        	279B4     	PVCCD_HV_CPU0_ATSEN 
          	               	37        	279B4     	PVCCD_HV_CPU0_LSET1 
          	               	38        	279B4     	PVCCD_HV_CPU0_ACSP1 
          	               	39        	279B4     	PVCCD_HV_CPU0_VREF  
          	               	40        	279B4     	GND                 
          	               	41        	279B4     	NC                  

PU42      	RAA2213404GNPHB0	          	          	                    
          	               	1         	276B4     	PVCCFA_EHV_CPU0_BTSEN
          	               	2         	276B3     	PVCCFA_EHV_CPU0_FAULT
          	               	3         	276B3     	PVCCFA_EHV_CPU0_NC1 
          	               	4         	276B4     	PVCCFA_EHV_CPU0_VDD1
          	               	5         	276B4     	PVCCFA_EHV_CPU0_LSET1
          	               	6_7-13_15-29	276B3     	GND                 
          	               	8_12      	276B3     	SW_PVCCFA_EHV_CPU0_SW1
          	               	16_18-28  	276B3     	SW_P12V_PVCCINFAON_CPU0_FLT
          	               	19        	276B3     	SW_PVCCFA_EHV_CPU0_BOOTR1
          	               	20        	276B3     	SW_PVCCFA_EHV_CPU0_BOOT1
          	               	21        	276B4     	PVCCFA_EHV_CPU0_BPWM1
          	               	22        	276B4     	PVCCFA_EHV_CPU0_NC2 
          	               	23        	276B3     	GND                 
          	               	24        	276B4     	PVCCINFAON_CPU0_VREF
          	               	25        	276B4     	PVCCFA_EHV_CPU0_BCSP1
          	               	26        	276B3     	GND                 
          	               	27        	276B4     	NC                  

PU43_P0_1 	ISL99390FRZTR5935	          	          	                    
          	               	1         	275B4     	PVCCINFAON_CPU0_VOS1
          	               	2         	275B4     	GND                 
          	               	3         	275B4     	PVCCINFAON_CPU0_VDD1
          	               	4         	275B4     	PVCCFA_EHV_CPU0_PVCC
          	               	5         	275B4     	GND                 
          	               	6         	275B4     	NC                  
          	               	7_9-20_24 	275B4     	GND                 
          	               	10_19     	275B4     	SW_PVCCINFAON_CPU0_SW1
          	               	25_29     	275B4     	SW_P12V_PVCCINFAON_CPU0_FLT
          	               	30        	275B4     	SW_P12V_PVCCINFAON_CPU0_FLT
          	               	31        	275B4     	NC                  
          	               	32        	275B4     	SW_PVCCINFAON_CPU0_BOOTR1
          	               	33        	275B4     	SW_PVCCINFAON_CPU0_BOOT1
          	               	34        	275B4     	PVCCINFAON_CPU0_APWM1
          	               	35        	275B4     	PVCCINFAON_CPU0_VDD1
          	               	36        	275B4     	PVCCINFAON_CPU0_ATSEN
          	               	37        	275B4     	PVCCINFAON_CPU0_LSET1
          	               	38        	275B4     	PVCCINFAON_CPU0_ACSP1
          	               	39        	275B4     	PVCCINFAON_CPU0_VREF
          	               	40        	275B4     	GND                 
          	               	41        	275B4     	NC                  

PU44_P0_2 	ISL99390FRZTR5935	          	          	                    
          	               	1         	275A4     	PVCCINFAON_CPU0_VOS2
          	               	2         	275A4     	GND                 
          	               	3         	275A4     	PVCCINFAON_CPU0_VDD2
          	               	4         	275A4     	PVCCFA_EHV_CPU0_PVCC
          	               	5         	275A4     	GND                 
          	               	6         	275A4     	NC                  
          	               	7_9-20_24 	275A4     	GND                 
          	               	10_19     	275A4     	SW_PVCCINFAON_CPU0_SW2
          	               	25_29     	275A4     	SW_P12V_PVCCINFAON_CPU0_FLT
          	               	30        	275A4     	SW_P12V_PVCCINFAON_CPU0_FLT
          	               	31        	275A4     	NC                  
          	               	32        	275A4     	SW_PVCCINFAON_CPU0_BOOTR2
          	               	33        	275A4     	SW_PVCCINFAON_CPU0_BOOT2
          	               	34        	275A4     	PVCCINFAON_CPU0_APWM2
          	               	35        	275A4     	PVCCINFAON_CPU0_VDD2
          	               	36        	275A4     	PVCCINFAON_CPU0_ATSEN
          	               	37        	275A4     	PVCCINFAON_CPU0_LSET2
          	               	38        	275A4     	PVCCINFAON_CPU0_ACSP2
          	               	39        	275A4     	PVCCINFAON_CPU0_VREF
          	               	40        	275A4     	GND                 
          	               	41        	275A4     	NC                  

PU49      	RAA2213404GNPHB0	          	          	                    
          	               	1         	294B4     	PVCCFA_EHV_CPU1_BTSEN
          	               	2         	294B3     	PVCCFA_EHV_CPU1_FAULT
          	               	3         	294B3     	PVCCFA_EHV_CPU1_NC1 
          	               	4         	294B4     	PVCCFA_EHV_CPU1_VDD1
          	               	5         	294B4     	PVCCFA_EHV_CPU1_LSET1
          	               	6_7-13_15-29	294B3     	GND                 
          	               	8_12      	294B3     	SW_PVCCFA_EHV_CPU1_SW1
          	               	16_18-28  	294B3     	SW_P12V_PVCCINFAON_CPU1_FLT
          	               	19        	294B3     	SW_PVCCFA_EHV_CPU1_BOOTR1
          	               	20        	294B3     	SW_PVCCFA_EHV_CPU1_BOOT1
          	               	21        	294B4     	PVCCFA_EHV_CPU1_BPWM1
          	               	22        	294B4     	PVCCFA_EHV_CPU1_NC2 
          	               	23        	294B3     	GND                 
          	               	24        	294B4     	PVCCINFAON_CPU1_VREF
          	               	25        	294B4     	PVCCFA_EHV_CPU1_BCSP1
          	               	26        	294B3     	GND                 
          	               	27        	294B4     	NC                  

PU50_P1_1 	ISL99390FRZTR5935	          	          	                    
          	               	1         	293B4     	PVCCINFAON_CPU1_VOS1
          	               	2         	293B4     	GND                 
          	               	3         	293B4     	PVCCINFAON_CPU1_VDD1
          	               	4         	293B4     	PVCCFA_EHV_CPU1_PVCC
          	               	5         	293B4     	GND                 
          	               	6         	293B4     	NC                  
          	               	7_9-20_24 	293B4     	GND                 
          	               	10_19     	293B4     	SW_PVCCINFAON_CPU1_SW1
          	               	25_29     	293B4     	SW_P12V_PVCCINFAON_CPU1_FLT
          	               	30        	293B4     	SW_P12V_PVCCINFAON_CPU1_FLT
          	               	31        	293B4     	NC                  
          	               	32        	293B4     	SW_PVCCINFAON_CPU1_BOOTR1
          	               	33        	293B4     	SW_PVCCINFAON_CPU1_BOOT1
          	               	34        	293B4     	PVCCINFAON_CPU1_APWM1
          	               	35        	293B4     	PVCCINFAON_CPU1_VDD1
          	               	36        	293B4     	PVCCINFAON_CPU1_ATSEN
          	               	37        	293B4     	PVCCINFAON_CPU1_LSET1
          	               	38        	293B4     	PVCCINFAON_CPU1_ACSP1
          	               	39        	293B4     	PVCCINFAON_CPU1_VREF
          	               	40        	293B4     	GND                 
          	               	41        	293B4     	NC                  

PU51_P1_2 	ISL99390FRZTR5935	          	          	                    
          	               	1         	293A4     	PVCCINFAON_CPU1_VOS2
          	               	2         	293A4     	GND                 
          	               	3         	293A4     	PVCCINFAON_CPU1_VDD2
          	               	4         	293A4     	PVCCFA_EHV_CPU1_PVCC
          	               	5         	293A4     	GND                 
          	               	6         	293A4     	NC                  
          	               	7_9-20_24 	293A4     	GND                 
          	               	10_19     	293A4     	SW_PVCCINFAON_CPU1_SW2
          	               	25_29     	293A4     	SW_P12V_PVCCINFAON_CPU1_FLT
          	               	30        	293A4     	SW_P12V_PVCCINFAON_CPU1_FLT
          	               	31        	293A4     	NC                  
          	               	32        	293A4     	SW_PVCCINFAON_CPU1_BOOTR2
          	               	33        	293A4     	SW_PVCCINFAON_CPU1_BOOT2
          	               	34        	293A4     	PVCCINFAON_CPU1_APWM2
          	               	35        	293A4     	PVCCINFAON_CPU1_VDD2
          	               	36        	293A4     	PVCCINFAON_CPU1_ATSEN
          	               	37        	293A4     	PVCCINFAON_CPU1_LSET2
          	               	38        	293A4     	PVCCINFAON_CPU1_ACSP2
          	               	39        	293A4     	PVCCINFAON_CPU1_VREF
          	               	40        	293A4     	GND                 
          	               	41        	293A4     	NC                  

PU69_P0_1 	ISL99390FRZTR5935	          	          	                    
          	               	1         	271B4     	PVCCFA_EHV_FIVRA_CPU0_VOS1
          	               	2         	271B4     	GND                 
          	               	3         	271B4     	PVCCFA_EHV_FIVRA_CPU0_VDD1
          	               	4         	271B4     	PVCCFA_EHV_FIVRA_CPU0_PVCC1
          	               	5         	271B4     	GND                 
          	               	6         	271B4     	NC                  
          	               	7_9-20_24 	271B4     	GND                 
          	               	10_19     	271B4     	SW_PVCCFA_EHV_FIVRA_CPU0_SW1
          	               	25_29     	271B4     	SW_P12V_PVCCFA_EHV_FIVRA_CPU0_R
          	               	30        	271B4     	SW_P12V_PVCCFA_EHV_FIVRA_CPU0_R
          	               	31        	271B4     	NC                  
          	               	32        	271B4     	SW_PVCCFA_EHV_FIVRA_CPU0_BOOTR1
          	               	33        	271B4     	SW_PVCCFA_EHV_FIVRA_CPU0_BOOT1
          	               	34        	271B4     	PVCCFA_EHV_FIVRA_CPU0_PWM1
          	               	35        	271B4     	PVCCFA_EHV_FIVRA_CPU0_VDD1
          	               	36        	271B4     	PVCCFA_EHV_FIVRA_CPU0_BTSEN
          	               	37        	271B4     	PVCCFA_EHV_FIVRA_CPU0_LSET1
          	               	38        	271B4     	PVCCFA_EHV_FIVRA_CPU0_IMON1
          	               	39        	271B4     	PVCCIN_CPU0_VREF    
          	               	40        	271B4     	GND                 
          	               	41        	271B4     	NC                  

PU70_P0_2 	ISL99390FRZTR5935	          	          	                    
          	               	1         	271A4     	PVCCFA_EHV_FIVRA_CPU0_VOS2
          	               	2         	271A4     	GND                 
          	               	3         	271A4     	PVCCFA_EHV_FIVRA_CPU0_VDD2
          	               	4         	271A4     	PVCCFA_EHV_FIVRA_CPU0_PVCC2
          	               	5         	271A4     	GND                 
          	               	6         	271A4     	NC                  
          	               	7_9-20_24 	271A4     	GND                 
          	               	10_19     	271A4     	SW_PVCCFA_EHV_FIVRA_CPU0_SW2
          	               	25_29     	271A4     	SW_P12V_PVCCFA_EHV_FIVRA_CPU0_L
          	               	30        	271A4     	SW_P12V_PVCCFA_EHV_FIVRA_CPU0_L
          	               	31        	271A4     	NC                  
          	               	32        	271A4     	SW_PVCCFA_EHV_FIVRA_CPU0_BOOTR2
          	               	33        	271A4     	SW_PVCCFA_EHV_FIVRA_CPU0_BOOT2
          	               	34        	271A4     	PVCCFA_EHV_FIVRA_CPU0_PWM2
          	               	35        	271A4     	PVCCFA_EHV_FIVRA_CPU0_VDD2
          	               	36        	271A4     	PVCCFA_EHV_FIVRA_CPU0_BTSEN
          	               	37        	271A4     	PVCCFA_EHV_FIVRA_CPU0_LSET2
          	               	38        	271A4     	PVCCFA_EHV_FIVRA_CPU0_IMON2
          	               	39        	271A4     	PVCCIN_CPU0_VREF    
          	               	40        	271A4     	GND                 
          	               	41        	271A4     	NC                  

PU71_P0_3 	ISL99390FRZTR5935	          	          	                    
          	               	1         	272B4     	PVCCFA_EHV_FIVRA_CPU0_VOS3
          	               	2         	272B4     	GND                 
          	               	3         	272B4     	PVCCFA_EHV_FIVRA_CPU0_VDD3
          	               	4         	272B4     	PVCCFA_EHV_FIVRA_CPU0_PVCC1
          	               	5         	272B4     	GND                 
          	               	6         	272B4     	NC                  
          	               	7_9-20_24 	272B4     	GND                 
          	               	10_19     	272B4     	SW_PVCCFA_EHV_FIVRA_CPU0_SW3
          	               	25_29     	272B4     	SW_P12V_PVCCFA_EHV_FIVRA_CPU0_R
          	               	30        	272B4     	SW_P12V_PVCCFA_EHV_FIVRA_CPU0_R
          	               	31        	272B4     	NC                  
          	               	32        	272B4     	SW_PVCCFA_EHV_FIVRA_CPU0_BOOTR3
          	               	33        	272B4     	SW_PVCCFA_EHV_FIVRA_CPU0_BOOT3
          	               	34        	272B4     	PVCCFA_EHV_FIVRA_CPU0_PWM3
          	               	35        	272B4     	PVCCFA_EHV_FIVRA_CPU0_VDD3
          	               	36        	272B4     	PVCCFA_EHV_FIVRA_CPU0_BTSEN
          	               	37        	272B4     	PVCCFA_EHV_FIVRA_CPU0_LSET3
          	               	38        	272B4     	PVCCFA_EHV_FIVRA_CPU0_IMON3
          	               	39        	272B4     	PVCCIN_CPU0_VREF    
          	               	40        	272B4     	GND                 
          	               	41        	272B4     	NC                  

PU72_P0_4 	ISL99390FRZTR5935	          	          	                    
          	               	1         	272A4     	PVCCFA_EHV_FIVRA_CPU0_VOS4
          	               	2         	272A4     	GND                 
          	               	3         	272A4     	PVCCFA_EHV_FIVRA_CPU0_VDD4
          	               	4         	272B4     	PVCCFA_EHV_FIVRA_CPU0_PVCC2
          	               	5         	272A4     	GND                 
          	               	6         	272A4     	NC                  
          	               	7_9-20_24 	272A4     	GND                 
          	               	10_19     	272A4     	SW_PVCCFA_EHV_FIVRA_CPU0_SW4
          	               	25_29     	272B4     	SW_P12V_PVCCFA_EHV_FIVRA_CPU0_L
          	               	30        	272A4     	SW_P12V_PVCCFA_EHV_FIVRA_CPU0_L
          	               	31        	272A4     	NC                  
          	               	32        	272A4     	SW_PVCCFA_EHV_FIVRA_CPU0_BOOTR4
          	               	33        	272A4     	SW_PVCCFA_EHV_FIVRA_CPU0_BOOT4
          	               	34        	272A4     	PVCCFA_EHV_FIVRA_CPU0_PWM4
          	               	35        	272A4     	PVCCFA_EHV_FIVRA_CPU0_VDD4
          	               	36        	272A4     	PVCCFA_EHV_FIVRA_CPU0_BTSEN
          	               	37        	272A4     	PVCCFA_EHV_FIVRA_CPU0_LSET4
          	               	38        	272A4     	PVCCFA_EHV_FIVRA_CPU0_IMON4
          	               	39        	272A4     	PVCCIN_CPU0_VREF    
          	               	40        	272A4     	GND                 
          	               	41        	272A4     	NC                  

PU73      	RS53319LR      	          	          	                    
          	               	1         	262B3     	SW_P1V05_PCH_AUX_BST
          	               	2         	262A3     	GND                 
          	               	3         	262A3     	P1V05_PCH_AUX_CS    
          	               	4         	262B3     	P1V05_PCH_AUX_MODE  
          	               	5         	262A3     	P1V05_PCH_AUX_REF   
          	               	6         	262A3     	SH_P1V05_PCH_AUX_N  
          	               	7         	262B3     	P1V05_PCH_AUX_FB    
          	               	8         	262B3     	FM_P1V05_PCH_AUX_R_EN
          	               	9         	262B3     	PWRGD_P1V05_PCH_AUX_R
          	               	10        	262B3     	SW_P12V_AUX_P1V05_PCH_AUX_FLT
          	               	11_18     	262A3     	GND                 
          	               	19        	262B3     	P1V05_PCH_AUX_VCC   
          	               	20        	262B3     	SW_P1V05_PCH_AUX_SW 
          	               	21        	262B3     	SW_P12V_AUX_P1V05_PCH_AUX_FLT

PU74      	NB682GDZ       	          	          	                    
          	               	1         	263B3     	SW_P1V8_PCH_AUX_FLT 
          	               	2         	263A3     	GND                 
          	               	3         	263B3     	P1V8_PCH_AUX_VCC    
          	               	4         	263B3     	GND                 
          	               	5         	263B3     	FM_PCH_P1V8_AUX_EN_R
          	               	6         	263B3     	P1V8_PCH_AUX_VCC    
          	               	7         	263A3     	P1V8_PCH_AUX_MODE   
          	               	8         	263B3     	SW_P1V8_PCH_AUX_SW  
          	               	9         	263B3     	SW_P1V8_PCH_AUX_BST 
          	               	10        	263B3     	P1V8_PCH_AUX_VCC    
          	               	11        	263A3     	GND                 
          	               	12        	263B3     	P1V8_PCH_AUX        
          	               	13        	263B3     	PWRGD_P1V8_PCH_AUX_R

PU75_P1_1 	ISL99390FRZTR5935	          	          	                    
          	               	1         	289B4     	PVCCFA_EHV_FIVRA_CPU1_VOS1
          	               	2         	289B4     	GND                 
          	               	3         	289B4     	PVCCFA_EHV_FIVRA_CPU1_VDD1
          	               	4         	289B4     	PVCCFA_EHV_FIVRA_CPU1_PVCC1
          	               	5         	289B4     	GND                 
          	               	6         	289B4     	NC                  
          	               	7_9-20_24 	289B4     	GND                 
          	               	10_19     	289B4     	SW_PVCCFA_EHV_FIVRA_CPU1_SW1
          	               	25_29     	289B4     	SW_P12V_PVCCFA_EHV_FIVRA_CPU1_R
          	               	30        	289B4     	SW_P12V_PVCCFA_EHV_FIVRA_CPU1_R
          	               	31        	289B4     	NC                  
          	               	32        	289B4     	SW_PVCCFA_EHV_FIVRA_CPU1_BOOTR1
          	               	33        	289B4     	SW_PVCCFA_EHV_FIVRA_CPU1_BOOT1
          	               	34        	289B4     	PVCCFA_EHV_FIVRA_CPU1_PWM1
          	               	35        	289B4     	PVCCFA_EHV_FIVRA_CPU1_VDD1
          	               	36        	289B4     	PVCCFA_EHV_FIVRA_CPU1_BTSEN
          	               	37        	289B4     	PVCCFA_EHV_FIVRA_CPU1_LSET1
          	               	38        	289B4     	PVCCFA_EHV_FIVRA_CPU1_IMON1
          	               	39        	289B4     	PVCCIN_CPU1_VREF    
          	               	40        	289B4     	GND                 
          	               	41        	289B4     	NC                  

PU76_P1_2 	ISL99390FRZTR5935	          	          	                    
          	               	1         	289A4     	PVCCFA_EHV_FIVRA_CPU1_VOS2
          	               	2         	289A4     	GND                 
          	               	3         	289A4     	PVCCFA_EHV_FIVRA_CPU1_VDD2
          	               	4         	289A4     	PVCCFA_EHV_FIVRA_CPU1_PVCC2
          	               	5         	289A4     	GND                 
          	               	6         	289A4     	NC                  
          	               	7_9-20_24 	289A4     	GND                 
          	               	10_19     	289A4     	SW_PVCCFA_EHV_FIVRA_CPU1_SW2
          	               	25_29     	289A4     	SW_P12V_PVCCFA_EHV_FIVRA_CPU1_L
          	               	30        	289A4     	SW_P12V_PVCCFA_EHV_FIVRA_CPU1_L
          	               	31        	289A4     	NC                  
          	               	32        	289A4     	SW_PVCCFA_EHV_FIVRA_CPU1_BOOTR2
          	               	33        	289A4     	SW_PVCCFA_EHV_FIVRA_CPU1_BOOT2
          	               	34        	289A4     	PVCCFA_EHV_FIVRA_CPU1_PWM2
          	               	35        	289A4     	PVCCFA_EHV_FIVRA_CPU1_VDD2
          	               	36        	289A4     	PVCCFA_EHV_FIVRA_CPU1_BTSEN
          	               	37        	289A4     	PVCCFA_EHV_FIVRA_CPU1_LSET2
          	               	38        	289A4     	PVCCFA_EHV_FIVRA_CPU1_IMON2
          	               	39        	289A4     	PVCCIN_CPU1_VREF    
          	               	40        	289A4     	GND                 
          	               	41        	289A4     	NC                  

PU77_P1_3 	ISL99390FRZTR5935	          	          	                    
          	               	1         	290B4     	PVCCFA_EHV_FIVRA_CPU1_VOS3
          	               	2         	290B4     	GND                 
          	               	3         	290B4     	PVCCFA_EHV_FIVRA_CPU1_VDD3
          	               	4         	290B4     	PVCCFA_EHV_FIVRA_CPU1_PVCC1
          	               	5         	290B4     	GND                 
          	               	6         	290B4     	NC                  
          	               	7_9-20_24 	290B4     	GND                 
          	               	10_19     	290B4     	SW_PVCCFA_EHV_FIVRA_CPU1_SW3
          	               	25_29     	290B4     	SW_P12V_PVCCFA_EHV_FIVRA_CPU1_R
          	               	30        	290B4     	SW_P12V_PVCCFA_EHV_FIVRA_CPU1_R
          	               	31        	290B4     	NC                  
          	               	32        	290B4     	SW_PVCCFA_EHV_FIVRA_CPU1_BOOTR3
          	               	33        	290B4     	SW_PVCCFA_EHV_FIVRA_CPU1_BOOT3
          	               	34        	290B4     	PVCCFA_EHV_FIVRA_CPU1_PWM3
          	               	35        	290B4     	PVCCFA_EHV_FIVRA_CPU1_VDD3
          	               	36        	290B4     	PVCCFA_EHV_FIVRA_CPU1_BTSEN
          	               	37        	290B4     	PVCCFA_EHV_FIVRA_CPU1_LSET3
          	               	38        	290B4     	PVCCFA_EHV_FIVRA_CPU1_IMON3
          	               	39        	290B4     	PVCCIN_CPU1_VREF    
          	               	40        	290B4     	GND                 
          	               	41        	290B4     	NC                  

PU78_P1_4 	ISL99390FRZTR5935	          	          	                    
          	               	1         	290A4     	PVCCFA_EHV_FIVRA_CPU1_VOS4
          	               	2         	290A4     	GND                 
          	               	3         	290A4     	PVCCFA_EHV_FIVRA_CPU1_VDD4
          	               	4         	290B4     	PVCCFA_EHV_FIVRA_CPU1_PVCC2
          	               	5         	290A4     	GND                 
          	               	6         	290A4     	NC                  
          	               	7_9-20_24 	290A4     	GND                 
          	               	10_19     	290A4     	SW_PVCCFA_EHV_FIVRA_CPU1_SW4
          	               	25_29     	290B4     	SW_P12V_PVCCFA_EHV_FIVRA_CPU1_L
          	               	30        	290B4     	SW_P12V_PVCCFA_EHV_FIVRA_CPU1_L
          	               	31        	290A4     	NC                  
          	               	32        	290A4     	SW_PVCCFA_EHV_FIVRA_CPU1_BOOTR4
          	               	33        	290A4     	SW_PVCCFA_EHV_FIVRA_CPU1_BOOT4
          	               	34        	290A4     	PVCCFA_EHV_FIVRA_CPU1_PWM4
          	               	35        	290A4     	PVCCFA_EHV_FIVRA_CPU1_VDD4
          	               	36        	290A4     	PVCCFA_EHV_FIVRA_CPU1_BTSEN
          	               	37        	290A4     	PVCCFA_EHV_FIVRA_CPU1_LSET4
          	               	38        	290A4     	PVCCFA_EHV_FIVRA_CPU1_IMON4
          	               	39        	290A4     	PVCCIN_CPU1_VREF    
          	               	40        	290A4     	GND                 
          	               	41        	290A4     	NC                  

PU79      	RS53318LR      	          	          	                    
          	               	1         	281B3     	SW_PVPP_HBM_CPU0_BST
          	               	2         	281A3     	GND                 
          	               	3         	281A3     	PVPP_HBM_CPU0_CS    
          	               	4         	281B3     	PVPP_HBM_CPU0_MODE  
          	               	5         	281A3     	PVPP_HBM_CPU0_REF   
          	               	6         	281A3     	SH_PVPP_HBM_CPU0_N  
          	               	7         	281B3     	PVPP_HBM_CPU0_FB    
          	               	8         	281B3     	FM_PVPP_HBM_CPU0_EN 
          	               	9         	281B3     	PWRGD_PVPP_HBM_CPU0_R
          	               	10        	281B3     	SW_P12V_PVCCIN_CPU0_FLT
          	               	11_18     	281A3     	GND                 
          	               	19        	281B3     	PVPP_HBM_CPU0_VCC   
          	               	20        	281B3     	SW_PVPP_HBM_CPU0_SW 
          	               	21        	281B3     	SW_P12V_PVCCIN_CPU0_FLT

PU80      	RS53318LR      	          	          	                    
          	               	1         	299B3     	SW_PVPP_HBM_CPU1_BST
          	               	2         	299A3     	GND                 
          	               	3         	299A4     	PVPP_HBM_CPU1_CS    
          	               	4         	299B4     	PVPP_HBM_CPU1_MODE  
          	               	5         	299B3     	PVPP_HBM_CPU1_REF   
          	               	6         	299B3     	SH_PVPP_HBM_CPU1_N  
          	               	7         	299B3     	PVPP_HBM_CPU1_FB    
          	               	8         	299B4     	FM_PVPP_HBM_CPU1_EN 
          	               	9         	299B3     	PWRGD_PVPP_HBM_CPU1_R
          	               	10        	299B4     	SW_P12V_PVCCIN_CPU1_FLT
          	               	11_18     	299A3     	GND                 
          	               	19        	299B4     	PVPP_HBM_CPU1_VCC   
          	               	20        	299B3     	SW_PVPP_HBM_CPU1_SW 
          	               	21        	299B4     	SW_P12V_PVCCIN_CPU1_FLT

PU81      	RS53317LR      	          	          	                    
          	               	1         	282A3     	GND                 
          	               	2         	282B3     	SW_PVNN_MAIN_CPU0_SW
          	               	3         	282B4     	SW_P12V_PVCCINFAON_CPU0_FLT
          	               	4         	282A4     	PVNN_MAIN_CPU0_CS   
          	               	5         	282B4     	FM_PVNN_MAIN_CPU0_EN
          	               	6         	282B3     	PVNN_MAIN_CPU0_FB   
          	               	7         	282A3     	GND                 
          	               	8         	282A3     	PVNN_MAIN_CPU0_REF  
          	               	9         	282B3     	PWRGD_PVNN_MAIN_CPU0_R
          	               	10        	282B3     	SW_PVNN_MAIN_CPU0_BST
          	               	11        	282B3     	SW_PVNN_MAIN_CPU0_SW
          	               	12        	282B4     	PVNN_MAIN_CPU0_MODE 
          	               	13        	282B4     	PVNN_MAIN_CPU0_VCC  
          	               	14        	282A3     	GND                 

PU82      	RS53317LR      	          	          	                    
          	               	1         	300A3     	GND                 
          	               	2         	300B3     	SW_PVNN_MAIN_CPU1_SW
          	               	3         	300B3     	SW_P12V_PVCCINFAON_CPU1_FLT
          	               	4         	300A3     	PVNN_MAIN_CPU1_CS   
          	               	5         	300B3     	FM_PVNN_MAIN_CPU1_EN
          	               	6         	300A3     	PVNN_MAIN_CPU1_FB   
          	               	7         	300A3     	GND                 
          	               	8         	300A3     	PVNN_MAIN_CPU1_REF  
          	               	9         	300B3     	PWRGD_PVNN_MAIN_CPU1_R
          	               	10        	300B3     	SW_PVNN_MAIN_CPU1_BST
          	               	11        	300B3     	SW_PVNN_MAIN_CPU1_SW
          	               	12        	300B3     	PVNN_MAIN_CPU1_MODE 
          	               	13        	300A3     	PVNN_MAIN_CPU1_VCC  
          	               	14        	300A3     	GND                 

PU173     	MOSFET_N_SMLF  	          	          	                    
          	               	D         	281A2     	FM_HBM_VPP_SEL_CPU0_D
          	               	G         	281A2     	FM_HBM2_HBM3_VPP_SEL
          	               	S         	281A2     	SH_PVPP_HBM_CPU0_N  

PU174     	MOSFET_N_SMLF  	          	          	                    
          	               	D         	299A2     	FM_HBM_VPP_SEL_CPU1_D
          	               	G         	299A2     	FM_HBM2_HBM3_VPP_SEL
          	               	S         	299A2     	SH_PVPP_HBM_CPU1_N  

PU181     	RS53318LR      	          	          	                    
          	               	1         	258B3     	SW_P5V_AUX_BST      
          	               	2         	258A3     	GND                 
          	               	3         	258A4     	P5V_AUX_CS          
          	               	4         	258B4     	P5V_AUX_MODE        
          	               	5         	258A3     	P5V_AUX_REF         
          	               	6         	258B3     	GND                 
          	               	7         	258B3     	P5V_AUX_FB          
          	               	8         	258B4     	PWRGD_P3V3_AUX      
          	               	9         	258B3     	PWRGD_P5V_AUX_R     
          	               	10        	258B4     	SW_P5V_AUX_FLT      
          	               	11_18     	258A3     	GND                 
          	               	19        	258B4     	P5V_AUX_VCC         
          	               	20        	258B3     	SW_P5V_AUX_SW       
          	               	21        	258B4     	SW_P5V_AUX_FLT      

PU200     	MAX15090BEWIT  	          	          	                    
          	               	A1        	162B2     	P3V3_OCP_SENSE_2    
          	               	A2        	162B2     	P3V3_OCP_VCC_2      
          	               	A3        	162B2     	P3V3_AUX            
          	               	A4        	162B2     	P3V3_OCP_V3_2_R     
          	               	A5        	162B2     	P3V3_AUX            
          	               	A6        	162B2     	P3V3_OCP_GATE_2     
          	               	A7        	162B2     	GND                 
          	               	B1        	162B2     	P3V3_OCP_CB_2       
          	               	B2        	162B2     	GND                 
          	               	B3        	162B2     	P3V3_AUX            
          	               	B4        	162B2     	P3V3_OCP_V3_2_R     
          	               	B5        	162B2     	P3V3_AUX            
          	               	B6        	162B2     	P3V3_OCP_V3_2_R     
          	               	B7        	162B2     	GND                 
          	               	C1        	162B2     	GND                 
          	               	C2        	162B2     	GND                 
          	               	C3        	162B2     	P3V3_AUX            
          	               	C4        	162B2     	P3V3_OCP_V3_2_R     
          	               	C5        	162B2     	P3V3_AUX            
          	               	C6        	162B2     	P3V3_OCP_V3_2_R     
          	               	C7        	162B2     	P3V3_OCP_FAULT_2    
          	               	D1        	162B2     	P3V3_OCP_REG_2      
          	               	D2        	162B2     	P3V3_OCP_UV_2       
          	               	D3        	162B2     	P3V3_OCP_OV_2       
          	               	D4        	162B2     	P3V3_OCP_V3_2_R     
          	               	D5        	162B2     	P3V3_AUX            
          	               	D6        	162B2     	P3V3_OCP_V3_2_R     
          	               	D7        	162B2     	P3V3_OCP_PWRGD_2    

PU201     	MAX15090BEWIT  	          	          	                    
          	               	A1        	162B2     	P12V_OCP_SENSE_2    
          	               	A2        	162B2     	P12V_OCP_VCC_2      
          	               	A3        	162B2     	P12V_AUX            
          	               	A4        	162B2     	P12V_OCP_V3_2       
          	               	A5        	162B2     	P12V_AUX            
          	               	A6        	162B2     	P12V_OCP_GATE_2     
          	               	A7        	162B2     	GND                 
          	               	B1        	162B2     	P12V_OCP_CB_2       
          	               	B2        	162A2     	GND                 
          	               	B3        	162B2     	P12V_AUX            
          	               	B4        	162B2     	P12V_OCP_V3_2       
          	               	B5        	162B2     	P12V_AUX            
          	               	B6        	162B2     	P12V_OCP_V3_2       
          	               	B7        	162A2     	GND                 
          	               	C1        	162A2     	GND                 
          	               	C2        	162A2     	GND                 
          	               	C3        	162B2     	P12V_AUX            
          	               	C4        	162B2     	P12V_OCP_V3_2       
          	               	C5        	162B2     	P12V_AUX            
          	               	C6        	162B2     	P12V_OCP_V3_2       
          	               	C7        	162B2     	P12V_OCP_FAULT_2    
          	               	D1        	162B2     	P12V_OCP_REG_2      
          	               	D2        	162B2     	P12V_OCP_UV_2       
          	               	D3        	162B2     	P12V_OCP_OV_2       
          	               	D4        	162B2     	P12V_OCP_V3_2       
          	               	D5        	162B2     	P12V_AUX            
          	               	D6        	162B2     	P12V_OCP_V3_2       
          	               	D7        	162B2     	P12V_OCP_PWRGD_2    

PU202     	MAX15090BEWIT  	          	          	                    
          	               	A1        	156B2     	P3V3_OCP_SENSE_1    
          	               	A2        	156B2     	P3V3_OCP_VCC_1      
          	               	A3        	156B2     	P3V3_AUX            
          	               	A4        	156B2     	P3V3_OCP_SFF_R      
          	               	A5        	156B2     	P3V3_AUX            
          	               	A6        	156B2     	P3V3_OCP_GATE_PU202_1
          	               	A7        	156B2     	GND                 
          	               	B1        	156B2     	P3V3_OCP_CB_1       
          	               	B2        	156B2     	GND                 
          	               	B3        	156B2     	P3V3_AUX            
          	               	B4        	156B2     	P3V3_OCP_SFF_R      
          	               	B5        	156B2     	P3V3_AUX            
          	               	B6        	156B2     	P3V3_OCP_SFF_R      
          	               	B7        	156B2     	GND                 
          	               	C1        	156B2     	GND                 
          	               	C2        	156B2     	GND                 
          	               	C3        	156B2     	P3V3_AUX            
          	               	C4        	156B2     	P3V3_OCP_SFF_R      
          	               	C5        	156B2     	P3V3_AUX            
          	               	C6        	156B2     	P3V3_OCP_SFF_R      
          	               	C7        	156B2     	P3V3_OCP_FAULT_1    
          	               	D1        	156B2     	P3V3_OCP_REG_1      
          	               	D2        	156B2     	P3V3_OCP_UV_1       
          	               	D3        	156B2     	P3V3_OCP_OV_1       
          	               	D4        	156B2     	P3V3_OCP_SFF_R      
          	               	D5        	156B2     	P3V3_AUX            
          	               	D6        	156B2     	P3V3_OCP_SFF_R      
          	               	D7        	156B2     	P3V3_OCP_PWRGD_1    

PU203     	MAX15090BEWIT  	          	          	                    
          	               	A1        	156B2     	P12V_OCP_SENSE_1    
          	               	A2        	156B2     	P12V_OCP_VCC_1      
          	               	A3        	156B2     	P12V_AUX            
          	               	A4        	156B2     	P12V_OCP_SFF        
          	               	A5        	156B2     	P12V_AUX            
          	               	A6        	156B2     	P12V_OCP_GATE_1     
          	               	A7        	156B2     	GND                 
          	               	B1        	156B2     	P12V_OCP_CB_1       
          	               	B2        	156A2     	GND                 
          	               	B3        	156B2     	P12V_AUX            
          	               	B4        	156B2     	P12V_OCP_SFF        
          	               	B5        	156B2     	P12V_AUX            
          	               	B6        	156B2     	P12V_OCP_SFF        
          	               	B7        	156A2     	GND                 
          	               	C1        	156A2     	GND                 
          	               	C2        	156A2     	GND                 
          	               	C3        	156B2     	P12V_AUX            
          	               	C4        	156B2     	P12V_OCP_SFF        
          	               	C5        	156B2     	P12V_AUX            
          	               	C6        	156B2     	P12V_OCP_SFF        
          	               	C7        	156B2     	P12V_OCP_FAULT_1    
          	               	D1        	156B2     	P12V_OCP_REG_1      
          	               	D2        	156B2     	P12V_OCP_UV_1       
          	               	D3        	156B2     	P12V_OCP_OV_1       
          	               	D4        	156B2     	P12V_OCP_SFF        
          	               	D5        	156B2     	P12V_AUX            
          	               	D6        	156B2     	P12V_OCP_SFF        
          	               	D7        	156B2     	P12V_OCP_PWRGD_1    

PU204     	RS31312R       	          	          	                    
          	               	1         	157A4     	P12V_OCP_EN_1_R2    
          	               	2         	157A4     	GND                 
          	               	3         	157A4     	GND                 
          	               	4         	157A4     	P12V_OCP_TIMER_1    
          	               	5         	157A4     	P12V_OCP_ISET_1     
          	               	6         	157A4     	P12V_OCP_SS_1       
          	               	7         	157A4     	GND                 
          	               	8         	157A3     	P12V_OCP_IMON_1     
          	               	9         	157A3     	P12V_OCP_FLTB_1     
          	               	10        	157A3     	HP_LVC3_OCP_V3_1_P12V_PWRGD
          	               	11        	157A3     	P12V_OCP_OV_FB_1    
          	               	12        	157A3     	P12V_OCP_AVIN_PD_1  
          	               	13        	157A3     	P12V_OCP_SFF        
          	               	14        	157A3     	P12V_OCP_SFF        
          	               	15        	157A3     	P12V_OCP_SFF        
          	               	16        	157A3     	P12V_OCP_SFF        
          	               	17        	157A3     	P12V_OCP_SFF        
          	               	18        	157A3     	P12V_OCP_SFF        
          	               	19        	157A3     	P12V_OCP_SFF        
          	               	20        	157A3     	P12V_OCP_SFF        
          	               	21_22     	157A4     	P12V_AUX            
          	               	23        	157A4     	P12V_AUX            
          	               	24        	157A4     	P12V_AUX            
          	               	25        	157A4     	P12V_AUX            
          	               	26        	157A4     	P12V_AUX            

PU205     	MP5016GQHLZ    	          	          	                    
          	               	1_2       	157B2     	P3V3_AUX            
          	               	3         	157B1     	GND                 
          	               	4         	157B2     	P3V3_OCP_ILIMIT_1   
          	               	5         	157B2     	P3V3_OCP_MODE_1     
          	               	6_7       	157B1     	P3V3_OCP_SFF_R      
          	               	8         	157B1     	P3V3_OCP_GATE_1     
          	               	9         	157B2     	P3V3_OCP_EN_1_R2    
          	               	10        	157B2     	P3V3_OCP_DVDT_1     

PU206     	RS31312R       	          	          	                    
          	               	1         	163A4     	P12V_OCP_V3_2_EN_2_R3
          	               	2         	163A4     	GND                 
          	               	3         	163A4     	GND                 
          	               	4         	163A4     	P12V_OCP_TIMER_2    
          	               	5         	163A4     	P12V_OCP_ISET_2     
          	               	6         	163A4     	P12V_OCP_SS_2       
          	               	7         	163A4     	GND                 
          	               	8         	163A3     	P12V_OCP_IMON_2     
          	               	9         	163A3     	P12V_OCP_FLTB_2     
          	               	10        	163A3     	HP_LVC3_OCP_V3_2_P12V_PWRGD
          	               	11        	163A3     	P12V_OCP_OV_FB_2    
          	               	12        	163A3     	P12V_OCP_AVIN_PD_2  
          	               	13        	163A3     	P12V_OCP_V3_2       
          	               	14        	163A3     	P12V_OCP_V3_2       
          	               	15        	163A3     	P12V_OCP_V3_2       
          	               	16        	163A3     	P12V_OCP_V3_2       
          	               	17        	163A3     	P12V_OCP_V3_2       
          	               	18        	163A3     	P12V_OCP_V3_2       
          	               	19        	163A3     	P12V_OCP_V3_2       
          	               	20        	163A3     	P12V_OCP_V3_2       
          	               	21_22     	163A4     	P12V_AUX            
          	               	23        	163A4     	P12V_AUX            
          	               	24        	163A4     	P12V_AUX            
          	               	25        	163A4     	P12V_AUX            
          	               	26        	163A4     	P12V_AUX            

PU207     	MP5016GQHLZ    	          	          	                    
          	               	1_2       	163B2     	P3V3_AUX            
          	               	3         	163B1     	GND                 
          	               	4         	163B2     	P3V3_OCP_ILIMIT_2   
          	               	5         	163B2     	P3V3_OCP_MODE_2     
          	               	6_7       	163B1     	P3V3_OCP_V3_2_R     
          	               	8         	163B1     	P3V3_OCP_GATE_PU207_2
          	               	9         	163B2     	P3V3_OCP_EN_2       
          	               	10        	163B2     	P3V3_OCP_DVDT_2     

PU287     	MP5991GLUZ     	          	          	                    
          	               	1         	302B3     	P12V_AUX            
          	               	2         	302B3     	P12V_AUX            
          	               	3         	302B3     	HSC_D_OC_1          
          	               	4         	302B3     	HSC_ON              
          	               	5         	302B3     	HSC_FAULT           
          	               	6         	302B3     	HSC_FLT_TYPE_1      
          	               	7         	302B3     	HSC_NC1_1           
          	               	8         	302B3     	HSC_MODE_1          
          	               	9         	302B3     	P12V_PSU            
          	               	10        	302B3     	P12V_PSU            
          	               	11        	302B3     	P12V_PSU            
          	               	12        	302B3     	P12V_PSU            
          	               	13        	302B3     	P12V_PSU            
          	               	14        	302B3     	P12V_PSU            
          	               	15        	302B3     	P12V_PSU            
          	               	16        	302B3     	P12V_PSU            
          	               	17        	302B3     	HSC_SCREF_1         
          	               	18        	302B3     	HSC_VTEMP           
          	               	19        	302B3     	HSC_SS              
          	               	20        	302B3     	AGND_HSC            
          	               	21        	302B3     	HSC_VDD_R_1         
          	               	22        	302B3     	HSC_IMON            
          	               	23        	302B3     	HSC_CS_1            
          	               	24        	302B3     	HSC_OCREF           
          	               	25        	302B3     	P12V_AUX            
          	               	26        	302B3     	P12V_AUX            
          	               	27        	302B3     	P12V_AUX            
          	               	28        	302B3     	P12V_AUX            
          	               	29        	302B3     	P12V_AUX            
          	               	30        	302B3     	P12V_AUX            
          	               	31        	302B3     	P12V_AUX            
          	               	32        	302B3     	P12V_AUX            
          	               	33        	302B3     	P12V_PSU            

PU288     	MP5991GLUZ     	          	          	                    
          	               	1         	302B3     	P12V_AUX            
          	               	2         	302B3     	P12V_AUX            
          	               	3         	302A3     	HSC_D_OC_2          
          	               	4         	302A3     	HSC_ON              
          	               	5         	302A3     	HSC_FAULT           
          	               	6         	302A3     	HSC_FLT_TYPE_2      
          	               	7         	302A3     	HSC_NC1_2           
          	               	8         	302A3     	HSC_MODE_2          
          	               	9         	302B3     	P12V_PSU            
          	               	10        	302B3     	P12V_PSU            
          	               	11        	302B3     	P12V_PSU            
          	               	12        	302B3     	P12V_PSU            
          	               	13        	302A3     	P12V_PSU            
          	               	14        	302A3     	P12V_PSU            
          	               	15        	302A3     	P12V_PSU            
          	               	16        	302A3     	P12V_PSU            
          	               	17        	302A3     	HSC_SCREF_2         
          	               	18        	302A3     	HSC_VTEMP           
          	               	19        	302A3     	HSC_SS              
          	               	20        	302A3     	AGND_HSC            
          	               	21        	302A3     	HSC_VDD_R_2         
          	               	22        	302A3     	HSC_IMON            
          	               	23        	302A3     	HSC_CS_2            
          	               	24        	302A3     	HSC_OCREF           
          	               	25        	302B3     	P12V_AUX            
          	               	26        	302B3     	P12V_AUX            
          	               	27        	302A3     	P12V_AUX            
          	               	28        	302A3     	P12V_AUX            
          	               	29        	302A3     	P12V_AUX            
          	               	30        	302A3     	P12V_AUX            
          	               	31        	302A3     	P12V_AUX            
          	               	32        	302A3     	P12V_AUX            
          	               	33        	302A3     	P12V_PSU            

PU289     	MP5990GMA1111Z 	          	          	                    
          	               	1         	301B3     	P12V_PSU            
          	               	2         	301B3     	P12V_PSU            
          	               	3         	301B3     	P12V_PSU            
          	               	4         	301B3     	P12V_PSU            
          	               	5         	301B3     	P12V_PSU            
          	               	6         	301B3     	P12V_PSU            
          	               	7         	301B3     	P12V_PSU            
          	               	8         	301B3     	P12V_PSU            
          	               	9         	301B3     	HSC_VSENSE          
          	               	10        	301B3     	IRQ_SML1_PMBUS_ALERT
          	               	11        	301B3     	SMB_SML1_PMBUS_HSC_L_SCL
          	               	12        	301B3     	SMB_SML1_PMBUS_HSC_R_SDA
          	               	13        	301B2     	MB0_P12V_STBY_PWRGD 
          	               	14        	301B3     	HSC_VIN_UVW_N       
          	               	15        	301B2     	HSC_VTEMP           
          	               	16        	301B2     	HSC_SS              
          	               	17        	301B3     	HSC_VDD_R           
          	               	18        	301B3     	AGND_HSC            
          	               	19        	301B3     	HSC_VDD18           
          	               	20        	301B2     	HSC_CS              
          	               	21        	301B2     	HSC_IMON            
          	               	22        	301B2     	HSC_OCREF           
          	               	23        	301B3     	HSC_ADDR            
          	               	24        	301B2     	HSC_VOSEN           
          	               	25        	301B2     	HSC_SCREF           
          	               	26        	301B3     	HSC_EN_R            
          	               	27        	301B2     	P12V_AUX            
          	               	28        	301B2     	P12V_AUX            
          	               	29        	301B2     	P12V_AUX            
          	               	30        	301B2     	P12V_AUX            
          	               	31        	301B2     	P12V_AUX            
          	               	32        	301B2     	P12V_AUX            
          	               	33        	301B2     	P12V_AUX            
          	               	34        	301B2     	P12V_AUX            
          	               	35        	301B2     	P12V_AUX            
          	               	36        	301B2     	P12V_AUX            
          	               	37        	301B2     	HSC_D_OC_R          
          	               	38        	301B3     	HSC_ON_R            
          	               	39        	301B2     	HSC_FAULT           
          	               	40        	301B2     	HSC_FLT_TYPE        
          	               	41        	301B2     	HSC_MODE            
          	               	42        	301B3     	P12V_PSU            
          	               	43        	301B3     	P12V_PSU            
          	               	44        	301B3     	AGND_HSC            
          	               	45        	301B3     	HSC_VDD_R           

PU292     	RS31312R       	          	          	                    
          	               	1         	193B3     	P12V_E1S_EN_0_R2    
          	               	2         	193B3     	GND                 
          	               	3         	193B3     	GND                 
          	               	4         	193B3     	P12V_E1S_TIMER_0    
          	               	5         	193B3     	P12V_E1S_ISET_0     
          	               	6         	193B3     	P12V_E1S_SS_0       
          	               	7         	193B3     	GND                 
          	               	8         	193B3     	P12V_E1S_IMON_0     
          	               	9         	193B3     	P12V_E1S_FLTB_0     
          	               	10        	193B3     	HP_LVC3_E1S_0_HSC_PWRGD
          	               	11        	193B3     	P12V_E1S_OV_FB_0    
          	               	12        	193B3     	P12V_E1S_AVIN_PD_0  
          	               	13        	193B3     	P12V_E1S_0          
          	               	14        	193B3     	P12V_E1S_0          
          	               	15        	193B3     	P12V_E1S_0          
          	               	16        	193B3     	P12V_E1S_0          
          	               	17        	193B3     	P12V_E1S_0          
          	               	18        	193B3     	P12V_E1S_0          
          	               	19        	193B3     	P12V_E1S_0          
          	               	20        	193B3     	P12V_E1S_0          
          	               	21_22     	193B3     	P12V_AUX            
          	               	23        	193B3     	P12V_AUX            
          	               	24        	193B3     	P12V_AUX            
          	               	25        	193B3     	P12V_AUX            
          	               	26        	193B3     	P12V_AUX            

PU293     	MP5016GQHLZ    	          	          	                    
          	               	1_2       	193A3     	P3V3_AUX            
          	               	3         	193A2     	GND                 
          	               	4         	193A3     	P3V3_E1S_ILIMIT_0   
          	               	5         	193A3     	P3V3_E1S_MODE_0     
          	               	6_7       	193A2     	P3V3_E1S_0_R        
          	               	8         	193A2     	P3V3_E1S_GATE_0_PU293
          	               	9         	193A3     	P3V3_E1S_EN_0_R2    
          	               	10        	193A3     	P3V3_E1S_DVDT_0     

PU294     	MAX15090BEWIT  	          	          	                    
          	               	A1        	192B2     	P12V_E1S_SENSE_0    
          	               	A2        	192B2     	P12V_E1S_VCC_0      
          	               	A3        	192B2     	P12V_AUX            
          	               	A4        	192B2     	P12V_E1S_0          
          	               	A5        	192B2     	P12V_AUX            
          	               	A6        	192B2     	P12V_E1S_GATE_0     
          	               	A7        	192B2     	GND                 
          	               	B1        	192B2     	P12V_E1S_CB_0       
          	               	B2        	192B2     	GND                 
          	               	B3        	192B2     	P12V_AUX            
          	               	B4        	192B2     	P12V_E1S_0          
          	               	B5        	192B2     	P12V_AUX            
          	               	B6        	192B2     	P12V_E1S_0          
          	               	B7        	192B2     	GND                 
          	               	C1        	192B2     	GND                 
          	               	C2        	192B2     	GND                 
          	               	C3        	192B2     	P12V_AUX            
          	               	C4        	192B2     	P12V_E1S_0          
          	               	C5        	192B2     	P12V_AUX            
          	               	C6        	192B2     	P12V_E1S_0          
          	               	C7        	192B2     	P12V_E1S_FAULT_0    
          	               	D1        	192B2     	P12V_E1S_REG_0      
          	               	D2        	192B2     	P12V_E1S_UV_0       
          	               	D3        	192B2     	P12V_E1S_OV_0       
          	               	D4        	192B2     	P12V_E1S_0          
          	               	D5        	192B2     	P12V_AUX            
          	               	D6        	192B2     	P12V_E1S_0          
          	               	D7        	192B2     	P12V_E1S_PWRGD_0    

PU295     	MAX15090BEWIT  	          	          	                    
          	               	A1        	192A2     	P3V3_E1S_SENSE_0    
          	               	A2        	192A2     	P3V3_E1S_VCC_0      
          	               	A3        	192A2     	P3V3_AUX            
          	               	A4        	192A2     	P3V3_E1S_0_R        
          	               	A5        	192A2     	P3V3_AUX            
          	               	A6        	192A2     	P3V3_E1S_GATE_0     
          	               	A7        	192A2     	GND                 
          	               	B1        	192A2     	P3V3_E1S_CB_0       
          	               	B2        	192A2     	GND                 
          	               	B3        	192A2     	P3V3_AUX            
          	               	B4        	192A2     	P3V3_E1S_0_R        
          	               	B5        	192A2     	P3V3_AUX            
          	               	B6        	192A2     	P3V3_E1S_0_R        
          	               	B7        	192A2     	GND                 
          	               	C1        	192A2     	GND                 
          	               	C2        	192A2     	GND                 
          	               	C3        	192A2     	P3V3_AUX            
          	               	C4        	192A2     	P3V3_E1S_0_R        
          	               	C5        	192A2     	P3V3_AUX            
          	               	C6        	192A2     	P3V3_E1S_0_R        
          	               	C7        	192A2     	P3V3_E1S_FAULT_0    
          	               	D1        	192A2     	P3V3_E1S_REG_0      
          	               	D2        	192A2     	P3V3_E1S_UV_0       
          	               	D3        	192A2     	P3V3_E1S_OV_0       
          	               	D4        	192A2     	P3V3_E1S_0_R        
          	               	D5        	192A2     	P3V3_AUX            
          	               	D6        	192A2     	P3V3_E1S_0_R        
          	               	D7        	192A2     	P3V3_E1S_PWRGD_0    

PU296     	MP5991GLUZ     	          	          	                    
          	               	1         	303B3     	P12V_AUX            
          	               	2         	303B3     	P12V_AUX            
          	               	3         	303B3     	HSC_D_OC_3          
          	               	4         	303B3     	HSC_ON              
          	               	5         	303B3     	HSC_FAULT           
          	               	6         	303B3     	HSC_FLT_TYPE_3      
          	               	7         	303B3     	HSC_NC1_3           
          	               	8         	303B3     	HSC_MODE_3          
          	               	9         	303B3     	P12V_PSU            
          	               	10        	303B3     	P12V_PSU            
          	               	11        	303B3     	P12V_PSU            
          	               	12        	303B3     	P12V_PSU            
          	               	13        	303B3     	P12V_PSU            
          	               	14        	303B3     	P12V_PSU            
          	               	15        	303B3     	P12V_PSU            
          	               	16        	303B3     	P12V_PSU            
          	               	17        	303B3     	HSC_SCREF_3         
          	               	18        	303B3     	HSC_VTEMP           
          	               	19        	303B3     	HSC_SS              
          	               	20        	303B3     	AGND_HSC            
          	               	21        	303B3     	HSC_VDD_R_3         
          	               	22        	303B3     	HSC_IMON            
          	               	23        	303B3     	HSC_CS_3            
          	               	24        	303B3     	HSC_OCREF           
          	               	25        	303B3     	P12V_AUX            
          	               	26        	303B3     	P12V_AUX            
          	               	27        	303B3     	P12V_AUX            
          	               	28        	303B3     	P12V_AUX            
          	               	29        	303B3     	P12V_AUX            
          	               	30        	303B3     	P12V_AUX            
          	               	31        	303B3     	P12V_AUX            
          	               	32        	303B3     	P12V_AUX            
          	               	33        	303B3     	P12V_PSU            

PU297     	MP5991GLUZ     	          	          	                    
          	               	1         	303B3     	P12V_AUX            
          	               	2         	303B3     	P12V_AUX            
          	               	3         	303A3     	HSC_D_OC_4          
          	               	4         	303A3     	HSC_ON              
          	               	5         	303A3     	HSC_FAULT           
          	               	6         	303A3     	HSC_FLT_TYPE_4      
          	               	7         	303A3     	HSC_NC1_4           
          	               	8         	303A3     	HSC_MODE_4          
          	               	9         	303B3     	P12V_PSU            
          	               	10        	303B3     	P12V_PSU            
          	               	11        	303B3     	P12V_PSU            
          	               	12        	303B3     	P12V_PSU            
          	               	13        	303B3     	P12V_PSU            
          	               	14        	303B3     	P12V_PSU            
          	               	15        	303B3     	P12V_PSU            
          	               	16        	303B3     	P12V_PSU            
          	               	17        	303A3     	HSC_SCREF_4         
          	               	18        	303A3     	HSC_VTEMP           
          	               	19        	303A3     	HSC_SS              
          	               	20        	303A3     	AGND_HSC            
          	               	21        	303A3     	HSC_VDD_R_4         
          	               	22        	303A3     	HSC_IMON            
          	               	23        	303A3     	HSC_CS_4            
          	               	24        	303A3     	HSC_OCREF           
          	               	25        	303B3     	P12V_AUX            
          	               	26        	303B3     	P12V_AUX            
          	               	27        	303B3     	P12V_AUX            
          	               	28        	303B3     	P12V_AUX            
          	               	29        	303B3     	P12V_AUX            
          	               	30        	303B3     	P12V_AUX            
          	               	31        	303A3     	P12V_AUX            
          	               	32        	303A3     	P12V_AUX            
          	               	33        	303A3     	P12V_PSU            

PU299     	RS31312R       	          	          	                    
          	               	1         	242A3     	P12V_SCM_EN_R2      
          	               	2         	242A3     	GND                 
          	               	3         	242A3     	GND                 
          	               	4         	242A3     	P12V_SCM_TIMER      
          	               	5         	242A3     	P12V_SCM_ISET       
          	               	6         	242A3     	P12V_SCM_SS         
          	               	7         	242A3     	GND                 
          	               	8         	242A2     	P12V_SCM_IMON       
          	               	9         	242A2     	P12V_SCM_FLTB_N     
          	               	10        	242A2     	HP_LVC3_SCM_HSC_PWRGD_R
          	               	11        	242A2     	P12V_SCM_OV_FB      
          	               	12        	242A2     	P12V_SCM_AVIN_PD    
          	               	13        	242A2     	P12V_SCM_R          
          	               	14        	242A2     	P12V_SCM_R          
          	               	15        	242A2     	P12V_SCM_R          
          	               	16        	242A2     	P12V_SCM_R          
          	               	17        	242A2     	P12V_SCM_R          
          	               	18        	242A2     	P12V_SCM_R          
          	               	19        	242A2     	P12V_SCM_R          
          	               	20        	242A2     	P12V_SCM_R          
          	               	21_22     	242A3     	P12V_AUX            
          	               	23        	242A3     	P12V_AUX            
          	               	24        	242A3     	P12V_AUX            
          	               	25        	242A3     	P12V_AUX            
          	               	26        	242A3     	P12V_AUX            

PU300     	MAX15090BEWIT  	          	          	                    
          	               	A1        	242B2     	P12V_SCM_SENSE      
          	               	A2        	242B2     	P12V_SCM_VCC        
          	               	A3        	242B2     	P12V_AUX            
          	               	A4        	242B2     	P12V_SCM_R          
          	               	A5        	242B2     	P12V_AUX            
          	               	A6        	242B2     	P12V_SCM_GATE       
          	               	A7        	242B2     	GND                 
          	               	B1        	242B2     	P12V_SCM_CB         
          	               	B2        	242B2     	GND                 
          	               	B3        	242B2     	P12V_AUX            
          	               	B4        	242B2     	P12V_SCM_R          
          	               	B5        	242B2     	P12V_AUX            
          	               	B6        	242B2     	P12V_SCM_R          
          	               	B7        	242B2     	GND                 
          	               	C1        	242B2     	GND                 
          	               	C2        	242B2     	GND                 
          	               	C3        	242B2     	P12V_AUX            
          	               	C4        	242B2     	P12V_SCM_R          
          	               	C5        	242B2     	P12V_AUX            
          	               	C6        	242B2     	P12V_SCM_R          
          	               	C7        	242B2     	P12V_SCM_FAULT_N    
          	               	D1        	242B2     	P12V_SCM_REG        
          	               	D2        	242B2     	P12V_SCM_UV         
          	               	D3        	242B2     	P12V_SCM_OV         
          	               	D4        	242B2     	P12V_SCM_R          
          	               	D5        	242B2     	P12V_AUX            
          	               	D6        	242B2     	P12V_SCM_R          
          	               	D7        	242B2     	P12V_SCM_PWRGD      

Q15       	MOSFET_NCH_DUAL	          	          	                    
          	               	1         	235A2     	GND                 
          	               	2         	235A2     	FM_SMB_PEHPCPU0_PCIE_ALERT_R_N
          	               	3         	235A2     	FM_PEHPCPU0_ALERT_N 
          	               	4         	235A2     	GND                 
          	               	5         	235A2     	FM_SMB_CPU0_ALERT_R1
          	               	6         	235A2     	FM_SMB_CPU0_ALERT_R1

Q16       	MOSFET_NCH_DUAL	          	          	                    
          	               	1         	235A2     	GND                 
          	               	2         	235A2     	FM_SMB_PEHPCPU1_PCIE_ALERT_R_N
          	               	3         	235A2     	FM_PEHPCPU1_ALERT_N 
          	               	4         	235A2     	GND                 
          	               	5         	235A2     	FM_SMB_CPU1_ALERT_R1
          	               	6         	235A2     	FM_SMB_CPU1_ALERT_R1

Q33       	MOSFET_NCH_GDS_ESD_PROTECTED	          	          	                    
          	               	D         	218A3     	LED_CPU_RMCA_CATERR 
          	               	G         	218A3     	CPU_RMCA_CATERR_LVT3_N
          	               	S         	218A3     	LED_CPU_RMCA_CATERR_R

Q34       	MOSFET_NCH_GDS_ESD_PROTECTED	          	          	                    
          	               	D         	185A4     	RST_RTCRST_N        
          	               	G         	185A4     	RST_PFR_OVR_RTC     
          	               	S         	185A4     	GND                 

Q35       	MOSFET_NCH_GDS_ESD_PROTECTED	          	          	                    
          	               	D         	185A4     	RST_SRTCRST_N       
          	               	G         	185A4     	RST_PFR_OVR_SRTC    
          	               	S         	185A4     	GND                 

Q37       	MOSFET_NCH_DUAL	          	          	                    
          	               	1         	260B4     	GND                 
          	               	2         	260B4     	VR_P5V_EN           
          	               	3         	260B3     	VR_P5V_EN_D_R1      
          	               	4         	260B3     	GND                 
          	               	5         	260B4     	VR_P5V_EN_N         
          	               	6         	260B4     	VR_P5V_EN_N         

Q39       	MOSFET_NCH_GDS_ESD_PROTECTED	          	          	                    
          	               	D         	242B4     	P12V_SCM_EN         
          	               	G         	242B4     	FM_SCM_PRSNT1_R_N   
          	               	S         	242B4     	GND                 

Q46       	MOSFET_NCH_GDS_ESD_PROTECTED	          	          	                    
          	               	D         	191B2     	E1S_0_PRSNT         
          	               	G         	191B2     	E1S_0_PRSNT_N       
          	               	S         	191A2     	GND                 

Q50       	MOSFET_NCH_DUAL	          	          	                    
          	               	1         	213A4     	GND                 
          	               	2         	213A4     	PWRGD_P5V_AUX       
          	               	3         	213B4     	PWRGD_P5V_AUX_R2    
          	               	4         	213A4     	GND                 
          	               	5         	213A4     	PWRGD_P5V_AUX_R1    
          	               	6         	213B4     	PWRGD_P5V_AUX_R1    

Q52       	MOSFET_NCH_GDS_ESD_PROTECTED	          	          	                    
          	               	D         	244B3     	FM_COMP_P3V3_AUX_VIN_R
          	               	G         	244B3     	PWRGD_P3V3_AUX_R2   
          	               	S         	244B3     	GND                 

Q53       	MOSFET_NCH_GDS_ESD_PROTECTED	          	          	                    
          	               	D         	244B2     	PWRGD_P3V3_AUX_R2   
          	               	G         	244B2     	PWRGD_P3V3_AUX      
          	               	S         	244B2     	GND                 

Q54       	MOSFET_NCH_GDS_ESD_PROTECTED	          	          	                    
          	               	D         	247B2     	P12V_AUX_BLEEDING   
          	               	G         	247B2     	FM_P12V_HSC_EN_R_N  
          	               	S         	247B2     	GND                 

Q56       	MOSFET_NCH_1D3S	          	          	                    
          	               	1         	260B1     	P3V3                
          	               	2         	260B1     	P3V3                
          	               	3         	260B1     	P3V3                
          	               	4         	260B1     	PWRGD_P5V_ISO_R     
          	               	5         	260B1     	P3V3_AUX            

Q57       	MOSFET_NCH_1D3S	          	          	                    
          	               	1         	260B3     	P5V                 
          	               	2         	260B3     	P5V                 
          	               	3         	260B3     	P5V                 
          	               	4         	260B3     	VR_P5V_EN_D_R       
          	               	5         	260B3     	P5V_AUX             

Q67       	MOSFET_NCH_DUAL	          	          	                    
          	               	1         	148B4     	GND                 
          	               	2         	148B4     	BIC_MONITER         
          	               	3         	148B4     	BIC_MONITER_ISO     
          	               	4         	148B4     	GND                 
          	               	5         	148B4     	BIC_MONITER_N       
          	               	6         	148B4     	BIC_MONITER_N       

Q69       	MOSFET_NCH_DUAL	          	          	                    
          	               	1         	148B4     	GND                 
          	               	2         	148B4     	RST_BMC_FROM_SWB_N  
          	               	3         	148B4     	RST_BMC_FROM_SWB_ISO_N
          	               	4         	148B4     	GND                 
          	               	5         	148B4     	RST_BMC_FROM_SWB    
          	               	6         	148B4     	RST_BMC_FROM_SWB    

Q70       	MOSFET_NCH_DUAL	          	          	                    
          	               	1         	148A4     	GND                 
          	               	2         	148A4     	FM_SWB_BIC_READY_N  
          	               	3         	148B4     	FM_SWB_BIC_READY_ISO_N
          	               	4         	148A4     	GND                 
          	               	5         	148B4     	FM_SWB_BIC_READY    
          	               	6         	148B4     	FM_SWB_BIC_READY    

Q71       	MOSFET_NCH_DUAL	          	          	                    
          	               	1         	148B2     	GND                 
          	               	2         	148B2     	FM_SWB_PWRGD        
          	               	3         	148B1     	FM_SWB_PWRGD_ISO    
          	               	4         	148B1     	GND                 
          	               	5         	148B2     	FM_SWB_PWRGD_N      
          	               	6         	148B2     	FM_SWB_PWRGD_N      

Q72       	MOSFET_NCH_DUAL	          	          	                    
          	               	1         	148B2     	GND                 
          	               	2         	148B2     	FM_GPU_PWRGD        
          	               	3         	148B1     	FM_GPU_PWRGD_ISO    
          	               	4         	148B1     	GND                 
          	               	5         	148B1     	FM_GPU_PWRGD_N      
          	               	6         	148B2     	FM_GPU_PWRGD_N      

Q74       	MOSFET_NCH_DUAL	          	          	                    
          	               	1         	148A2     	GND                 
          	               	2         	148A2     	FM_SMB_2_ALERT_GPU_N
          	               	3         	148B1     	FM_SMB_2_ALERT_GPU_ISO_N
          	               	4         	148B1     	GND                 
          	               	5         	148B1     	FM_SMB_2_ALERT_GPU  
          	               	6         	148B2     	FM_SMB_2_ALERT_GPU  

Q75       	MOSFET_NCH_DUAL	          	          	                    
          	               	1         	148A4     	GND                 
          	               	2         	148A4     	FM_SMB_1_ALERT_GPU_N
          	               	3         	148A4     	FM_SMB_1_ALERT_GPU_ISO_N
          	               	4         	148A4     	GND                 
          	               	5         	148A4     	FM_SMB_1_ALERT_GPU  
          	               	6         	148A4     	FM_SMB_1_ALERT_GPU  

Q76       	MOSFET_NCH_DUAL	          	          	                    
          	               	1         	252B4     	GND                 
          	               	2         	252B4     	PWRGD_P1V8_PCH_AUX  
          	               	3         	252B4     	LED_PWRGD_P1V05_PCH_AUX_D
          	               	4         	252B4     	GND                 
          	               	5         	252B4     	PWRGD_P1V05_PCH_AUX 
          	               	6         	252B4     	LED_PWRGD_P1V8_PCH_AUX_D

Q77       	MOSFET_NCH_DUAL	          	          	                    
          	               	1         	252B4     	GND                 
          	               	2         	252B4     	RST_RSMRST_PLD_R_N  
          	               	3         	252A4     	LED_FM_PCH_SLP_S4_N_D
          	               	4         	252A4     	GND                 
          	               	5         	252A4     	FM_PCH_SLP_S4_N     
          	               	6         	252B4     	LED_RST_RSMRST_PLD_R_N_D

Q78       	MOSFET_NCH_DUAL	          	          	                    
          	               	1         	252B2     	GND                 
          	               	2         	252B2     	FM_PCH_SLP_S3_N     
          	               	3         	252B2     	LED_PWRGD_PS_PWROK_PLD_D
          	               	4         	252B2     	GND                 
          	               	5         	252B2     	PWRGD_PS_PWROK_PLD  
          	               	6         	252B2     	LED_FM_PCH_SLP_S3_N_D

Q79       	MOSFET_NCH_DUAL	          	          	                    
          	               	1         	253B4     	GND                 
          	               	2         	253B4     	PWRGD_PVCCD_HV_CPU0 
          	               	3         	253B4     	LED_PWRGD_PVPP_HBM_CPU0_D
          	               	4         	253B4     	GND                 
          	               	5         	253B4     	PWRGD_PVPP_HBM_CPU0 
          	               	6         	253B4     	LED_PWRGD_PVCCD_HV_CPU0_D

Q80       	MOSFET_NCH_DUAL	          	          	                    
          	               	1         	253B4     	GND                 
          	               	2         	253B4     	PWRGD_PVCCFA_EHV_CPU0
          	               	3         	253A4     	LED_PWRGD_PVCCFA_EHV_FIVRA_CP_1
          	               	4         	253A4     	GND                 
          	               	5         	253A4     	PWRGD_PVCCFA_EHV_FIVRA_CPU0
          	               	6         	253B4     	LED_PWRGD_PVCCFA_EHV_CPU0_D

Q81       	MOSFET_NCH_DUAL	          	          	                    
          	               	1         	253B2     	GND                 
          	               	2         	253B2     	PWRGD_PVCCINFAON_CPU0
          	               	3         	253B2     	LED_PWRGD_PVNN_MAIN_CPU0_D
          	               	4         	253B2     	GND                 
          	               	5         	253B2     	PWRGD_PVNN_MAIN_CPU0
          	               	6         	253B2     	LED_PWRGD_PVCCINFAON_CPU0_D

Q83       	MOSFET_NCH_DUAL	          	          	                    
          	               	1         	253B2     	GND                 
          	               	2         	253B2     	PWRGD_PVCCIN_CPU0   
          	               	3         	254B2     	LED_PWRGD_PVCCIN_CPU1_D
          	               	4         	254B2     	GND                 
          	               	5         	254B2     	PWRGD_PVCCIN_CPU1   
          	               	6         	253B2     	LED_PWRGD_PVCCIN_CPU0_D

Q84       	MOSFET_NCH_DUAL	          	          	                    
          	               	1         	254B4     	GND                 
          	               	2         	254B4     	PWRGD_PVCCD_HV_CPU1 
          	               	3         	254B4     	LED_PWRGD_PVPP_HBM_CPU1_D
          	               	4         	254B4     	GND                 
          	               	5         	254B4     	PWRGD_PVPP_HBM_CPU1 
          	               	6         	254B4     	LED_PWRGD_PVCCD_HV_CPU1_D

Q85       	MOSFET_NCH_DUAL	          	          	                    
          	               	1         	254B4     	GND                 
          	               	2         	254B4     	PWRGD_PVCCFA_EHV_CPU1
          	               	3         	254A4     	LED_PWRGD_PVCCFA_EHV_FIVRA_CP_2
          	               	4         	254A4     	GND                 
          	               	5         	254A4     	PWRGD_PVCCFA_EHV_FIVRA_CPU1
          	               	6         	254B4     	LED_PWRGD_PVCCFA_EHV_CPU1_D

Q86       	MOSFET_NCH_DUAL	          	          	                    
          	               	1         	254B2     	GND                 
          	               	2         	254B2     	PWRGD_PVCCINFAON_CPU1
          	               	3         	254B2     	LED_PWRGD_PVNN_MAIN_CPU1_D
          	               	4         	254B2     	GND                 
          	               	5         	254B2     	PWRGD_PVNN_MAIN_CPU1
          	               	6         	254B2     	LED_PWRGD_PVCCINFAON_CPU1_D

Q87       	MOSFET_NCH_DUAL	          	          	                    
          	               	1         	255B4     	GND                 
          	               	2         	255B4     	PWRGD_PCH_PWROK_R   
          	               	3         	255B4     	LED_PWRGD_SYS_PWROK_R_D
          	               	4         	255B4     	GND                 
          	               	5         	255B4     	PWRGD_SYS_PWROK_R   
          	               	6         	255B4     	LED_PWRGD_PCH_PWROK_R_D

Q88       	MOSFET_NCH_DUAL	          	          	                    
          	               	1         	255A4     	GND                 
          	               	2         	255A4     	PWRGD_CPUPWRGD_LVC2_R1
          	               	3         	255A4     	LED_RST_PLTRST_N_D  
          	               	4         	255A4     	GND                 
          	               	5         	255A4     	RST_PLTRST_N        
          	               	6         	255B4     	LED_PWRGD_CPUPWRGD_GTL_D

Q95       	MOSFET_NCH_DUAL	          	          	                    
          	               	1         	190A3     	GND                 
          	               	2         	190A3     	HDD_ACTIVITY_BUF    
          	               	3         	190A2     	NC_Q95_D2           
          	               	4         	190A2     	NC_Q95_S2           
          	               	5         	190A3     	NC_Q95_G2           
          	               	6         	190A3     	HDD_ACTIVITY_BUF_N  

Q96       	MOSFET_NCH_DUAL	          	          	                    
          	               	1         	148A2     	GND                 
          	               	2         	148A2     	GPU_FPGA_READY      
          	               	3         	148A1     	GPU_FPGA_READY_ISO  
          	               	4         	148A1     	GND                 
          	               	5         	148A2     	GPU_FPGA_READY_N    
          	               	6         	148A2     	GPU_FPGA_READY_N    

Q97       	MOSFET_NCH_DUAL	          	          	                    
          	               	1         	256A4     	GND                 
          	               	2         	256A4     	RST_PLD_CPU0_DRAM_EF_N
          	               	3         	256A4     	LED_RST_PLD_CPU0_DRAM_GH_N_D
          	               	4         	256A4     	GND                 
          	               	5         	256A4     	RST_PLD_CPU0_DRAM_GH_N
          	               	6         	256A4     	LED_RST_PLD_CPU0_DRAM_EF_N_D

Q98       	MOSFET_NCH_DUAL	          	          	                    
          	               	1         	256B4     	GND                 
          	               	2         	256B4     	RST_PLD_CPU0_DRAM_AB_N
          	               	3         	256B4     	LED_RST_PLD_CPU0_DRAM_CD_N_D
          	               	4         	256B4     	GND                 
          	               	5         	256B4     	RST_PLD_CPU0_DRAM_CD_N
          	               	6         	256B4     	LED_RST_PLD_CPU0_DRAM_AB_N_D

Q99       	MOSFET_NCH_DUAL	          	          	                    
          	               	1         	256B2     	GND                 
          	               	2         	256B2     	RST_PLD_CPU1_DRAM_CD_N
          	               	6         	256B2     	LED_RST_PLD_CPU1_DRAM_CD_N_D

Q100      	MOSFET_NCH_DUAL	          	          	                    
          	               	1         	256A2     	GND                 
          	               	2         	256A2     	RST_PLD_CPU1_DRAM_EF_N
          	               	3         	256A2     	LED_RST_PLD_CPU1_DRAM_GH_N_D
          	               	4         	256A2     	GND                 
          	               	5         	256A2     	RST_PLD_CPU1_DRAM_GH_N
          	               	6         	256B2     	LED_RST_PLD_CPU1_DRAM_EF_N_D

Q101      	MOSFET_NCH_DUAL	          	          	                    
          	               	1         	147B4     	GND                 
          	               	2         	147B4     	GPU_FPGA_THERM_OVERT_N
          	               	3         	147B4     	GPU_FPGA_THERM_OVERT_ISO_N
          	               	4         	147B4     	GND                 
          	               	5         	147B4     	GPU_FPGA_THERM_OVERT
          	               	6         	147B4     	GPU_FPGA_THERM_OVERT

Q102      	MOSFET_NCH_DUAL	          	          	                    
          	               	1         	147B4     	GND                 
          	               	2         	147B4     	GPU_BASE_HMC_READY  
          	               	3         	147B4     	GPU_BASE_HMC_READY_ISO
          	               	4         	147B4     	GND                 
          	               	5         	147B4     	GPU_BASE_HMC_READY_N
          	               	6         	147B4     	GPU_BASE_HMC_READY_N

Q103      	MOSFET_NCH_DUAL	          	          	                    
          	               	1         	147A4     	GND                 
          	               	2         	147A4     	GPU_HMC_PRSNT_N     
          	               	3         	147B4     	GPU_HMC_PRSNT_ISO_N 
          	               	4         	147B4     	GND                 
          	               	5         	147B4     	GPU_HMC_PRSNT       
          	               	6         	147B4     	GPU_HMC_PRSNT       

Q104      	MOSFET_NCH_DUAL	          	          	                    
          	               	1         	147A4     	GND                 
          	               	2         	147A4     	GPU_FPGA_OVERT_N    
          	               	3         	147A4     	GPU_FPGA_OVERT_ISO_N
          	               	4         	147A4     	GND                 
          	               	5         	147A4     	GPU_FPGA_OVERT      
          	               	6         	147A4     	GPU_FPGA_OVERT      

Q105      	MOSFET_NCH_DUAL	          	          	                    
          	               	1         	256B2     	GND                 
          	               	2         	256B2     	RST_PLD_CPU1_DRAM_AB_N
          	               	6         	256B2     	LED_RST_PLD_CPU1_DRAM_AB_N_D

Q106      	MOSFET_NCH_DUAL	          	          	                    
          	               	1         	147B2     	GND                 
          	               	2         	147B2     	GPU_WP_HW_CTRL_N    
          	               	6         	147B2     	GPU_WP_HW_CTRL_ISO  

Q107      	MOSFET_NCH_DUAL	          	          	                    
          	               	1         	147B2     	GND                 
          	               	2         	147B2     	GPU_PRSNT_N         
          	               	3         	147B1     	GPU_PRSNT_N_ISO     
          	               	4         	147B1     	GND                 
          	               	5         	147B1     	GPU_PRSNT           
          	               	6         	147B2     	GPU_PRSNT           

Q108      	MOSFET_NCH_DUAL	          	          	                    
          	               	1         	147A2     	GND                 
          	               	2         	147A2     	GPU_FPGA_EROT_FATALERR_N
          	               	3         	147B1     	GPU_FPGA_EROT_FATALERR_ISO_N
          	               	4         	147A1     	GND                 
          	               	5         	147B1     	GPU_FPGA_EROT_FATALERR
          	               	6         	147B2     	GPU_FPGA_EROT_FATALERR

Q118      	MOSFET_NCH_DUAL	          	          	                    
          	               	1         	162A4     	GND                 
          	               	2         	162A4     	P12V_OCP_EN_2_R     
          	               	3         	162B4     	P12V_OCP_UV_2_R     
          	               	4         	162B4     	GND                 
          	               	5         	162B4     	P12V_OCP_2_EN_G     
          	               	6         	162B4     	P12V_OCP_2_EN_G     

Q119      	MOSFET_NCH_DUAL	          	          	                    
          	               	1         	162B4     	GND                 
          	               	2         	162B4     	P3V3_OCP_EN_2_R     
          	               	3         	162B4     	P3V3_OCP_UV_2_R1    
          	               	4         	162B4     	GND                 
          	               	5         	162B4     	P3V3_OCP_2_EN_G     
          	               	6         	162B4     	P3V3_OCP_2_EN_G     

Q123      	MOSFET_NCH_DUAL	          	          	                    
          	               	1         	156A4     	GND                 
          	               	2         	156A4     	P12V_OCP_EN_1_R     
          	               	3         	156B4     	P12V_OCP_UV_1_R     
          	               	4         	156B4     	GND                 
          	               	5         	156B4     	P12V_OCP_1_EN_G     
          	               	6         	156B4     	P12V_OCP_1_EN_G     

Q124      	MOSFET_NCH_DUAL	          	          	                    
          	               	1         	156B4     	GND                 
          	               	2         	156B4     	P3V3_OCP_EN_1_R     
          	               	3         	156B3     	P3V3_OCP_UV_1_R1    
          	               	4         	156B3     	GND                 
          	               	5         	156B4     	P3V3_OCP_1_EN_G     
          	               	6         	156B4     	P3V3_OCP_1_EN_G     

Q125      	MOSFET_NCH_DUAL	          	          	                    
          	               	1         	242B4     	GND                 
          	               	2         	242B4     	P12V_SCM_EN_R       
          	               	3         	242B3     	P12V_SCM_UV_R       
          	               	4         	242B3     	GND                 
          	               	5         	242B3     	P12V_SCM_EN_G       
          	               	6         	242B4     	P12V_SCM_EN_G       

Q126      	MOSFET_NCH_DUAL	          	          	                    
          	               	1         	192A4     	GND                 
          	               	2         	192A4     	P3V3_E1S_EN_1_R     
          	               	3         	192A4     	P3V3_E1S_UV_0_R     
          	               	4         	192A4     	GND                 
          	               	5         	192A4     	P3V3_E1S_0_EN_G     
          	               	6         	192A4     	P3V3_E1S_0_EN_G     

Q127      	MOSFET_NCH_DUAL	          	          	                    
          	               	1         	192B4     	GND                 
          	               	2         	192B4     	P12V_E1S_EN_0_R     
          	               	3         	192B4     	P12V_E1S_UV_0_R     
          	               	4         	192B4     	GND                 
          	               	5         	192B4     	P12V_E1S_0_EN_G     
          	               	6         	192B4     	P12V_E1S_0_EN_G     

Q128      	MOSFET_NCH_DUAL	          	          	                    
          	               	1         	146B4     	GND                 
          	               	2         	146B4     	GPU_3V3IO_RSVD0_FFU 
          	               	3         	146B4     	GPU_3V3IO_RSVD0_FFU_ISO
          	               	4         	146B4     	GND                 
          	               	5         	146B4     	GPU_3V3IO_RSVD0_FFU_N
          	               	6         	146B4     	GPU_3V3IO_RSVD0_FFU_N

Q129      	MOSFET_NCH_DUAL	          	          	                    
          	               	1         	146A2     	GND                 
          	               	2         	146B2     	GPU_3V3IO_RSVD5_FFU 
          	               	3         	146B1     	GPU_3V3IO_RSVD5_FFU_ISO
          	               	4         	146B1     	GND                 
          	               	5         	146B2     	GPU_3V3IO_RSVD5_FFU_N
          	               	6         	146B2     	GPU_3V3IO_RSVD5_FFU_N

Q130      	MOSFET_NCH_DUAL	          	          	                    
          	               	1         	146B2     	GND                 
          	               	2         	146B2     	GPU_3V3IO_RSVD3_FFU 
          	               	3         	146B1     	GPU_3V3IO_RSVD3_FFU_ISO
          	               	4         	146B1     	GND                 
          	               	5         	146B2     	GPU_3V3IO_RSVD3_FFU_N
          	               	6         	146B2     	GPU_3V3IO_RSVD3_FFU_N

Q131      	MOSFET_NCH_DUAL	          	          	                    
          	               	1         	146B4     	GND                 
          	               	2         	146B4     	GPU_3V3IO_RSVD1_FFU 
          	               	3         	146B4     	GPU_3V3IO_RSVD1_FFU_ISO
          	               	4         	146B4     	GND                 
          	               	5         	146B4     	GPU_3V3IO_RSVD1_FFU_N
          	               	6         	146B4     	GPU_3V3IO_RSVD1_FFU_N

Q132      	MOSFET_NCH_DUAL	          	          	                    
          	               	1         	146A4     	GND                 
          	               	2         	146A4     	PRSNT_CABLE_GPU_B3_N
          	               	3         	146B4     	PRSNT_CABLE_GPU_B3_ISO_N
          	               	4         	146A4     	GND                 
          	               	5         	146B4     	PRSNT_CABLE_GPU_B3  
          	               	6         	146B4     	PRSNT_CABLE_GPU_B3  

Q133      	MOSFET_NCH_DUAL	          	          	                    
          	               	1         	146B2     	GND                 
          	               	2         	146B2     	PRSNT_CABLE_GPU_A2_N
          	               	3         	146B1     	PRSNT_CABLE_GPU_A2_ISO_N
          	               	4         	146B1     	GND                 
          	               	5         	146B2     	PRSNT_CABLE_GPU_A2  
          	               	6         	146B2     	PRSNT_CABLE_GPU_A2  

Q134      	MOSFET_NCH_DUAL	          	          	                    
          	               	1         	146A4     	GND                 
          	               	2         	146A4     	PRSNT_CABLE_GPU_A1_N
          	               	3         	146A4     	PRSNT_CABLE_GPU_A1_ISO_N
          	               	4         	146A4     	GND                 
          	               	5         	146A4     	PRSNT_CABLE_GPU_A1  
          	               	6         	146A4     	PRSNT_CABLE_GPU_A1  

Q135      	MOSFET_NCH_DUAL	          	          	                    
          	               	1         	145B4     	GND                 
          	               	2         	145B4     	GPU_3V3IO_RSVD1     
          	               	3         	145B4     	GPU_3V3IO_RSVD1_ISO 
          	               	4         	145B4     	GND                 
          	               	5         	145B4     	GPU_3V3IO_RSVD1_N   
          	               	6         	145B4     	GPU_3V3IO_RSVD1_N   

Q136      	MOSFET_NCH_DUAL	          	          	                    
          	               	1         	145A4     	GND                 
          	               	2         	145A4     	GPU_3V3IO_RSVD4     
          	               	3         	145B4     	GPU_3V3IO_RSVD4_ISO 
          	               	4         	145A4     	GND                 
          	               	5         	145B4     	GPU_3V3IO_RSVD4_N   
          	               	6         	145B4     	GPU_3V3IO_RSVD4_N   

Q137      	MOSFET_NCH_DUAL	          	          	                    
          	               	1         	145B4     	GND                 
          	               	2         	145B4     	GPU_3V3IO_RSVD3     
          	               	3         	145B4     	GPU_3V3IO_RSVD3_ISO 
          	               	4         	145B4     	GND                 
          	               	5         	145B4     	GPU_3V3IO_RSVD3_N   
          	               	6         	145B4     	GPU_3V3IO_RSVD3_N   

Q138      	SBC847BPDXV6T1G	          	          	                    
          	               	1         	121B2     	GND                 
          	               	2         	121B2     	H_CPU0_THERMTRIP_R_N
          	               	3         	121B3     	H_CPU0_THERMTRIP_N  
          	               	4         	121B3     	PVNN_TERM_CPU0      
          	               	5         	121B3     	H_CPU0_THERMTRIP_VT_R_N
          	               	6         	121B2     	H_CPU0_THERMTRIP_VT_N

Q139      	SBC847BPDXV6T1G	          	          	                    
          	               	1         	121B2     	GND                 
          	               	2         	121B2     	H_CPU1_THERMTRIP_R_N
          	               	3         	121B3     	H_CPU1_THERMTRIP_N  
          	               	4         	121B3     	PVNN_TERM_CPU1      
          	               	5         	121B3     	H_CPU1_THERMTRIP_VT_R_N
          	               	6         	121B2     	H_CPU1_THERMTRIP_VT_N

Q140      	SBC847BPDXV6T1G	          	          	                    
          	               	1         	123B2     	GND                 
          	               	2         	123B3     	H_CPU1_MEMTRIP_R    
          	               	3         	123B3     	H_CPU1_MEMTRIP      
          	               	4         	123B3     	PVNN_TERM_CPU1      
          	               	5         	123B3     	H_CPU1_MEMTRIP_OUT_VT_R_N
          	               	6         	123B2     	H_CPU1_MEMTRIP_VT_N 

Q141      	SBC847BPDXV6T1G	          	          	                    
          	               	1         	123B2     	GND                 
          	               	2         	123B3     	H_CPU0_MEMTRIP_R    
          	               	3         	123B3     	H_CPU0_MEMTRIP      
          	               	4         	123B3     	PVNN_TERM_CPU0      
          	               	5         	123B3     	H_CPU0_MEMTRIP_OUT_VT_R_N
          	               	6         	123B2     	H_CPU0_MEMTRIP_VT_N 

Q142      	SBC847BPDXV6T1G	          	          	                    
          	               	1         	122A2     	GND                 
          	               	2         	122A2     	H_CPU1_MEMHOT_OUT_R 
          	               	3         	122A3     	H_CPU1_MEMHOT_OUT   
          	               	4         	122A3     	PVNN_TERM_CPU1      
          	               	5         	122A3     	H_CPU1_MEMHOT_OUT_VT_R_N
          	               	6         	122A2     	H_CPU1_MEMHOT_OUT_VT_N

Q143      	SBC847BPDXV6T1G	          	          	                    
          	               	1         	122B2     	GND                 
          	               	2         	122B2     	H_CPU0_MEMHOT_OUT_R 
          	               	3         	122B3     	H_CPU0_MEMHOT_OUT   
          	               	4         	122B3     	PVNN_TERM_CPU0      
          	               	5         	122B3     	H_CPU0_MEMHOT_OUT_VT_R_N
          	               	6         	122B2     	H_CPU0_MEMHOT_OUT_VT_N

Q144      	MOSFET_NCH_DUAL	          	          	                    
          	               	1         	224A3     	GND                 
          	               	2         	224A3     	PWRGD_PS_PWROK_PLD  
          	               	3         	224B3     	PWRGD_PS_PWROK_PLD_ISO
          	               	4         	224B3     	GND                 
          	               	5         	224B3     	PWRGD_PS_PWROK_PLD_N
          	               	6         	224B3     	PWRGD_PS_PWROK_PLD_N

Q145      	MOSFET_NCH_DUAL	          	          	                    
          	               	1         	246A3     	GND                 
          	               	2         	246A3     	HPDB_HSC_PWRGD      
          	               	3         	246A2     	HPDB_HSC_PWRGD_ISO  
          	               	4         	246A2     	GND                 
          	               	5         	246A3     	HPDB_HSC_PWRGD_N    
          	               	6         	246A3     	HPDB_HSC_PWRGD_N    

Q146      	MOSFET_NCH_DUAL	          	          	                    
          	               	1         	146A2     	GND                 
          	               	2         	146A2     	SWB_HSC_PWRGD       
          	               	3         	146A1     	SWB_HSC_PWRGD_ISO   
          	               	4         	146A1     	GND                 
          	               	5         	146A2     	SWB_HSC_PWRGD_N     
          	               	6         	146A2     	SWB_HSC_PWRGD_N     

Q148      	MOSFET_NCH_DUAL	          	          	                    
          	               	1         	145A4     	GND                 
          	               	2         	145A4     	HGX_DETECT_N        
          	               	3         	145A4     	HGX_DETECT_N_ISO    
          	               	4         	145A4     	GND                 
          	               	5         	145A4     	HGX_DETECT          
          	               	6         	145A4     	HGX_DETECT          

Q150      	MOSFET_NCH_DUAL	          	          	                    
          	               	1         	255A2     	GND                 
          	               	2         	255A2     	P12V_SCM_FAULT_R_N  
          	               	3         	255A2     	LED_P12V_SCM_FAULT_D2
          	               	4         	255A2     	GND                 
          	               	5         	255A2     	LED_P12V_SCM_FAULT_D1
          	               	6         	255A2     	LED_P12V_SCM_FAULT_D1

Q151      	MOSFET_NCH_DUAL	          	          	                    
          	               	1         	144B4     	GND                 
          	               	2         	144B4     	PRSNT_SWB_N         
          	               	3         	144B4     	PRSNT_SWB_ISO_N     
          	               	4         	144B4     	GND                 
          	               	5         	144B4     	PRSNT_SWB           
          	               	6         	144B4     	PRSNT_SWB           

Q152      	MOSFET_NCH_DUAL	          	          	                    
          	               	1         	144B4     	GND                 
          	               	2         	144B4     	PRSNT_CABLE_SWB_B2_N
          	               	3         	144B4     	PRSNT_CABLE_SWB_B2_ISO_N
          	               	4         	144B4     	GND                 
          	               	5         	144B4     	PRSNT_CABLE_SWB_B2  
          	               	6         	144B4     	PRSNT_CABLE_SWB_B2  

Q153      	MOSFET_NCH_DUAL	          	          	                    
          	               	1         	144A4     	GND                 
          	               	2         	144A4     	PRSNT_CABLE_SWB_B1_N
          	               	3         	144B3     	PRSNT_CABLE_SWB_B1_ISO_N
          	               	4         	144A3     	GND                 
          	               	5         	144A4     	PRSNT_CABLE_SWB_B1  
          	               	6         	144A4     	PRSNT_CABLE_SWB_B1  

Q154      	MOSFET_NCH_DUAL	          	          	                    
          	               	1         	144A4     	GND                 
          	               	2         	144A4     	PRSNT_CABLE_GPU_A3_N
          	               	3         	144A3     	PRSNT_CABLE_GPU_A3_ISO_N
          	               	4         	144A3     	GND                 
          	               	5         	144A4     	PRSNT_CABLE_GPU_A3  
          	               	6         	144A4     	PRSNT_CABLE_GPU_A3  

Q236      	MOSFET_NCH_DUAL	          	          	                    
          	               	1         	260A2     	GND                 
          	               	2         	260A2     	PWRGD_P5V           
          	               	3         	260A2     	PWRGD_P5V_ISO       
          	               	4         	260A2     	GND                 
          	               	5         	260A2     	PWRGD_P5V_N         
          	               	6         	260A2     	PWRGD_P5V_N         

R1        	Q_RES_0402LF   	          	          	                    
          	               	1         	13B4      	H_CPU_PRDY_QS_GTL_N 
          	               	2         	13B4      	H_CPU0_PRDY_QS_GTL_R_N

R2        	Q_RES_0402LF   	          	          	                    
          	               	1         	13B4      	H_CPU_PREQ_QS_GTL_N 
          	               	2         	13B4      	H_CPU0_PREQ_QS_GTL_R_N

R3        	Q_RES_0402LF   	          	          	                    
          	               	1         	13B4      	PECI_CPU_GTL        
          	               	2         	13B4      	PECI_CPU0_GTL_R     

R4        	Q_RES_0402LF   	          	          	                    
          	               	1         	13B4      	JTAG_MUX_CPU0_GTL_TDI
          	               	2         	13B4      	JTAG_DBP_CPU0_GTL_R_TDI

R5        	Q_RES_0402LF   	          	          	                    
          	               	1         	13B4      	JTAG_DBP_CPU_GTL_TCK
          	               	2         	13B4      	JTAG_DBP_CPU0_GTL_R_TCK

R6        	Q_RES_0402LF   	          	          	                    
          	               	1         	13B4      	JTAG_DBP_CPU_QS_GTL_TMS
          	               	2         	13B4      	JTAG_DBP_CPU0_QS_GTL_R_TMS

R7        	Q_RES_0402LF   	          	          	                    
          	               	1         	14A4      	H_CPU0_PMDOWN_PCH_R 
          	               	2         	14A3      	H_CPU0_PMDOWN_PCH   

R8        	Q_RES_0402LF   	          	          	                    
          	               	1         	204B4     	P3V3_AUX            
          	               	2         	204B4     	FM_PS_PWROK_DLY_R_SEL

R10       	Q_RES_0402LF   	          	          	                    
          	               	1         	14A4      	H_CPU0_PMSYNC_PCH_R 
          	               	2         	14A3      	H_CPU0_PMSYNC_PCH   

R11       	Q_RES_0402LF   	          	          	                    
          	               	1         	14A4      	H_CPU0_PMDOWN_CPU1_R1
          	               	2         	14A3      	H_CPU0_PMDOWN_CPU1  

R12       	Q_RES_0402LF   	          	          	                    
          	               	1         	14B2      	SVID_DIO0_CPU0      
          	               	2         	14B2      	SVID_DIO0_CPU0_R    

R13       	Q_RES_0402LF   	          	          	                    
          	               	1         	14B2      	SVID_CLK0_CPU0      
          	               	2         	14B2      	SVID_CLK0_CPU0_R    

R14       	Q_RES_0402LF   	          	          	                    
          	               	1         	14B2      	SVID_ALERT0_CPU0_N  
          	               	2         	14B2      	SVID_ALERT0_CPU0_R_N

R15       	Q_RES_0402LF   	          	          	                    
          	               	1         	14B2      	SVID_DIO1_CPU0      
          	               	2         	14B2      	SVID_DIO1_CPU0_R    

R16       	Q_RES_0402LF   	          	          	                    
          	               	1         	14B2      	SVID_CLK1_CPU0      
          	               	2         	14B2      	SVID_CLK1_CPU0_R    

R17       	Q_RES_0402LF   	          	          	                    
          	               	1         	14B2      	SVID_ALERT1_CPU0_N  
          	               	2         	14B2      	SVID_ALERT1_CPU0_R_N

R18       	Q_RES_0402LF   	          	          	                    
          	               	1         	16B3      	PVNN_TERM_CPU0      
          	               	2         	16B3      	DBP_CPU_MBP0_GTL_N  

R19       	Q_RES_0402LF   	          	          	                    
          	               	1         	16B2      	PVNN_TERM_CPU0      
          	               	2         	16B2      	DBP_CPU_MBP1_GTL_N  

R20       	Q_RES_0402LF   	          	          	                    
          	               	1         	16B2      	DBP_CPU_MBP0_GTL_N  
          	               	2         	16B2      	FM_PCH_TRIGGER0_N   

R21       	Q_RES_0402LF   	          	          	                    
          	               	1         	16B2      	DBP_CPU_MBP1_GTL_N  
          	               	2         	16B2      	FM_PCH_TRIGGER1_N   

R22       	Q_RES_0402LF   	          	          	                    
          	               	1         	16B2      	DBP_CPU0_MBP0_GTL_R_N
          	               	2         	16B2      	DBP_CPU_MBP0_GTL_N  

R23       	Q_RES_0402LF   	          	          	                    
          	               	1         	16B2      	DBP_CPU0_MBP1_GTL_R_N
          	               	2         	16B2      	DBP_CPU_MBP1_GTL_N  

R24       	Q_RES_0402LF   	          	          	                    
          	               	1         	16B2      	DBP_CPU0_HOOK8_MBP2_GTL_QS_R_N
          	               	2         	16B2      	DBP_CPU_HOOK8_MBP2_GTL_QS_N

R25       	Q_RES_0402LF   	          	          	                    
          	               	1         	16B2      	DBP_CPU0_HOOK9_MBP3_GTL_QS_R_N
          	               	2         	16B2      	DBP_CPU_HOOK9_MBP3_GTL_QS_N

R26       	Q_RES_0402LF   	          	          	                    
          	               	1         	82A4      	PD_CHA_CPU0_DIMM1_SAA
          	               	2         	82A4      	GND                 

R27       	Q_RES_0402LF   	          	          	                    
          	               	1         	83A4      	PD_CHA_CPU0_DIMM2_SAA
          	               	2         	83A4      	GND                 

R28       	Q_RES_0402LF   	          	          	                    
          	               	1         	84A4      	PD_CHB_CPU0_DIMM1_SAA
          	               	2         	84A4      	GND                 

R29       	Q_RES_0402LF   	          	          	                    
          	               	1         	85A4      	PD_CHB_CPU0_DIMM2_SAA
          	               	2         	85A4      	GND                 

R30       	Q_RES_0402LF   	          	          	                    
          	               	1         	86A4      	PD_CHC_CPU0_DIMM1_SAA
          	               	2         	86A4      	GND                 

R31       	Q_RES_0402LF   	          	          	                    
          	               	1         	87A4      	PD_CHC_CPU0_DIMM2_SAA
          	               	2         	87A4      	GND                 

R32       	Q_RES_0402LF   	          	          	                    
          	               	1         	88A4      	PD_CHD_CPU0_DIMM1_SAA
          	               	2         	88A4      	GND                 

R33       	Q_RES_0402LF   	          	          	                    
          	               	1         	89A4      	PD_CHD_CPU0_DIMM2_SAA
          	               	2         	89A4      	GND                 

R34       	Q_RES_0402LF   	          	          	                    
          	               	1         	90A4      	PD_CHE_CPU0_DIMM1_SAA
          	               	2         	90A4      	GND                 

R35       	Q_RES_0402LF   	          	          	                    
          	               	1         	91A4      	PD_CHE_CPU0_DIMM2_SAA
          	               	2         	91A4      	GND                 

R36       	Q_RES_0402LF   	          	          	                    
          	               	1         	92A4      	PD_CHF_CPU0_DIMM1_SAA
          	               	2         	92A4      	GND                 

R37       	Q_RES_0402LF   	          	          	                    
          	               	1         	93A4      	PD_CHF_CPU0_DIMM2_SAA
          	               	2         	93A4      	GND                 

R38       	Q_RES_0402LF   	          	          	                    
          	               	1         	94A4      	PD_CHG_CPU0_DIMM1_SAA
          	               	2         	94A4      	GND                 

R39       	Q_RES_0402LF   	          	          	                    
          	               	1         	95A4      	PD_CHG_CPU0_DIMM2_SAA
          	               	2         	95A4      	GND                 

R40       	Q_RES_0402LF   	          	          	                    
          	               	1         	96A4      	PD_CHH_CPU0_DIMM1_SAA
          	               	2         	96A4      	GND                 

R41       	Q_RES_0402LF   	          	          	                    
          	               	1         	97A4      	PD_CHH_CPU0_DIMM2_SAA
          	               	2         	97A4      	GND                 

R42       	Q_RES_0402LF   	          	          	                    
          	               	1         	98A4      	PD_CHA_CPU1_DIMM1_SAA
          	               	2         	98A4      	GND                 

R43       	Q_RES_0402LF   	          	          	                    
          	               	1         	99A4      	PD_CHA_CPU1_DIMM2_SAA
          	               	2         	99A4      	GND                 

R44       	Q_RES_0402LF   	          	          	                    
          	               	1         	100A4     	PD_CHB_CPU1_DIMM1_SAA
          	               	2         	100A4     	GND                 

R45       	Q_RES_0402LF   	          	          	                    
          	               	1         	101A4     	PD_CHB_CPU1_DIMM2_SAA
          	               	2         	101A4     	GND                 

R46       	Q_RES_0402LF   	          	          	                    
          	               	1         	102A4     	PD_CHC_CPU1_DIMM1_SAA
          	               	2         	102A4     	GND                 

R47       	Q_RES_0402LF   	          	          	                    
          	               	1         	103A4     	PD_CHC_CPU1_DIMM2_SAA
          	               	2         	103A4     	GND                 

R48       	Q_RES_0402LF   	          	          	                    
          	               	1         	104A4     	PD_CHD_CPU1_DIMM1_SAA
          	               	2         	104A4     	GND                 

R49       	Q_RES_0402LF   	          	          	                    
          	               	1         	47B1      	PVNN_TERM_CPU1      
          	               	2         	47B1      	DBP_CPU_MBP0_GTL_N  

R50       	Q_RES_0402LF   	          	          	                    
          	               	1         	47B1      	PVNN_TERM_CPU1      
          	               	2         	47B1      	DBP_CPU_MBP1_GTL_N  

R51       	Q_RES_0402LF   	          	          	                    
          	               	1         	47B2      	DBP_CPU1_MBP0_GTL_R_N
          	               	2         	47B2      	DBP_CPU_MBP0_GTL_N  

R52       	Q_RES_0402LF   	          	          	                    
          	               	1         	47B2      	DBP_CPU1_MBP1_GTL_R_N
          	               	2         	47B2      	DBP_CPU_MBP1_GTL_N  

R53       	Q_RES_0402LF   	          	          	                    
          	               	1         	47B2      	DBP_CPU1_HOOK8_MBP2_GTL_QS_R_N
          	               	2         	47B2      	DBP_CPU_HOOK8_MBP2_GTL_QS_N

R54       	Q_RES_0402LF   	          	          	                    
          	               	1         	47B2      	DBP_CPU1_HOOK9_MBP3_GTL_QS_R_N
          	               	2         	47B2      	DBP_CPU_HOOK9_MBP3_GTL_QS_N

R55       	Q_RES_0402LF   	          	          	                    
          	               	1         	45B2      	SVID_DIO0_CPU1      
          	               	2         	45B2      	SVID_DIO0_CPU1_R    

R56       	Q_RES_0402LF   	          	          	                    
          	               	1         	45B2      	SVID_CLK0_CPU1      
          	               	2         	45B2      	SVID_CLK0_CPU1_R    

R57       	Q_RES_0402LF   	          	          	                    
          	               	1         	45B2      	SVID_ALERT0_CPU1_N  
          	               	2         	45B2      	SVID_ALERT0_CPU1_R_N

R58       	Q_RES_0402LF   	          	          	                    
          	               	1         	45B2      	SVID_DIO1_CPU1      
          	               	2         	45B2      	SVID_DIO1_CPU1_R    

R59       	Q_RES_0402LF   	          	          	                    
          	               	1         	45B2      	SVID_CLK1_CPU1      
          	               	2         	45B2      	SVID_CLK1_CPU1_R    

R60       	Q_RES_0402LF   	          	          	                    
          	               	1         	45B2      	SVID_ALERT1_CPU1_N  
          	               	2         	45B2      	SVID_ALERT1_CPU1_R_N

R61       	Q_RES_0402LF   	          	          	                    
          	               	1         	44B4      	H_CPU_PRDY_QS_GTL_N 
          	               	2         	44B4      	H_CPU1_PRDY_QS_GTL_R_N

R62       	Q_RES_0402LF   	          	          	                    
          	               	1         	44B4      	H_CPU_PREQ_QS_GTL_N 
          	               	2         	44B4      	H_CPU1_PREQ_QS_GTL_R_N

R63       	Q_RES_0402LF   	          	          	                    
          	               	1         	44B4      	PECI_CPU_GTL        
          	               	2         	44B4      	PECI_CPU1_GTL_R     

R64       	Q_RES_0402LF   	          	          	                    
          	               	1         	44B4      	JTAG_MUX_CPU1_GTL_TDI
          	               	2         	44B4      	JTAG_DBP_CPU1_GTL_R_TDI

R65       	Q_RES_0402LF   	          	          	                    
          	               	1         	44B4      	JTAG_DBP_CPU_GTL_TCK
          	               	2         	44B4      	JTAG_DBP_CPU1_GTL_R_TCK

R66       	Q_RES_0402LF   	          	          	                    
          	               	1         	44B4      	JTAG_DBP_CPU_QS_GTL_TMS
          	               	2         	44B4      	JTAG_DBP_CPU1_QS_GTL_R_TMS

R67       	Q_RES_0402LF   	          	          	                    
          	               	1         	43B4      	PWRGD_PLT_AUX_CPU0_LVT3_R
          	               	2         	43B4      	PWRGD_PLT_AUX_CPU0_LVT3

R68       	Q_RES_0402LF   	          	          	                    
          	               	1         	43B4      	PWRGD_PLT_AUX_CPU1_LVT3_R
          	               	2         	43B4      	PWRGD_PLT_AUX_CPU1_LVT3

R69       	Q_RES_0402LF   	          	          	                    
          	               	1         	43B4      	PWRGD_PLT_AUX_CPU0_LVT3
          	               	2         	43B4      	GND                 

R70       	Q_RES_0402LF   	          	          	                    
          	               	1         	43B4      	PWRGD_PLT_AUX_CPU1_LVT3
          	               	2         	43B4      	GND                 

R71       	Q_RES_0402LF   	          	          	                    
          	               	1         	204B4     	P3V3_AUX            
          	               	2         	204B4     	FM_ME_BT_DONE       

R72       	Q_RES_0402LF   	          	          	                    
          	               	1         	113A4     	PD_CHH_CPU1_DIMM2_SAA
          	               	2         	113A4     	GND                 

R73       	Q_RES_0402LF   	          	          	                    
          	               	1         	112A4     	PD_CHH_CPU1_DIMM1_SAA
          	               	2         	112A4     	GND                 

R74       	Q_RES_0402LF   	          	          	                    
          	               	1         	111A4     	PD_CHG_CPU1_DIMM2_SAA
          	               	2         	111A4     	GND                 

R75       	Q_RES_0402LF   	          	          	                    
          	               	1         	110A4     	PD_CHG_CPU1_DIMM1_SAA
          	               	2         	110A4     	GND                 

R76       	Q_RES_0402LF   	          	          	                    
          	               	1         	109A4     	PD_CHF_CPU1_DIMM2_SAA
          	               	2         	109A4     	GND                 

R77       	Q_RES_0402LF   	          	          	                    
          	               	1         	108A4     	PD_CHF_CPU1_DIMM1_SAA
          	               	2         	108A4     	GND                 

R78       	Q_RES_0402LF   	          	          	                    
          	               	1         	107A4     	PD_CHE_CPU1_DIMM2_SAA
          	               	2         	107A4     	GND                 

R79       	Q_RES_0402LF   	          	          	                    
          	               	1         	106A4     	PD_CHE_CPU1_DIMM1_SAA
          	               	2         	106A4     	GND                 

R80       	Q_RES_0402LF   	          	          	                    
          	               	1         	105A4     	PD_CHD_CPU1_DIMM2_SAA
          	               	2         	105A4     	GND                 

R87       	Q_RES_0402LF   	          	          	                    
          	               	1         	229A1     	P3V3_AUX            
          	               	2         	229A1     	FM_SPD_REMOTE_EN    

R90       	Q_RES_0402LF   	          	          	                    
          	               	1         	126A4     	PVNN_TERM_CPU1      
          	               	2         	126A4     	PU_CPU1_UPI0_AC_COUPLING

R91       	Q_RES_0402LF   	          	          	                    
          	               	1         	126A4     	PVNN_TERM_CPU1      
          	               	2         	126A4     	PU_CPU1_UPI1_AC_COUPLING

R92       	Q_RES_0402LF   	          	          	                    
          	               	1         	126A4     	PVNN_TERM_CPU1      
          	               	2         	126A4     	PU_CPU1_UPI2_AC_COUPLING

R93       	Q_RES_0402LF   	          	          	                    
          	               	1         	126A4     	PVNN_TERM_CPU1      
          	               	2         	126A4     	PU_CPU1_UPI3_AC_COUPLING

R94       	Q_RES_0402LF   	          	          	                    
          	               	1         	126B4     	PVNN_TERM_CPU0      
          	               	2         	126B4     	PU_CPU0_UPI0_AC_COUPLING

R95       	Q_RES_0402LF   	          	          	                    
          	               	1         	126A4     	PVNN_TERM_CPU0      
          	               	2         	126A4     	PU_CPU0_UPI1_AC_COUPLING

R96       	Q_RES_0402LF   	          	          	                    
          	               	1         	126A4     	PVNN_TERM_CPU0      
          	               	2         	126A4     	PU_CPU0_UPI2_AC_COUPLING

R97       	Q_RES_0402LF   	          	          	                    
          	               	1         	126A4     	PVNN_TERM_CPU0      
          	               	2         	126A4     	PU_CPU0_UPI3_AC_COUPLING

R106      	Q_RES_0402LF   	          	          	                    
          	               	1         	206B3     	GND                 
          	               	2         	206B3     	FM_PLD_CLKS_DEV_EN  

R107      	Q_RES_0402LF   	          	          	                    
          	               	1         	241B4     	SMB_HOST_3V3AUX_SCL_R
          	               	2         	241B4     	SMB_HOST_CLK_BUF_3V3AUX_SCL

R108      	Q_RES_0402LF   	          	          	                    
          	               	1         	241B4     	SMB_HOST_3V3AUX_SDA_R
          	               	2         	241B4     	SMB_HOST_CLK_BUF_3V3AUX_SDA

R109      	Q_RES_0402LF   	          	          	                    
          	               	1         	223B4     	FM_PLD_CLK_25M_R_EN 
          	               	2         	223B4     	FM_PLD_CLK_25M_EN   

R110      	Q_RES_0402LF   	          	          	                    
          	               	1         	223B4     	FM_PLD_CLKS_DEV_R_EN
          	               	2         	223B4     	FM_PLD_CLKS_DEV_EN  

R111      	Q_RES_0402LF   	          	          	                    
          	               	1         	223B4     	P3V3                
          	               	2         	223B4     	FM_PLD_CLKS_OE_R_N  

R113      	Q_RES_0402LF   	          	          	                    
          	               	1         	223B3     	FM_PLD_CLKS_OE_R_N  
          	               	2         	223B3     	FM_DB2000_OE_N      

R120      	Q_RES_0603LF   	          	          	                    
          	               	1         	179A3     	XTAL_PCH_RTC2_R     
          	               	2         	179A3     	XTAL_PCH_RTC1       

R122      	Q_RES_0402LF   	          	          	                    
          	               	1         	125B4     	PWRGD_DRAMPWRGD_CPU1_AB_R_LVC1
          	               	2         	125B4     	PWRGD_DRAMPWRGD_CPU1_AB_LVC1_R2

R124      	Q_RES_0402LF   	          	          	                    
          	               	1         	125B4     	PWRGD_DRAMPWRGD_CPU1_CD_R_LVC1
          	               	2         	125B4     	PWRGD_DRAMPWRGD_CPU1_CD_LVC1_R2

R126      	Q_RES_0402LF   	          	          	                    
          	               	1         	125B4     	PWRGD_DRAMPWRGD_CPU1_EF_R_LVC1
          	               	2         	125B4     	PWRGD_DRAMPWRGD_CPU1_EF_LVC1_R2

R128      	Q_RES_0402LF   	          	          	                    
          	               	1         	125B4     	PWRGD_DRAMPWRGD_CPU1_GH_R_LVC1
          	               	2         	125B4     	PWRGD_DRAMPWRGD_CPU1_GH_LVC1_R2

R130      	Q_RES_0402LF   	          	          	                    
          	               	1         	125A4     	PWRGD_CPU1_LVC1_R   
          	               	2         	125A4     	PWRGD_CPU1_BUF_R    

R132      	Q_RES_0402LF   	          	          	                    
          	               	1         	125A4     	RST_CPU1_LVC1_R_N   
          	               	2         	125A4     	RST_CPU1_BUF_R_N    

R135      	Q_RES_0402LF   	          	          	                    
          	               	1         	125B2     	PWRGD_DRAMPWRGD_CPU1_AB_LVC1_R2
          	               	2         	125B2     	PVCCD_HV_CPU1       

R137      	Q_RES_0402LF   	          	          	                    
          	               	1         	125B2     	PWRGD_DRAMPWRGD_CPU1_CD_LVC1_R2
          	               	2         	125B2     	PVCCD_HV_CPU1       

R139      	Q_RES_0402LF   	          	          	                    
          	               	1         	220B2     	FM_BMC_PWRBTN_N     
          	               	2         	220B2     	P3V3_AUX            

R142      	Q_RES_0402LF   	          	          	                    
          	               	1         	240B4     	PVNN_TERM_CPU0      
          	               	2         	240B4     	PVCCIO_PECI_BMC     

R143      	Q_RES_0402LF   	          	          	                    
          	               	1         	197B4     	PECI_PCH            
          	               	2         	197B4     	PECI_PCH_R          

R144      	Q_RES_0402LF   	          	          	                    
          	               	1         	197B4     	PECI_BMC            
          	               	2         	197B4     	PECI_BMC_R          

R145      	Q_RES_0402LF   	          	          	                    
          	               	1         	197B4     	PVNN_TERM_CPU0      
          	               	2         	197B4     	PECI_PCH_R          

R146      	Q_RES_0402LF   	          	          	                    
          	               	1         	197B4     	PVNN_TERM_CPU0      
          	               	2         	197B4     	PECI_BMC_R          

R147      	Q_RES_0402LF   	          	          	                    
          	               	1         	197B4     	PECI_PCH_R          
          	               	2         	197B4     	GND                 

R148      	Q_RES_0402LF   	          	          	                    
          	               	1         	197B4     	PECI_BMC_R          
          	               	2         	197B4     	GND                 

R149      	Q_RES_0402LF   	          	          	                    
          	               	1         	197B3     	PECI_PCH_R          
          	               	2         	197B3     	PECI_PCH_B1         

R151      	Q_RES_0402LF   	          	          	                    
          	               	1         	125B2     	PWRGD_DRAMPWRGD_CPU1_EF_LVC1_R2
          	               	2         	125B2     	PVCCD_HV_CPU1       

R153      	Q_RES_0402LF   	          	          	                    
          	               	1         	125B2     	PWRGD_DRAMPWRGD_CPU1_GH_LVC1_R2
          	               	2         	125B2     	PVCCD_HV_CPU1       

R155      	Q_RES_0402LF   	          	          	                    
          	               	1         	125A2     	PWRGD_CPU1_BUF_R    
          	               	2         	125A2     	PVNN_TERM_CPU1      

R156      	Q_RES_0402LF   	          	          	                    
          	               	1         	125A2     	PWRGD_CPU1_BUF_R    
          	               	2         	125A2     	PWRGD_CPU1_LVC1     

R157      	Q_RES_0402LF   	          	          	                    
          	               	1         	125A2     	RST_CPU1_BUF_R_N    
          	               	2         	125A2     	PVNN_TERM_CPU1      

R158      	Q_RES_0402LF   	          	          	                    
          	               	1         	125A2     	RST_CPU1_BUF_R_N    
          	               	2         	125A2     	RST_CPU1_LVC1_N     

R160      	Q_RES_0402LF   	          	          	                    
          	               	1         	124B4     	PWRGD_DRAMPWRGD_CPU0_AB_R_LVC1
          	               	2         	124B4     	PWRGD_DRAMPWRGD_CPU0_AB_LVC1_R2

R162      	Q_RES_0402LF   	          	          	                    
          	               	1         	124B4     	PWRGD_DRAMPWRGD_CPU0_CD_R_LVC1
          	               	2         	124B4     	PWRGD_DRAMPWRGD_CPU0_CD_LVC1_R2

R164      	Q_RES_0402LF   	          	          	                    
          	               	1         	124B4     	PWRGD_DRAMPWRGD_CPU0_EF_R_LVC1
          	               	2         	124B4     	PWRGD_DRAMPWRGD_CPU0_EF_LVC1_R2

R166      	Q_RES_0402LF   	          	          	                    
          	               	1         	124B4     	PWRGD_DRAMPWRGD_CPU0_GH_R_LVC1
          	               	2         	124B4     	PWRGD_DRAMPWRGD_CPU0_GH_LVC1_R2

R168      	Q_RES_0402LF   	          	          	                    
          	               	1         	124A4     	PWRGD_CPU0_LVC1_R   
          	               	2         	124A4     	PWRGD_CPU0_BUF_R    

R171      	Q_RES_0402LF   	          	          	                    
          	               	1         	124A4     	RST_CPU0_LVC1_R_N   
          	               	2         	124A4     	RST_CPU0_BUF_R_N    

R175      	Q_RES_0402LF   	          	          	                    
          	               	1         	124B2     	PWRGD_DRAMPWRGD_CPU0_AB_LVC1_R2
          	               	2         	124B2     	PVCCD_HV_CPU0       

R177      	Q_RES_0402LF   	          	          	                    
          	               	1         	124B2     	PWRGD_DRAMPWRGD_CPU0_CD_LVC1_R2
          	               	2         	124B2     	PVCCD_HV_CPU0       

R179      	Q_RES_0402LF   	          	          	                    
          	               	1         	124B2     	PWRGD_DRAMPWRGD_CPU0_EF_LVC1_R2
          	               	2         	124B2     	PVCCD_HV_CPU0       

R181      	Q_RES_0402LF   	          	          	                    
          	               	1         	124B2     	PWRGD_DRAMPWRGD_CPU0_GH_LVC1_R2
          	               	2         	124B2     	PVCCD_HV_CPU0       

R183      	Q_RES_0402LF   	          	          	                    
          	               	1         	124A2     	PWRGD_CPU0_BUF_R    
          	               	2         	124A2     	PVNN_TERM_CPU0      

R184      	Q_RES_0402LF   	          	          	                    
          	               	1         	124A2     	PWRGD_CPU0_BUF_R    
          	               	2         	124A2     	PWRGD_CPU0_LVC1     

R185      	Q_RES_0402LF   	          	          	                    
          	               	1         	124A2     	RST_CPU0_BUF_R_N    
          	               	2         	124A2     	PVNN_TERM_CPU0      

R186      	Q_RES_0402LF   	          	          	                    
          	               	1         	124A2     	RST_CPU0_BUF_R_N    
          	               	2         	124A2     	RST_CPU0_LVC1_N     

R188      	Q_RES_0402LF   	          	          	                    
          	               	1         	123A3     	H_CPU_NMI_LVC1_R_N  
          	               	2         	123A3     	H_CPU_NMI_LVC1_N    

R195      	Q_RES_0402LF   	          	          	                    
          	               	1         	123A2     	H_CPU_NMI_LVC1_N    
          	               	2         	123A2     	H_CPU0_NMI_LVC1_N   

R196      	Q_RES_0402LF   	          	          	                    
          	               	1         	123A2     	H_CPU_NMI_LVC1_N    
          	               	2         	123A2     	H_CPU1_NMI_LVC1_N   

R197      	Q_RES_0402LF   	          	          	                    
          	               	1         	123A2     	PVNN_TERM_CPU0      
          	               	2         	123A2     	H_CPU0_NMI_LVC1_N   

R198      	Q_RES_0402LF   	          	          	                    
          	               	1         	123A2     	PVNN_TERM_CPU1      
          	               	2         	123A2     	H_CPU1_NMI_LVC1_N   

R200      	Q_RES_0402LF   	          	          	                    
          	               	1         	123B4     	PVNN_TERM_CPU0      
          	               	2         	123B4     	H_CPU0_MEMTRIP_LVC1_R_N

R202      	Q_RES_0402LF   	          	          	                    
          	               	1         	123B4     	PVNN_TERM_CPU1      
          	               	2         	123B4     	H_CPU1_MEMTRIP_LVC1_R_N

R203      	Q_RES_0402LF   	          	          	                    
          	               	1         	122B4     	H_CPU0_MEMHOT_OUT_LVC1_R_N
          	               	2         	122B4     	H_CPU0_MEMHOT_OUT_VT_R_N

R204      	Q_RES_0402LF   	          	          	                    
          	               	1         	122A4     	H_CPU1_MEMHOT_OUT_LVC1_R_N
          	               	2         	122A4     	H_CPU1_MEMHOT_OUT_VT_R_N

R205      	Q_RES_0402LF   	          	          	                    
          	               	1         	123B4     	H_CPU0_MEMTRIP_LVC1_R_N
          	               	2         	123B4     	H_CPU0_MEMTRIP_OUT_VT_R_N

R206      	Q_RES_0402LF   	          	          	                    
          	               	1         	123B4     	H_CPU1_MEMTRIP_LVC1_R_N
          	               	2         	123B4     	H_CPU1_MEMTRIP_OUT_VT_R_N

R208      	Q_RES_0402LF   	          	          	                    
          	               	1         	122B4     	H_CPU0_MEMHOT_IN_LVC1_R_N
          	               	2         	122B3     	H_CPU0_MEMHOT_IN_LVC1_R1_N

R210      	Q_RES_0402LF   	          	          	                    
          	               	1         	122B4     	H_CPU1_MEMHOT_IN_LVC1_R_N
          	               	2         	122B3     	H_CPU1_MEMHOT_IN_LVC1_R1_N

R219      	Q_RES_0402LF   	          	          	                    
          	               	1         	122B2     	PVNN_TERM_CPU0      
          	               	2         	122B2     	H_CPU0_MEMHOT_IN_LVC1_R1_N

R220      	Q_RES_0402LF   	          	          	                    
          	               	1         	122B2     	PVNN_TERM_CPU1      
          	               	2         	122B2     	H_CPU1_MEMHOT_IN_LVC1_R1_N

R223      	Q_RES_0402LF   	          	          	                    
          	               	1         	296A1     	P3V3_AUX            
          	               	2         	296A1     	IRQ_PVCCD_CPU1_VRHOT_LVC3_N

R237      	Q_RES_0402LF   	          	          	                    
          	               	1         	121B4     	H_CPU0_THERMTRIP_LVC1_R_N
          	               	2         	121B4     	H_CPU0_THERMTRIP_VT_R_N

R238      	Q_RES_0402LF   	          	          	                    
          	               	1         	121B4     	H_CPU1_THERMTRIP_LVC1_R_N
          	               	2         	121B4     	H_CPU1_THERMTRIP_VT_R_N

R239      	Q_RES_0402LF   	          	          	                    
          	               	1         	121B3     	H_CPU0_PROCHOT_LVC1_R_N
          	               	2         	121B3     	H_CPU0_PROCHOT_LVC1_N

R240      	Q_RES_0402LF   	          	          	                    
          	               	1         	121A3     	H_CPU1_PROCHOT_LVC1_R_N
          	               	2         	121A3     	H_CPU1_PROCHOT_LVC1_N

R241      	Q_RES_0402LF   	          	          	                    
          	               	1         	121B2     	P3V3                
          	               	2         	121B2     	H_CPU0_THERMTRIP_VT_N

R242      	Q_RES_0402LF   	          	          	                    
          	               	1         	121B2     	P3V3                
          	               	2         	121B2     	H_CPU1_THERMTRIP_VT_N

R243      	Q_RES_0402LF   	          	          	                    
          	               	1         	121B2     	PVNN_TERM_CPU0      
          	               	2         	121B2     	H_CPU0_PROCHOT_LVC1_N

R244      	Q_RES_0402LF   	          	          	                    
          	               	1         	121A2     	PVNN_TERM_CPU1      
          	               	2         	121A2     	H_CPU1_PROCHOT_LVC1_N

R249      	Q_RES_0402LF   	          	          	                    
          	               	1         	120B4     	PVNN_TERM_CPU0      
          	               	2         	120B4     	FM_S3M_CPU0_LVC1_GPIO_0

R250      	Q_RES_0402LF   	          	          	                    
          	               	1         	120B4     	PVNN_TERM_CPU0      
          	               	2         	120B4     	FM_S3M_CPU0_LVC1_GPIO_1

R251      	Q_RES_0402LF   	          	          	                    
          	               	1         	120B4     	PVNN_TERM_CPU0      
          	               	2         	120B4     	FM_S3M_CPU0_LVC1_GPIO_4

R252      	Q_RES_0402LF   	          	          	                    
          	               	1         	120B4     	PVNN_TERM_CPU0      
          	               	2         	120B4     	PUD_PCH_BOOT_MODE_CPU0

R253      	Q_RES_0402LF   	          	          	                    
          	               	1         	120B4     	PVNN_TERM_CPU0      
          	               	2         	120B4     	FM_S3M_CPU0_LVC1_GPIO_2

R254      	Q_RES_0402LF   	          	          	                    
          	               	1         	120B4     	PVNN_TERM_CPU0      
          	               	2         	120B4     	FM_S3M_CPU0_LVC1_GPIO_3

R255      	Q_RES_0402LF   	          	          	                    
          	               	1         	120B4     	PVNN_TERM_CPU1      
          	               	2         	120B4     	FM_S3M_CPU1_LVC1_GPIO_0

R256      	Q_RES_0402LF   	          	          	                    
          	               	1         	120B4     	PVNN_TERM_CPU1      
          	               	2         	120B4     	FM_S3M_CPU1_LVC1_GPIO_1

R257      	Q_RES_0402LF   	          	          	                    
          	               	1         	120A4     	PVNN_TERM_CPU1      
          	               	2         	120A4     	FM_S3M_CPU1_LVC1_GPIO_4

R258      	Q_RES_0402LF   	          	          	                    
          	               	1         	120A4     	PVNN_TERM_CPU1      
          	               	2         	120A4     	PUD_PCH_BOOT_MODE_CPU1

R259      	Q_RES_0402LF   	          	          	                    
          	               	1         	120A4     	PVNN_TERM_CPU1      
          	               	2         	120A4     	FM_S3M_CPU1_LVC1_GPIO_2

R260      	Q_RES_0402LF   	          	          	                    
          	               	1         	120A4     	PVNN_TERM_CPU1      
          	               	2         	120A4     	FM_S3M_CPU1_LVC1_GPIO_3

R261      	Q_RES_0402LF   	          	          	                    
          	               	1         	119A4     	PVNN_TERM_CPU1      
          	               	2         	119A4     	PU_CPU1_TXT_AGENT   

R262      	Q_RES_0402LF   	          	          	                    
          	               	1         	119A4     	PVNN_TERM_CPU1      
          	               	2         	119A4     	PU_CPU1_SAFE_MODE_BOOT

R263      	Q_RES_0402LF   	          	          	                    
          	               	1         	119A4     	PVNN_TERM_CPU1      
          	               	2         	119A4     	PU_CPU1_FRMAGENT    

R264      	Q_RES_0402LF   	          	          	                    
          	               	1         	119A4     	PVNN_TERM_CPU1      
          	               	2         	119A4     	H_CPU1_BMCINIT_LVC1 

R265      	Q_RES_0402LF   	          	          	                    
          	               	1         	119A4     	PVNN_TERM_CPU1      
          	               	2         	119A4     	PU_CPU1_SOCKET_ID0  

R266      	Q_RES_0402LF   	          	          	                    
          	               	1         	119A4     	PVNN_TERM_CPU1      
          	               	2         	119A4     	PU_CPU1_SOCKET_ID1  

R267      	Q_RES_0402LF   	          	          	                    
          	               	1         	119A4     	PVNN_TERM_CPU1      
          	               	2         	119A4     	PU_CPU1_SOCKET_ID2  

R268      	Q_RES_0402LF   	          	          	                    
          	               	1         	119A4     	PVNN_TERM_CPU1      
          	               	2         	119A4     	PU_CPU1_LEGACY_SKT  

R269      	Q_RES_0402LF   	          	          	                    
          	               	1         	223A2     	FM_ADR_MODE1        
          	               	2         	223A2     	FM_ADR_MODE1_R      

R270      	Q_RES_0402LF   	          	          	                    
          	               	1         	119A4     	P3V3_AUX            
          	               	2         	119A4     	FM_CPU1_PKGID0      

R271      	Q_RES_0402LF   	          	          	                    
          	               	1         	119A4     	P3V3_AUX            
          	               	2         	119A4     	FM_CPU1_PKGID1      

R272      	Q_RES_0402LF   	          	          	                    
          	               	1         	119A4     	P3V3_AUX            
          	               	2         	119A4     	FM_CPU1_PKGID2      

R273      	Q_RES_0402LF   	          	          	                    
          	               	1         	119A4     	P3V3_AUX            
          	               	2         	119A4     	FM_CPU1_PROC_ID0    

R274      	Q_RES_0402LF   	          	          	                    
          	               	1         	119A4     	P3V3_AUX            
          	               	2         	119A4     	FM_CPU1_PROC_ID1    

R275      	Q_RES_0402LF   	          	          	                    
          	               	1         	119B4     	PVNN_TERM_CPU0      
          	               	2         	119B4     	PU_CPU0_TXT_AGENT   

R276      	Q_RES_0402LF   	          	          	                    
          	               	1         	119B4     	PVNN_TERM_CPU0      
          	               	2         	119B4     	PU_CPU0_SAFE_MODE_BOOT

R277      	Q_RES_0402LF   	          	          	                    
          	               	1         	119B4     	PVNN_TERM_CPU0      
          	               	2         	119B4     	PU_CPU0_FRMAGENT    

R278      	Q_RES_0402LF   	          	          	                    
          	               	1         	119B4     	PVNN_TERM_CPU0      
          	               	2         	119B4     	H_CPU0_BMCINIT_LVC1 

R279      	Q_RES_0402LF   	          	          	                    
          	               	1         	119B4     	PVNN_TERM_CPU0      
          	               	2         	119B4     	PU_CPU0_SOCKET_ID0  

R280      	Q_RES_0402LF   	          	          	                    
          	               	1         	119B4     	PVNN_TERM_CPU0      
          	               	2         	119B4     	PU_CPU0_SOCKET_ID1  

R281      	Q_RES_0402LF   	          	          	                    
          	               	1         	119B4     	PVNN_TERM_CPU0      
          	               	2         	119B4     	PU_CPU0_SOCKET_ID2  

R282      	Q_RES_0402LF   	          	          	                    
          	               	1         	119B4     	PVNN_TERM_CPU0      
          	               	2         	119B4     	PU_CPU0_LEGACY_SKT  

R283      	Q_RES_0402LF   	          	          	                    
          	               	1         	119B4     	P3V3_AUX            
          	               	2         	119B4     	FM_CPU0_PKGID0      

R284      	Q_RES_0402LF   	          	          	                    
          	               	1         	119B4     	P3V3_AUX            
          	               	2         	119B4     	FM_CPU0_PKGID1      

R285      	Q_RES_0402LF   	          	          	                    
          	               	1         	119B4     	P3V3_AUX            
          	               	2         	119B4     	FM_CPU0_PKGID2      

R286      	Q_RES_0402LF   	          	          	                    
          	               	1         	119B4     	P3V3_AUX            
          	               	2         	119B4     	FM_CPU0_PROC_ID0    

R287      	Q_RES_0402LF   	          	          	                    
          	               	1         	119B4     	P3V3_AUX            
          	               	2         	119B4     	FM_CPU0_PROC_ID1    

R288      	Q_RES_0402LF   	          	          	                    
          	               	1         	119A2     	PVNN_TERM_CPU0      
          	               	2         	119A2     	PD_CPU1_TXT_PLTEN   

R289      	Q_RES_0402LF   	          	          	                    
          	               	1         	119A2     	PD_CPU1_TXT_PLTEN   
          	               	2         	119A2     	GND                 

R290      	Q_RES_0402LF   	          	          	                    
          	               	1         	119A4     	GND                 
          	               	2         	119A4     	PD_CPU1_DMIMODE_OVERRIDE

R291      	Q_RES_0402LF   	          	          	                    
          	               	1         	119A4     	GND                 
          	               	2         	119A4     	PD_CPU1_ENH_MCECC_DIS

R292      	Q_RES_0402LF   	          	          	                    
          	               	1         	119B2     	PVNN_TERM_CPU0      
          	               	2         	119B2     	PD_CPU0_TXT_PLTEN   

R293      	Q_RES_0402LF   	          	          	                    
          	               	1         	119B2     	PD_CPU0_TXT_PLTEN   
          	               	2         	119B2     	GND                 

R294      	Q_RES_0402LF   	          	          	                    
          	               	1         	119B4     	GND                 
          	               	2         	119B4     	PD_CPU0_DMIMODE_OVERRIDE

R295      	Q_RES_0402LF   	          	          	                    
          	               	1         	119B4     	GND                 
          	               	2         	119B4     	PD_CPU0_ENH_MCECC_DIS

R296      	Q_RES_0402LF   	          	          	                    
          	               	1         	118B4     	PVNN_TERM_CPU0      
          	               	2         	118B4     	H_CPU_CATERR_LVC1_R_N

R297      	Q_RES_0402LF   	          	          	                    
          	               	1         	118B4     	H_CPU0_CATERR_LVC1_R_N
          	               	2         	118B4     	H_CPU_CATERR_LVC1_R_N

R298      	Q_RES_0402LF   	          	          	                    
          	               	1         	118B4     	PVNN_TERM_CPU1      
          	               	2         	118B4     	H_CPU_CATERR_LVC1_R_N

R299      	Q_RES_0402LF   	          	          	                    
          	               	1         	118B4     	H_CPU1_CATERR_LVC1_R_N
          	               	2         	118B4     	H_CPU_CATERR_LVC1_R_N

R301      	Q_RES_0402LF   	          	          	                    
          	               	1         	118B4     	PVNN_TERM_CPU0      
          	               	2         	118B4     	H_CPU_RMCA_LVC1_R_N 

R302      	Q_RES_0402LF   	          	          	                    
          	               	1         	118B4     	H_CPU0_RMCA_LVC1_R_N
          	               	2         	118B4     	H_CPU_RMCA_LVC1_R_N 

R303      	Q_RES_0402LF   	          	          	                    
          	               	1         	118B4     	PVNN_TERM_CPU1      
          	               	2         	118B4     	H_CPU_RMCA_LVC1_R_N 

R304      	Q_RES_0402LF   	          	          	                    
          	               	1         	118B4     	H_CPU1_RMCA_LVC1_R_N
          	               	2         	118B4     	H_CPU_RMCA_LVC1_R_N 

R307      	Q_RES_0402LF   	          	          	                    
          	               	1         	284B4     	P3V3_AUX            
          	               	2         	284B4     	PWRGD_PVCCIN_CPU1_R 

R308      	Q_RES_0402LF   	          	          	                    
          	               	1         	284B4     	PWRGD_PVCCIN_CPU1   
          	               	2         	284B4     	PWRGD_PVCCIN_CPU1_R 

R309      	Q_RES_0402LF   	          	          	                    
          	               	1         	284B4     	FM_PVCCIN_CPU1_EN   
          	               	2         	284B4     	PVCCIN_CPU1_EN_R    

R310      	Q_RES_0402LF   	          	          	                    
          	               	1         	284B4     	SVID_CLK0_CPU1_R    
          	               	2         	284B4     	SVID_CLK_PVCCIN_CPU1_R

R311      	Q_RES_0402LF   	          	          	                    
          	               	1         	284B4     	SVID_DIO0_CPU1_R    
          	               	2         	284B4     	SVID_DIO_PVCCIN_CPU1_R

R312      	Q_RES_0402LF   	          	          	                    
          	               	1         	284B4     	SVID_ALERT0_CPU1_R_N
          	               	2         	284B4     	SVID_ALERT_PVCCIN_CPU1_R

R315      	Q_RES_0402LF   	          	          	                    
          	               	1         	118A4     	PWRGD_CPUPWRGD_GTL  
          	               	2         	118A4     	PWRGD_CPUPWRGD_LVC1_R

R318      	Q_RES_0402LF   	          	          	                    
          	               	1         	229A1     	FM_SPD_REMOTE_EN    
          	               	2         	229A1     	GND                 

R319      	Q_RES_0402LF   	          	          	                    
          	               	1         	80A4      	P3V3_AUX            
          	               	2         	80A4      	PU_S3M_CPU0_CPLD_STATUS

R320      	Q_RES_0402LF   	          	          	                    
          	               	1         	80A4      	P3V3_AUX            
          	               	2         	80A4      	PU_S3M_CPU0_CPLD_CONFD

R321      	Q_RES_0402LF   	          	          	                    
          	               	1         	80A4      	P3V3_AUX            
          	               	2         	80A4      	FM_S3M_CPU0_CPLD_CONFIG_N

R322      	Q_RES_0402LF   	          	          	                    
          	               	1         	14A4      	H_CPU0_PMSYNC_CPU1_R
          	               	2         	14A3      	H_CPU0_PMSYNC_CPU1_R1

R323      	Q_RES_1206LF   	          	          	                    
          	               	1         	80B4      	PVCCINFAON_CPU0     
          	               	2         	80B4      	PVNN_TERM_CPU0      

R324      	Q_RES_1206LF   	          	          	                    
          	               	1         	80B4      	PVNN_MAIN_CPU0      
          	               	2         	80B4      	PVNN_TERM_CPU0      

R325      	Q_RES_0402LF   	          	          	                    
          	               	1         	80A2      	P3V3_AUX            
          	               	2         	80A2      	PU_S3M_CPU1_CPLD_STATUS

R326      	Q_RES_0402LF   	          	          	                    
          	               	1         	80A2      	P3V3_AUX            
          	               	2         	80A2      	PU_S3M_CPU1_CPLD_CONFD

R327      	Q_RES_0402LF   	          	          	                    
          	               	1         	80A2      	P3V3_AUX            
          	               	2         	80A2      	FM_S3M_CPU1_CPLD_CONFIG_N

R328      	Q_RES_0402LF   	          	          	                    
          	               	1         	14A1      	SVID_DIO0_CPU0_R    
          	               	2         	14A1      	PVNN_TERM_CPU0      

R329      	Q_RES_1206LF   	          	          	                    
          	               	1         	80B2      	PVCCINFAON_CPU1     
          	               	2         	80B2      	PVNN_TERM_CPU1      

R330      	Q_RES_1206LF   	          	          	                    
          	               	1         	80B2      	PVNN_MAIN_CPU1      
          	               	2         	80B2      	PVNN_TERM_CPU1      

R331      	Q_RES_0402LF   	          	          	                    
          	               	1         	127B4     	P3V3_AUX            
          	               	2         	127B4     	PD_PIROM_CPU0_ADDR2 

R332      	Q_RES_0402LF   	          	          	                    
          	               	1         	127B4     	PD_PIROM_CPU0_ADDR2 
          	               	2         	127B4     	GND                 

R333      	Q_RES_0402LF   	          	          	                    
          	               	1         	127B4     	P3V3_AUX            
          	               	2         	127B4     	PD_PIROM_CPU0_ADDR1 

R334      	Q_RES_0402LF   	          	          	                    
          	               	1         	127B4     	PD_PIROM_CPU0_ADDR1 
          	               	2         	127B4     	GND                 

R335      	Q_RES_0402LF   	          	          	                    
          	               	1         	127B4     	P3V3_AUX            
          	               	2         	127B4     	PD_PIROM_CPU0_ADDR0 

R336      	Q_RES_0402LF   	          	          	                    
          	               	1         	225A4     	H_CPU0_ERR0_LVC1_R_N
          	               	2         	225A4     	H_CPU_ERR0_LVC1_R_N 

R337      	Q_RES_0402LF   	          	          	                    
          	               	1         	225A4     	H_CPU1_ERR0_LVC1_R_N
          	               	2         	225A4     	H_CPU_ERR0_LVC1_R_N 

R338      	Q_RES_0402LF   	          	          	                    
          	               	1         	225A4     	H_CPU_ERR0_LVC1_R_N 
          	               	2         	225A4     	H_CPU_ERR0_LVC1_N   

R340      	Q_RES_0402LF   	          	          	                    
          	               	1         	225A4     	H_CPU0_ERR1_LVC1_R_N
          	               	2         	225A4     	H_CPU_ERR1_LVC1_R_N 

R341      	Q_RES_0402LF   	          	          	                    
          	               	1         	225A4     	H_CPU1_ERR1_LVC1_R_N
          	               	2         	225A4     	H_CPU_ERR1_LVC1_R_N 

R342      	Q_RES_0402LF   	          	          	                    
          	               	1         	225A4     	H_CPU_ERR1_LVC1_R_N 
          	               	2         	225A4     	H_CPU_ERR1_LVC1_N   

R344      	Q_RES_0402LF   	          	          	                    
          	               	1         	225A4     	H_CPU0_ERR2_LVC1_R_N
          	               	2         	225A4     	H_CPU_ERR2_LVC1_R_N 

R345      	Q_RES_0402LF   	          	          	                    
          	               	1         	225A4     	H_CPU1_ERR2_LVC1_R_N
          	               	2         	225A4     	H_CPU_ERR2_LVC1_R_N 

R346      	Q_RES_0402LF   	          	          	                    
          	               	1         	225A4     	H_CPU_ERR2_LVC1_R_N 
          	               	2         	225A4     	H_CPU_ERR2_LVC1_N   

R361      	Q_RES_0402LF   	          	          	                    
          	               	1         	278B4     	P3V3_AUX            
          	               	2         	278B4     	PWRGD_PVCCD_HV_CPU0_R

R362      	Q_RES_0402LF   	          	          	                    
          	               	1         	278B4     	PWRGD_PVCCD_HV_CPU0 
          	               	2         	278B4     	PWRGD_PVCCD_HV_CPU0_R

R363      	Q_RES_0402LF   	          	          	                    
          	               	1         	278B4     	FM_PVCCD_HV_CPU0_EN 
          	               	2         	278B4     	PVCCD_HV_CPU0_EN_R  

R365      	Q_RES_0402LF   	          	          	                    
          	               	1         	218A4     	FM_CPU_RMCA_CATERR_LVT3_R_N
          	               	2         	218A4     	CPU_RMCA_CATERR_LVT3_N

R366      	Q_RES_0402LF   	          	          	                    
          	               	1         	218B3     	P3V3_AUX            
          	               	2         	218B3     	LED_CPU_RMCA_CATERR 

R367      	Q_RES_0402LF   	          	          	                    
          	               	1         	198B4     	P3V3_AUX            
          	               	2         	198B4     	FM_PCH_SPKR         

R369      	Q_RES_0402LF   	          	          	                    
          	               	1         	198A4     	P3V3_AUX            
          	               	2         	198A4     	FM_ADR_ACK          

R371      	Q_RES_0402LF   	          	          	                    
          	               	1         	198B3     	P3V3_AUX            
          	               	2         	198B3     	FM_PCH_BOOT_BIOS_STRAP

R372      	Q_RES_0402LF   	          	          	                    
          	               	1         	198B3     	FM_PCH_BOOT_BIOS_STRAP
          	               	2         	198B3     	GND                 

R374      	Q_RES_0402LF   	          	          	                    
          	               	1         	198A3     	P3V3_AUX            
          	               	2         	198A3     	FM_SPI_3V3_1V8_VOLTAGE

R375      	Q_RES_0402LF   	          	          	                    
          	               	1         	198A3     	FM_SPI_3V3_1V8_VOLTAGE
          	               	2         	198A3     	GND                 

R378      	Q_RES_0402LF   	          	          	                    
          	               	1         	198B2     	P3V3_AUX            
          	               	2         	198B2     	FM_ADR_MODE1        

R379      	Q_RES_0402LF   	          	          	                    
          	               	1         	198B2     	FM_ADR_MODE1        
          	               	2         	198B2     	GND                 

R380      	Q_RES_0402LF   	          	          	                    
          	               	1         	198A2     	P3V3_AUX            
          	               	2         	198A2     	FM_FLASH_SECURITY_STRAP

R381      	Q_RES_0402LF   	          	          	                    
          	               	1         	198A2     	FM_FLASH_SECURITY_STRAP
          	               	2         	198A2     	GND                 

R401      	Q_RES_0402LF   	          	          	                    
          	               	1         	204A4     	P3V3_AUX            
          	               	2         	204A4     	IRQ_TPM_SPI_N       

R409      	Q_RES_0402LF   	          	          	                    
          	               	1         	153A4     	P3V3_OCP_SFF        
          	               	2         	153A4     	OCP_SFF_ID0         

R410      	Q_RES_0402LF   	          	          	                    
          	               	1         	153A4     	OCP_SFF_ID0         
          	               	2         	153A4     	GND                 

R413      	Q_RES_0402LF   	          	          	                    
          	               	1         	159B4     	GND                 
          	               	2         	159B4     	FM_OCP_V3_2_PWR_GOOD

R414      	Q_RES_0402LF   	          	          	                    
          	               	1         	153A4     	P3V3_OCP_SFF        
          	               	2         	153A4     	OCP_SFF_ID1         

R415      	Q_RES_0402LF   	          	          	                    
          	               	1         	153A4     	OCP_SFF_ID1         
          	               	2         	153A4     	GND                 

R416      	Q_RES_0402LF   	          	          	                    
          	               	1         	153B4     	OCP_SFF_ISO_BIF0_EN 
          	               	2         	153B4     	OCP_SFF_BIF0_R_N    

R417      	Q_RES_0402LF   	          	          	                    
          	               	1         	153B4     	OCP_SFF_ISO_BIF1_EN 
          	               	2         	153B4     	OCP_SFF_BIF1_R_N    

R418      	Q_RES_0402LF   	          	          	                    
          	               	1         	153B4     	OCP_SFF_ISO_BIF2_EN 
          	               	2         	153B4     	OCP_SFF_BIF2_R_N    

R419      	Q_RES_0402LF   	          	          	                    
          	               	1         	155B3     	RST_OCP_V3_1_BUF_N  
          	               	2         	155B3     	RST_PERST0_OCP_SFF_N

R420      	Q_RES_0402LF   	          	          	                    
          	               	1         	153A3     	SGPIO_OCP_SFF_LD_N  
          	               	2         	153A3     	P3V3_OCP_SFF        

R421      	Q_RES_0402LF   	          	          	                    
          	               	1         	153A3     	SGPIO_OCP_SFF_DATAIN
          	               	2         	153A3     	P3V3_OCP_SFF        

R422      	Q_RES_0402LF   	          	          	                    
          	               	1         	153A3     	SGPIO_OCP_SFF_DATAOUT
          	               	2         	153A3     	GND                 

R423      	Q_RES_0402LF   	          	          	                    
          	               	1         	153A3     	SGPIO_OCP_SFF_CLK   
          	               	2         	153A3     	P3V3_OCP_SFF        

R424      	Q_RES_0402LF   	          	          	                    
          	               	1         	153B2     	SMB_OCP_SFF_3V3AUX_BUF_R_SCL
          	               	2         	153B2     	SMB_OCP_SFF_3V3AUX_BUF_SCL

R425      	Q_RES_0402LF   	          	          	                    
          	               	1         	153B2     	SMB_OCP_SFF_3V3AUX_BUF_R_SDA
          	               	2         	153B2     	SMB_OCP_SFF_3V3AUX_BUF_SDA

R429      	Q_RES_0402LF   	          	          	                    
          	               	1         	153B4     	OCP_SFF_MAIN_PWR_EN 
          	               	2         	153B4     	OCP_SFF_MAIN_PWR_EN_R

R435      	Q_RES_0402LF   	          	          	                    
          	               	1         	155B3     	RST_OCP_V3_1_BUF_N  
          	               	2         	155B3     	RST_PERST1_OCP_SFF_N

R442      	Q_RES_0603LF   	          	          	                    
          	               	1         	210B4     	P3V3_AUX_CLK_GEN_VDDXTAL_CK440
          	               	2         	210B4     	P3V3_AUX_CLK_GEN_VDDA25M_CK440

R444      	Q_RES_0402LF   	          	          	                    
          	               	1         	153A2     	OCP_SFF_USB2_3_DN   
          	               	2         	153A2     	USB2_3_DN           

R445      	Q_RES_0402LF   	          	          	                    
          	               	1         	153A2     	OCP_SFF_USB2_3_DP   
          	               	2         	153A2     	USB2_3_DP           

R447      	Q_RES_0603LF   	          	          	                    
          	               	1         	210B4     	P3V3_AUX_CLK_GEN_VDDMXCK_CK440
          	               	2         	210B4     	P3V3_AUX_CLK_GEN_VDDPT_CK440

R448      	Q_RES_0402LF   	          	          	                    
          	               	1         	236A2     	SMB_S3M_CPU0_3V3AUX_SCL
          	               	2         	236A2     	SMB_S3M_CPU1_3V3AUX_SCL

R453      	Q_RES_0402LF   	          	          	                    
          	               	1         	182B4     	P3V3_AUX            
          	               	2         	182B4     	PU_LAN_WAKE_N       

R456      	Q_RES_0402LF   	          	          	                    
          	               	1         	204B3     	P3V3_AUX            
          	               	2         	204B3     	PU_PCH_PMCALERT_N   

R474      	Q_RES_0402LF   	          	          	                    
          	               	1         	183A2     	FM_PCHHOT_N         
          	               	2         	183A2     	FM_PCHHOT_R_N       

R477      	Q_RES_0402LF   	          	          	                    
          	               	1         	179B4     	PD_PCH_XCLK_BIASREF 
          	               	2         	179B4     	GND                 

R478      	Q_RES_0402LF   	          	          	                    
          	               	1         	190B4     	P3V3_AUX            
          	               	2         	190B4     	PCIE_M2_SSD0_PRSNT_N

R480      	Q_RES_0402LF   	          	          	                    
          	               	1         	239B4     	JTAG_DBP_TMS        
          	               	2         	239B4     	JTAG_DBP_FB_TMS     

R481      	Q_RES_0402LF   	          	          	                    
          	               	1         	239B4     	JTAG_DBP_TDI        
          	               	2         	239B4     	JTAG_DBP_FB_TDI     

R482      	Q_RES_0402LF   	          	          	                    
          	               	1         	239B4     	JTAG_DBP_PREQ_N     
          	               	2         	239B4     	JTAG_DBP_PREQ_R_N   

R483      	Q_RES_0402LF   	          	          	                    
          	               	1         	239B2     	JTAG_BMC_DBP_TDO_R  
          	               	2         	239B2     	JTAG_BMC_DBP_TDO    

R486      	Q_RES_0402LF   	          	          	                    
          	               	1         	190B4     	M2_SSD0_CLKREQ_EN_N 
          	               	2         	190B4     	M2_SSD0_CLKREQ_EN_N_BUF

R487      	Q_RES_0402LF   	          	          	                    
          	               	1         	190B4     	P3V3_AUX            
          	               	2         	190B4     	M2_SSD0_CLKREQ_EN_N_BUF

R491      	Q_RES_0402LF   	          	          	                    
          	               	1         	190B4     	M2_SSD0_CLKREQ_EN_N 
          	               	2         	190B4     	GND                 

R494      	Q_RES_0402LF   	          	          	                    
          	               	1         	182B4     	P3V3_AUX            
          	               	2         	182B4     	IRQ_LVC3_WAKE_N     

R495      	Q_RES_0402LF   	          	          	                    
          	               	1         	181B4     	PCH_PCIEUP_RCOMPP   
          	               	2         	181B4     	PCH_PCIEUP_RCOMPN   

R496      	Q_RES_0402LF   	          	          	                    
          	               	1         	180B4     	PD_PCH_USB2_COMP    
          	               	2         	180B4     	GND                 

R497      	Q_RES_0402LF   	          	          	                    
          	               	1         	187B2     	PD_RCOMP_1P8_3P3    
          	               	2         	187B2     	GND                 

R498      	Q_RES_0402LF   	          	          	                    
          	               	1         	185B2     	P3V3_AUX            
          	               	2         	185B2     	FM_PCH_PRSNT_N      

R499      	Q_RES_0402LF   	          	          	                    
          	               	1         	185A2     	SPI_PCH_CLK         
          	               	2         	185A2     	SPI_SYS_CLK         

R501      	Q_RES_0402LF   	          	          	                    
          	               	1         	185A2     	SPI_PCH_CS0_R_N     
          	               	2         	185A2     	SPI_SYS_CS0_N       

R502      	Q_RES_0402LF   	          	          	                    
          	               	1         	198B2     	P3V3_AUX            
          	               	2         	198B2     	FM_PCH_CONSENT_STRAP_N

R506      	Q_RES_0402LF   	          	          	                    
          	               	1         	240A4     	IRQ_SMI_ACTIVE_BMC_N
          	               	2         	240A4     	IRQ0_A57            

R515      	Q_RES_0402LF   	          	          	                    
          	               	1         	127B4     	PD_PIROM_CPU0_ADDR0 
          	               	2         	127B4     	GND                 

R519      	Q_RES_0603LF   	          	          	                    
          	               	1         	210B4     	P3V3_AUX_CLK_GEN_VDD_CK440
          	               	2         	210B4     	P3V3_AUX_CLK_GEN_VDDA100M_CK440

R536      	Q_RES_0402LF   	          	          	                    
          	               	1         	231B4     	P3V3_AUX            
          	               	2         	231B4     	PCA9548_PCIE3_ADDR2 

R537      	Q_RES_0402LF   	          	          	                    
          	               	1         	231A4     	PCA9548_PCIE3_ADDR2 
          	               	2         	231A4     	GND                 

R538      	Q_RES_0402LF   	          	          	                    
          	               	1         	231B4     	P3V3_AUX            
          	               	2         	231B4     	PCA9548_PCIE3_ADDR1 

R539      	Q_RES_0402LF   	          	          	                    
          	               	1         	231A4     	PCA9548_PCIE3_ADDR1 
          	               	2         	231A4     	GND                 

R540      	Q_RES_0402LF   	          	          	                    
          	               	1         	231B4     	P3V3_AUX            
          	               	2         	231B4     	PCA9548_PCIE3_ADDR0 

R548      	Q_RES_0402LF   	          	          	                    
          	               	1         	14A1      	SVID_ALERT0_CPU0_R_N
          	               	2         	14A1      	PVNN_TERM_CPU0      

R553      	Q_RES_0402LF   	          	          	                    
          	               	1         	209B2     	CLK_100M_CK440_PCH_EXTCLK_R_DP
          	               	2         	209B2     	CLK_100M_CK440_PCH_EXTCLK_DP

R554      	Q_RES_0402LF   	          	          	                    
          	               	1         	209B2     	CLK_100M_CK440_PCH_EXTCLK_R_DN
          	               	2         	209B2     	CLK_100M_CK440_PCH_EXTCLK_DN

R555      	Q_RES_0402LF   	          	          	                    
          	               	1         	14A1      	SVID_DIO1_CPU0_R    
          	               	2         	14A1      	PVNN_TERM_CPU0      

R556      	Q_RES_0402LF   	          	          	                    
          	               	1         	14A1      	SVID_ALERT1_CPU0_R_N
          	               	2         	14A1      	PVNN_TERM_CPU0      

R557      	Q_RES_0402LF   	          	          	                    
          	               	1         	45A2      	SVID_DIO0_CPU1_R    
          	               	2         	45A1      	PVNN_TERM_CPU1      

R558      	Q_RES_0402LF   	          	          	                    
          	               	1         	45A2      	SVID_ALERT0_CPU1_R_N
          	               	2         	45A1      	PVNN_TERM_CPU1      

R559      	Q_RES_0402LF   	          	          	                    
          	               	1         	45A2      	SVID_DIO1_CPU1_R    
          	               	2         	45A1      	PVNN_TERM_CPU1      

R560      	Q_RES_0402LF   	          	          	                    
          	               	1         	45A2      	SVID_ALERT1_CPU1_R_N
          	               	2         	45A1      	PVNN_TERM_CPU1      

R563      	Q_RES_0402LF   	          	          	                    
          	               	1         	209B4     	CLK_100M_OCP_SFF_0_R_DP
          	               	2         	209B4     	CLK_100M_OCP_SFF_0_DP

R564      	Q_RES_0402LF   	          	          	                    
          	               	1         	209B4     	CLK_100M_OCP_SFF_0_R_DN
          	               	2         	209B4     	CLK_100M_OCP_SFF_0_DN

R565      	Q_RES_0402LF   	          	          	                    
          	               	1         	209B4     	CLK_100M_OCP_SFF_1_R_DP
          	               	2         	209B4     	CLK_100M_OCP_SFF_1_DP

R566      	Q_RES_0402LF   	          	          	                    
          	               	1         	209B4     	CLK_100M_OCP_SFF_1_R_DN
          	               	2         	209B4     	CLK_100M_OCP_SFF_1_DN

R567      	Q_RES_0402LF   	          	          	                    
          	               	1         	206B4     	P3V3                
          	               	2         	206B4     	PD_DB2000_SMB_SA1   

R568      	Q_RES_0402LF   	          	          	                    
          	               	1         	206A4     	PD_DB2000_SMB_SA1   
          	               	2         	206A4     	GND                 

R569      	Q_RES_0402LF   	          	          	                    
          	               	1         	206B4     	P3V3                
          	               	2         	206B4     	PD_DB2000_SMB_SA0   

R570      	Q_RES_0402LF   	          	          	                    
          	               	1         	206A4     	PD_DB2000_SMB_SA0   
          	               	2         	206A4     	GND                 

R571      	Q_RES_0603LF   	          	          	                    
          	               	1         	206B4     	P3V3_DB2000_FB_VDD  
          	               	2         	206B4     	P3V3_DB2000_VDDR    

R572      	Q_RES_0603LF   	          	          	                    
          	               	1         	206B4     	P3V3_DB2000_FB_VDD  
          	               	2         	206B4     	P3V3_DB2000_VDDA    

R573      	Q_RES_0402LF   	          	          	                    
          	               	1         	206A4     	P3V3                
          	               	2         	206A4     	FM_DB2000_VSBEN     

R574      	Q_RES_0402LF   	          	          	                    
          	               	1         	206A4     	FM_DB2000_VSBEN     
          	               	2         	206A4     	GND                 

R575      	Q_RES_0402LF   	          	          	                    
          	               	1         	206B3     	FM_PLD_CLKS_DEV_EN  
          	               	2         	206B3     	FM_DB2000_DEV_EN    

R576      	Q_RES_0402LF   	          	          	                    
          	               	1         	206B3     	FM_DB2000_OE_N      
          	               	2         	206B3     	FM_DB2000_1_OE_N    

R577      	Q_RES_0402LF   	          	          	                    
          	               	1         	241B4     	SMB_HOST_3V3AUX_SCL_R4
          	               	2         	241B4     	SMB_HOST_3V3AUX_SCL_R

R578      	Q_RES_0402LF   	          	          	                    
          	               	1         	241B4     	SMB_HOST_3V3AUX_SDA_R4
          	               	2         	241B4     	SMB_HOST_3V3AUX_SDA_R

R579      	Q_RES_0402LF   	          	          	                    
          	               	1         	241B4     	SMB_HOST_3V3AUX_SCL_R5
          	               	2         	241B4     	SMB_HOST_BMC_3V3AUX_SCL

R580      	Q_RES_0402LF   	          	          	                    
          	               	1         	241B4     	SMB_HOST_3V3AUX_SDA_R5
          	               	2         	241B4     	SMB_HOST_BMC_3V3AUX_SDA

R581      	Q_RES_0402LF   	          	          	                    
          	               	1         	241B4     	SMB_SML0_3V3AUX_SCL 
          	               	2         	241B4     	SMB_SML0_3V3AUX_PCH_SCL

R582      	Q_RES_0402LF   	          	          	                    
          	               	1         	241B4     	SMB_SML0_3V3AUX_SDA 
          	               	2         	241B4     	SMB_SML0_3V3AUX_PCH_SDA

R587      	Q_RES_0402LF   	          	          	                    
          	               	1         	231A4     	PCA9548_PCIE3_ADDR0 
          	               	2         	231A4     	GND                 

R588      	Q_RES_0402LF   	          	          	                    
          	               	1         	231B2     	SMB_PCIE0_3V3AUX_SCL
          	               	2         	231B2     	SMB_PCIE0_3V3AUX_SCL_R

R589      	Q_RES_0402LF   	          	          	                    
          	               	1         	231B2     	SMB_PCIE0_3V3AUX_SDA
          	               	2         	231B2     	SMB_PCIE0_3V3AUX_SDA_R

R592      	Q_RES_0402LF   	          	          	                    
          	               	1         	241B1     	SMB_FAN_3V3AUX_SCL  
          	               	2         	241B1     	P3V3_AUX            

R593      	Q_RES_0402LF   	          	          	                    
          	               	1         	241A2     	I3C_SPD_DDRABCD_CPU0_BMC_R_SCL
          	               	2         	241A2     	I3C_SPD_DDRABCD_CPU0_BMC_SCL

R594      	Q_RES_0402LF   	          	          	                    
          	               	1         	241A2     	I3C_SPD_DDRABCD_CPU0_BMC_R_SDA
          	               	2         	241A2     	I3C_SPD_DDRABCD_CPU0_BMC_SDA

R595      	Q_RES_0402LF   	          	          	                    
          	               	1         	241A2     	I3C_SPD_DDREFGH_CPU0_BMC_R_SCL
          	               	2         	241A2     	I3C_SPD_DDREFGH_CPU0_BMC_SCL

R596      	Q_RES_0402LF   	          	          	                    
          	               	1         	241A2     	I3C_SPD_DDREFGH_CPU0_BMC_R_SDA
          	               	2         	241A2     	I3C_SPD_DDREFGH_CPU0_BMC_SDA

R597      	Q_RES_0402LF   	          	          	                    
          	               	1         	241A2     	I3C_SPD_DDRABCD_CPU1_BMC_R_SCL
          	               	2         	241A2     	I3C_SPD_DDRABCD_CPU1_BMC_SCL

R598      	Q_RES_0402LF   	          	          	                    
          	               	1         	241A2     	I3C_SPD_DDRABCD_CPU1_BMC_R_SDA
          	               	2         	241A2     	I3C_SPD_DDRABCD_CPU1_BMC_SDA

R599      	Q_RES_0402LF   	          	          	                    
          	               	1         	241A2     	I3C_SPD_DDREFGH_CPU1_BMC_R_SCL
          	               	2         	241A2     	I3C_SPD_DDREFGH_CPU1_BMC_SCL

R600      	Q_RES_0402LF   	          	          	                    
          	               	1         	241A2     	I3C_SPD_DDREFGH_CPU1_BMC_R_SDA
          	               	2         	241A2     	I3C_SPD_DDREFGH_CPU1_BMC_SDA

R601      	Q_RES_0402LF   	          	          	                    
          	               	1         	241B1     	SMB_FAN_3V3AUX_SDA  
          	               	2         	241B1     	P3V3_AUX            

R607      	Q_RES_0402LF   	          	          	                    
          	               	1         	199B4     	P3V3_AUX            
          	               	2         	199B4     	FM_ESPI_FLASH_MODE  

R608      	Q_RES_0402LF   	          	          	                    
          	               	1         	199B4     	FM_ESPI_FLASH_MODE  
          	               	2         	199B4     	GND                 

R609      	Q_RES_0402LF   	          	          	                    
          	               	1         	199B4     	P3V3_AUX            
          	               	2         	199B4     	FM_ESPI_CS_SWIZZLE  

R610      	Q_RES_0402LF   	          	          	                    
          	               	1         	199B4     	FM_ESPI_CS_SWIZZLE  
          	               	2         	199B4     	GND                 

R611      	Q_RES_0402LF   	          	          	                    
          	               	1         	199A4     	P3V3_AUX            
          	               	2         	199A4     	FM_PCH_EXTERNALCLKMODE

R612      	Q_RES_0402LF   	          	          	                    
          	               	1         	199A4     	FM_PCH_EXTERNALCLKMODE
          	               	2         	199A4     	GND                 

R613      	Q_RES_0402LF   	          	          	                    
          	               	1         	199B3     	P3V3_AUX            
          	               	2         	199B3     	FM_JTAG_ODT_DISABLE 

R614      	Q_RES_0402LF   	          	          	                    
          	               	1         	199B3     	FM_JTAG_ODT_DISABLE 
          	               	2         	199B3     	GND                 

R615      	Q_RES_0402LF   	          	          	                    
          	               	1         	199B3     	P3V3_AUX            
          	               	2         	199B3     	FM_PCH_VISA_DEFAULT 

R617      	Q_RES_0402LF   	          	          	                    
          	               	1         	199A3     	P3V3_AUX            
          	               	2         	199A3     	FM_PCH_IO_EXPANDER  

R618      	Q_RES_0402LF   	          	          	                    
          	               	1         	199A3     	FM_PCH_IO_EXPANDER  
          	               	2         	199A3     	GND                 

R619      	Q_RES_0402LF   	          	          	                    
          	               	1         	199B2     	P3V3_AUX            
          	               	2         	199B2     	FM_LT_KEY_DOWNGRADE_N

R621      	Q_RES_0402LF   	          	          	                    
          	               	1         	199B2     	P3V3_AUX            
          	               	2         	199B2     	FM_PCH_SKIP_RTC_CLOCK

R622      	Q_RES_0402LF   	          	          	                    
          	               	1         	199B2     	FM_PCH_SKIP_RTC_CLOCK
          	               	2         	199B2     	GND                 

R623      	Q_RES_0402LF   	          	          	                    
          	               	1         	199A2     	P3V3_AUX            
          	               	2         	199A2     	FM_PCH_XTALSEL      

R624      	Q_RES_0402LF   	          	          	                    
          	               	1         	199A2     	FM_PCH_XTALSEL      
          	               	2         	199A2     	GND                 

R625      	Q_RES_0402LF   	          	          	                    
          	               	1         	127B3     	P3V3_AUX            
          	               	2         	127B3     	PD_PIROM_CPU1_ADDR2 

R626      	Q_RES_0402LF   	          	          	                    
          	               	1         	127B3     	PD_PIROM_CPU1_ADDR2 
          	               	2         	127B3     	GND                 

R627      	Q_RES_0402LF   	          	          	                    
          	               	1         	127B3     	P3V3_AUX            
          	               	2         	127B3     	PD_PIROM_CPU1_ADDR1 

R628      	Q_RES_0402LF   	          	          	                    
          	               	1         	127B3     	PD_PIROM_CPU1_ADDR1 
          	               	2         	127B3     	GND                 

R629      	Q_RES_0402LF   	          	          	                    
          	               	1         	127B3     	P3V3_AUX            
          	               	2         	127B3     	PU_PIROM_CPU1_ADDR0 

R630      	Q_RES_0402LF   	          	          	                    
          	               	1         	127B3     	PU_PIROM_CPU1_ADDR0 
          	               	2         	127B3     	GND                 

R635      	Q_RES_0402LF   	          	          	                    
          	               	1         	183A2     	PU_OC3_USB_N        
          	               	2         	183A1     	P3V3_AUX            

R650      	Q_RES_0402LF   	          	          	                    
          	               	1         	127B4     	P3V3_AUX            
          	               	2         	127B4     	PU_PIROM_CPU0_SM_WP 

R651      	Q_RES_0402LF   	          	          	                    
          	               	1         	231A2     	P3V3_AUX            
          	               	2         	231A2     	SMB_FRU_3V3AUX_SCL  

R652      	Q_RES_0402LF   	          	          	                    
          	               	1         	231A2     	P3V3_AUX            
          	               	2         	231A2     	SMB_FRU_3V3AUX_SDA  

R661      	Q_RES_0402LF   	          	          	                    
          	               	1         	230A4     	PD_I3C_SPD_DDR_CPU1_OE_N
          	               	2         	230A4     	GND                 

R662      	Q_RES_0402LF   	          	          	                    
          	               	1         	230B3     	PVNN_TERM_CPU1      
          	               	2         	230B3     	I3C_SPD_DDRABCD_CPU1_SCL

R663      	Q_RES_0402LF   	          	          	                    
          	               	1         	230B3     	PVNN_TERM_CPU1      
          	               	2         	230B3     	I3C_SPD_DDRABCD_CPU1_SDA

R664      	Q_RES_0402LF   	          	          	                    
          	               	1         	230B3     	PVNN_TERM_CPU1      
          	               	2         	230B3     	I3C_SPD_DDREFGH_CPU1_SCL

R665      	Q_RES_0402LF   	          	          	                    
          	               	1         	230A3     	I3C_SPD_DDRABCD_CPU1_R_SCL
          	               	2         	230A3     	I3C_SPD_DDRABCD_CPU1_LVC1_R_SCL

R666      	Q_RES_0402LF   	          	          	                    
          	               	1         	230A3     	I3C_SPD_DDRABCD_CPU1_R_SDA
          	               	2         	230A3     	I3C_SPD_DDRABCD_CPU1_LVC1_R_SDA

R667      	Q_RES_0402LF   	          	          	                    
          	               	1         	230A3     	I3C_SPD_DDREFGH_CPU1_R_SCL
          	               	2         	230A3     	I3C_SPD_DDREFGH_CPU1_LVC1_R_SCL

R668      	Q_RES_0402LF   	          	          	                    
          	               	1         	230A3     	I3C_SPD_DDREFGH_CPU1_R_SDA
          	               	2         	230A3     	I3C_SPD_DDREFGH_CPU1_LVC1_R_SDA

R669      	Q_RES_0402LF   	          	          	                    
          	               	1         	230B3     	PVNN_TERM_CPU1      
          	               	2         	230B3     	I3C_SPD_DDREFGH_CPU1_SDA

R670      	Q_RES_0402LF   	          	          	                    
          	               	1         	230B3     	I3C_SPD_DDRABCD_CPU1_SCL
          	               	2         	230B3     	I3C_SPD_DDRABCD_CPU1_R_SCL

R671      	Q_RES_0402LF   	          	          	                    
          	               	1         	230B3     	I3C_SPD_DDRABCD_CPU1_SDA
          	               	2         	230B3     	I3C_SPD_DDRABCD_CPU1_R_SDA

R672      	Q_RES_0402LF   	          	          	                    
          	               	1         	230B3     	I3C_SPD_DDREFGH_CPU1_SCL
          	               	2         	230B3     	I3C_SPD_DDREFGH_CPU1_R_SCL

R673      	Q_RES_0402LF   	          	          	                    
          	               	1         	230B3     	I3C_SPD_DDREFGH_CPU1_SDA
          	               	2         	230B3     	I3C_SPD_DDREFGH_CPU1_R_SDA

R674      	Q_RES_0402LF   	          	          	                    
          	               	1         	230B2     	I3C_SPD_DDRABCD_CPU1_LVC1_R_SCL
          	               	2         	230B2     	I3C_SPD_DDRABCD_CPU1_LVC1_SCL

R675      	Q_RES_0402LF   	          	          	                    
          	               	1         	230B2     	I3C_SPD_DDRABCD_CPU1_LVC1_R_SDA
          	               	2         	230B2     	I3C_SPD_DDRABCD_CPU1_LVC1_SDA

R676      	Q_RES_0402LF   	          	          	                    
          	               	1         	230B2     	I3C_SPD_DDREFGH_CPU1_LVC1_R_SCL
          	               	2         	230B2     	I3C_SPD_DDREFGH_CPU1_LVC1_SCL

R677      	Q_RES_0402LF   	          	          	                    
          	               	1         	230B2     	I3C_SPD_DDREFGH_CPU1_LVC1_R_SDA
          	               	2         	230B2     	I3C_SPD_DDREFGH_CPU1_LVC1_SDA

R678      	Q_RES_0402LF   	          	          	                    
          	               	1         	229A4     	PD_I3C_SPD_DDR_CPU0_OE_N
          	               	2         	229A4     	GND                 

R679      	Q_RES_0402LF   	          	          	                    
          	               	1         	229B3     	PVNN_TERM_CPU0      
          	               	2         	229B3     	I3C_SPD_DDRABCD_CPU0_SCL

R680      	Q_RES_0402LF   	          	          	                    
          	               	1         	229B3     	PVNN_TERM_CPU0      
          	               	2         	229B3     	I3C_SPD_DDRABCD_CPU0_SDA

R681      	Q_RES_0402LF   	          	          	                    
          	               	1         	229B3     	PVNN_TERM_CPU0      
          	               	2         	229B3     	I3C_SPD_DDREFGH_CPU0_SCL

R682      	Q_RES_0402LF   	          	          	                    
          	               	1         	229A3     	I3C_SPD_DDRABCD_CPU0_R_SCL
          	               	2         	229A3     	I3C_SPD_DDRABCD_CPU0_LVC1_R_SCL

R683      	Q_RES_0402LF   	          	          	                    
          	               	1         	229A3     	I3C_SPD_DDRABCD_CPU0_R_SDA
          	               	2         	229A3     	I3C_SPD_DDRABCD_CPU0_LVC1_R_SDA

R684      	Q_RES_0402LF   	          	          	                    
          	               	1         	229A3     	I3C_SPD_DDREFGH_CPU0_R_SCL
          	               	2         	229A3     	I3C_SPD_DDREFGH_CPU0_LVC1_R_SCL

R685      	Q_RES_0402LF   	          	          	                    
          	               	1         	229A3     	I3C_SPD_DDREFGH_CPU0_R_SDA
          	               	2         	229A3     	I3C_SPD_DDREFGH_CPU0_LVC1_R_SDA

R686      	Q_RES_0402LF   	          	          	                    
          	               	1         	229B3     	PVNN_TERM_CPU0      
          	               	2         	229B3     	I3C_SPD_DDREFGH_CPU0_SDA

R687      	Q_RES_0402LF   	          	          	                    
          	               	1         	229B3     	I3C_SPD_DDRABCD_CPU0_SCL
          	               	2         	229B3     	I3C_SPD_DDRABCD_CPU0_R_SCL

R688      	Q_RES_0402LF   	          	          	                    
          	               	1         	229B3     	I3C_SPD_DDRABCD_CPU0_SDA
          	               	2         	229B3     	I3C_SPD_DDRABCD_CPU0_R_SDA

R689      	Q_RES_0402LF   	          	          	                    
          	               	1         	229B3     	I3C_SPD_DDREFGH_CPU0_SCL
          	               	2         	229B3     	I3C_SPD_DDREFGH_CPU0_R_SCL

R690      	Q_RES_0402LF   	          	          	                    
          	               	1         	229B3     	I3C_SPD_DDREFGH_CPU0_SDA
          	               	2         	229B3     	I3C_SPD_DDREFGH_CPU0_R_SDA

R691      	Q_RES_0402LF   	          	          	                    
          	               	1         	229B2     	I3C_SPD_DDRABCD_CPU0_LVC1_R_SCL
          	               	2         	229B2     	I3C_SPD_DDRABCD_CPU0_LVC1_SCL

R692      	Q_RES_0402LF   	          	          	                    
          	               	1         	229B2     	I3C_SPD_DDRABCD_CPU0_LVC1_R_SDA
          	               	2         	229B2     	I3C_SPD_DDRABCD_CPU0_LVC1_SDA

R693      	Q_RES_0402LF   	          	          	                    
          	               	1         	229A2     	I3C_SPD_DDREFGH_CPU0_LVC1_R_SCL
          	               	2         	229A2     	I3C_SPD_DDREFGH_CPU0_LVC1_SCL

R694      	Q_RES_0402LF   	          	          	                    
          	               	1         	229A2     	I3C_SPD_DDREFGH_CPU0_LVC1_R_SDA
          	               	2         	229A2     	I3C_SPD_DDREFGH_CPU0_LVC1_SDA

R696      	Q_RES_0402LF   	          	          	                    
          	               	1         	182B4     	P3V3_AUX            
          	               	2         	182B4     	RST_PCH_RSTBTN_R_N  

R697      	Q_RES_0402LF   	          	          	                    
          	               	1         	182B4     	FM_BMC_RSTBTN_OUT_N 
          	               	2         	182B4     	RST_PCH_RSTBTN_R_N  

R698      	Q_RES_0402LF   	          	          	                    
          	               	1         	205A4     	FM_ADR_TRIGGER_R_N  
          	               	2         	205A4     	FM_ADR_TRIGGER_N    

R699      	Q_RES_0402LF   	          	          	                    
          	               	1         	183B2     	FM_PCH_CRASHLOG_TRIG_R_N
          	               	2         	183B2     	FM_PCH_CRASHLOG_TRIG_N

R700      	Q_RES_0402LF   	          	          	                    
          	               	1         	215A2     	FM_ADR_ACK_R        
          	               	2         	215A2     	FM_ADR_ACK          

R701      	Q_RES_0402LF   	          	          	                    
          	               	1         	130B4     	RST_PLD_CPU1_DRAM_CD_N
          	               	2         	130B4     	GND                 

R702      	Q_RES_0402LF   	          	          	                    
          	               	1         	130A4     	RST_PLD_CPU1_DRAM_GH_N
          	               	2         	130A4     	GND                 

R703      	Q_RES_0402LF   	          	          	                    
          	               	1         	130B4     	RST_PLD_CPU1_DRAM_AB_N
          	               	2         	130B4     	GND                 

R704      	Q_RES_0402LF   	          	          	                    
          	               	1         	130A4     	RST_PLD_CPU1_DRAM_EF_N
          	               	2         	130A4     	GND                 

R705      	Q_RES_0402LF   	          	          	                    
          	               	1         	129A4     	RST_PLD_CPU0_DRAM_GH_N
          	               	2         	129A4     	GND                 

R706      	Q_RES_0402LF   	          	          	                    
          	               	1         	129B4     	RST_PLD_CPU0_DRAM_AB_N
          	               	2         	129B4     	GND                 

R707      	Q_RES_0402LF   	          	          	                    
          	               	1         	129B4     	RST_PLD_CPU0_DRAM_CD_N
          	               	2         	129B4     	GND                 

R708      	Q_RES_0402LF   	          	          	                    
          	               	1         	129A4     	RST_PLD_CPU0_DRAM_EF_N
          	               	2         	129A4     	GND                 

R710      	Q_RES_0402LF   	          	          	                    
          	               	1         	243B3     	PD_MB_FRU_WP        
          	               	2         	243B3     	GND                 

R713      	Q_RES_0402LF   	          	          	                    
          	               	1         	243B2     	P3V3_AUX            
          	               	2         	243B2     	MB_FRU_ADDR2        

R714      	Q_RES_0402LF   	          	          	                    
          	               	1         	243B2     	MB_FRU_ADDR2        
          	               	2         	243B2     	GND                 

R717      	Q_RES_0402LF   	          	          	                    
          	               	1         	243B2     	P3V3_AUX            
          	               	2         	243B2     	MB_FRU_ADDR1        

R718      	Q_RES_0402LF   	          	          	                    
          	               	1         	243B2     	MB_FRU_ADDR1        
          	               	2         	243B2     	GND                 

R721      	Q_RES_0402LF   	          	          	                    
          	               	1         	243B2     	P3V3_AUX            
          	               	2         	243B2     	MB_FRU_ADDR0        

R722      	Q_RES_0402LF   	          	          	                    
          	               	1         	243B2     	MB_FRU_ADDR0        
          	               	2         	243B2     	GND                 

R727      	Q_RES_0402LF   	          	          	                    
          	               	1         	183A2     	PU_OC4_USB_N        
          	               	2         	183A1     	P3V3_AUX            

R734      	Q_RES_0402LF   	          	          	                    
          	               	1         	208B4     	CLK_CK440_SMB_ADDR1 
          	               	2         	208B4     	GND                 

R735      	Q_RES_0402LF   	          	          	                    
          	               	1         	220B4     	P3V3_AUX            
          	               	2         	220B4     	FM_DIMM_12V_CPS_SX_N

R736      	Q_RES_0402LF   	          	          	                    
          	               	1         	220B4     	FM_DIMM_12V_CPS_SX_N
          	               	2         	220B4     	GND                 

R737      	Q_RES_0402LF   	          	          	                    
          	               	1         	133A4     	FM_CPU1_SKTOCC_LVT3_N
          	               	2         	133A4     	FM_CPU1_SKTOCC_N    

R738      	Q_RES_0402LF   	          	          	                    
          	               	1         	133A4     	FM_CPU0_SKTOCC_LVT3_N
          	               	2         	133A4     	FM_CPU0_SKTOCC_N    

R739      	Q_RES_0402LF   	          	          	                    
          	               	1         	133A4     	P3V3_AUX            
          	               	2         	133A4     	FM_CPU1_SKTOCC_N    

R740      	Q_RES_0402LF   	          	          	                    
          	               	1         	133A3     	P3V3_AUX            
          	               	2         	133A3     	FM_CPU0_SKTOCC_N    

R741      	Q_RES_0402LF   	          	          	                    
          	               	1         	133B3     	PVNN_TERM_CPU0      
          	               	2         	133B3     	JTAG_MUX_CPU0_GTL_TDI

R742      	Q_RES_0402LF   	          	          	                    
          	               	1         	133B3     	PVNN_TERM_CPU1      
          	               	2         	133B3     	JTAG_CPU1_MUX_GTL_TDO

R743      	Q_RES_0402LF   	          	          	                    
          	               	1         	133B3     	PVNN_TERM_CPU1      
          	               	2         	133B3     	JTAG_MUX_CPU1_GTL_TDI

R744      	Q_RES_0402LF   	          	          	                    
          	               	1         	133B3     	PVNN_TERM_CPU0      
          	               	2         	133B3     	JTAG_CPU0_MUX_GTL_TDO

R745      	Q_RES_0402LF   	          	          	                    
          	               	1         	133A2     	FM_CPU_EN           
          	               	2         	133A2     	FM_CPU_EN_R         

R746      	Q_RES_0402LF   	          	          	                    
          	               	1         	132B4     	PD_74CB_A9          
          	               	2         	132B4     	GND                 

R747      	Q_RES_0402LF   	          	          	                    
          	               	1         	132A2     	P1V05_PCH_AUX       
          	               	2         	132A2     	JTAG_DBP_TDO_PCH    

R748      	Q_RES_0402LF   	          	          	                    
          	               	1         	132A2     	P1V05_PCH_AUX       
          	               	2         	132A2     	JTAG_DBP_TDI_PCH    

R749      	Q_RES_0402LF   	          	          	                    
          	               	1         	132A2     	P1V05_PCH_AUX       
          	               	2         	132A2     	JTAG_DBP_TMS_PCH    

R750      	Q_RES_0402LF   	          	          	                    
          	               	1         	132A2     	P1V05_PCH_AUX       
          	               	2         	132A2     	H_DBP_PREQ_N_PCH    

R751      	Q_RES_0402LF   	          	          	                    
          	               	1         	132A2     	P1V05_PCH_AUX       
          	               	2         	132A2     	H_DBP_PRDY_N_PCH    

R752      	Q_RES_0402LF   	          	          	                    
          	               	1         	132A3     	JTAG_DBP_TDO        
          	               	2         	132A3     	JTAG_DBP_TDO_PCH    

R753      	Q_RES_0402LF   	          	          	                    
          	               	1         	132A3     	JTAG_DBP_TDI        
          	               	2         	132A3     	JTAG_DBP_TDI_PCH    

R754      	Q_RES_0402LF   	          	          	                    
          	               	1         	132A3     	JTAG_DBP_TMS        
          	               	2         	132A3     	JTAG_DBP_TMS_PCH    

R755      	Q_RES_0402LF   	          	          	                    
          	               	1         	132A3     	JTAG_DBP_PREQ_N     
          	               	2         	132A3     	H_DBP_PREQ_N_PCH    

R756      	Q_RES_0402LF   	          	          	                    
          	               	1         	132A3     	JTAG_DBP_PRDY_N     
          	               	2         	132A3     	H_DBP_PRDY_N_PCH    

R757      	Q_RES_0402LF   	          	          	                    
          	               	1         	132B2     	PVNN_TERM_CPU0      
          	               	2         	132B2     	JTAG_DBP_CPU_QS_GTL_TMS

R758      	Q_RES_0402LF   	          	          	                    
          	               	1         	132B2     	PVNN_TERM_CPU0      
          	               	2         	132B2     	H_CPU_PREQ_QS_GTL_N 

R759      	Q_RES_0402LF   	          	          	                    
          	               	1         	132B2     	PVNN_TERM_CPU0      
          	               	2         	132B2     	H_CPU_PRDY_QS_GTL_N 

R760      	Q_RES_0402LF   	          	          	                    
          	               	1         	132B2     	PVNN_TERM_CPU0      
          	               	2         	132B2     	DBP_CPU_HOOK8_MBP2_GTL_QS_N

R761      	Q_RES_0402LF   	          	          	                    
          	               	1         	132B2     	PVNN_TERM_CPU0      
          	               	2         	132B2     	DBP_CPU_HOOK9_MBP3_GTL_QS_N

R762      	Q_RES_0402LF   	          	          	                    
          	               	1         	131B4     	JTAG_DBP_CPU_GTL_TCK
          	               	2         	131B4     	JTAG_DBP_CPU_GTL_TCK_R

R763      	Q_RES_0402LF   	          	          	                    
          	               	1         	131B4     	JTAG_DBP_TDI        
          	               	2         	131B4     	JTAG_DBP_TDI_R      

R764      	Q_RES_0402LF   	          	          	                    
          	               	1         	131B4     	JTAG_DBP_PRDY_N     
          	               	2         	131B4     	JTAG_DBP_PRDY_R1_N  

R765      	Q_RES_0402LF   	          	          	                    
          	               	1         	131B4     	JTAG_DBP_TCK_PCH    
          	               	2         	131B4     	JTAG_DBP_TCK_R_TCK  

R766      	Q_RES_0402LF   	          	          	                    
          	               	1         	131A3     	P3V3_AUX            
          	               	2         	131A3     	JTAG_DBP_POWER_BTN_N

R767      	Q_RES_0402LF   	          	          	                    
          	               	1         	131A3     	P3V3_AUX            
          	               	2         	131A3     	JTAG_RST_DBP_RST_CO_N

R768      	Q_RES_0402LF   	          	          	                    
          	               	1         	131A3     	P3V3_AUX            
          	               	2         	131A3     	JTAG_DBP_PRESENT_R_N

R769      	Q_RES_0402LF   	          	          	                    
          	               	1         	131B2     	PD_TRST_P3          
          	               	2         	131B2     	GND                 

R770      	Q_RES_0402LF   	          	          	                    
          	               	1         	183A2     	PU_OC5_USB_N        
          	               	2         	183A1     	P3V3_AUX            

R771      	Q_RES_0402LF   	          	          	                    
          	               	1         	131A3     	JTAG_DBP_PCH_DEBUG_CONSENT_N
          	               	2         	131A3     	FM_PCH_CONSENT_STRAP_N

R772      	Q_RES_0402LF   	          	          	                    
          	               	1         	131A3     	JTAG_RST_DBP_RSMRST_N
          	               	2         	131A3     	RST_RSMRST_PCH_N    

R773      	Q_RES_0402LF   	          	          	                    
          	               	1         	131A3     	JTAG_DBP_BOOT_HALT_N
          	               	2         	131A3     	FM_ADR_MODE0        

R774      	Q_RES_0402LF   	          	          	                    
          	               	1         	131A3     	JTAG_DBP_CPU_GTL_TCK
          	               	2         	131A3     	GND                 

R775      	Q_RES_0402LF   	          	          	                    
          	               	1         	131B2     	JTAG_DBP_TMS_R      
          	               	2         	131B2     	JTAG_DBP_TMS        

R776      	Q_RES_0402LF   	          	          	                    
          	               	1         	131B2     	JTAG_DBP_TDO_R      
          	               	2         	131B2     	JTAG_DBP_TDO        

R777      	Q_RES_0402LF   	          	          	                    
          	               	1         	131B2     	JTAG_DBP_PREQ_N_R   
          	               	2         	131B2     	JTAG_DBP_PREQ_N     

R778      	Q_RES_0402LF   	          	          	                    
          	               	1         	131B2     	P3V3_AUX            
          	               	2         	131B2     	JTAG_DBP_BOOT_HALT_N

R779      	Q_RES_0402LF   	          	          	                    
          	               	1         	131B2     	PVNN_TERM_CPU0      
          	               	2         	131B2     	FM_CPU_FBRK_DEBUG_N 

R780      	Q_RES_0402LF   	          	          	                    
          	               	1         	131B2     	FM_CPU_FBRK_DEBUG_N 
          	               	2         	131B2     	FM_CPU_FBRK_DEBUG_R_N

R803      	Q_RES_0402LF   	          	          	                    
          	               	1         	221B4     	JTAG_PLD_TDI_R      
          	               	2         	221B4     	JTAG_BMC_PLD_TDI    

R804      	Q_RES_0402LF   	          	          	                    
          	               	1         	221B4     	JTAG_PLD_TDO_R      
          	               	2         	221B4     	JTAG_BMC_PLD_TDO    

R805      	Q_RES_0402LF   	          	          	                    
          	               	1         	221B4     	JTAG_PLD_TMS_R      
          	               	2         	221B4     	JTAG_BMC_PLD_TMS    

R806      	Q_RES_0402LF   	          	          	                    
          	               	1         	221B4     	JTAG_PLD_TCK_R      
          	               	2         	221B4     	JTAG_BMC_PLD_TCK    

R815      	Q_RES_0402LF   	          	          	                    
          	               	1         	130A3     	RST_PLD_CPU1_DRAM_GH_N
          	               	2         	130A3     	RST_M_GH_CPU1_FPGA_N

R816      	Q_RES_0402LF   	          	          	                    
          	               	1         	130B3     	RST_PLD_CPU1_DRAM_AB_N
          	               	2         	130B3     	RST_M_AB_CPU1_FPGA_N

R817      	Q_RES_0402LF   	          	          	                    
          	               	1         	130B3     	RST_PLD_CPU1_DRAM_CD_N
          	               	2         	130B3     	RST_M_CD_CPU1_FPGA_N

R818      	Q_RES_0402LF   	          	          	                    
          	               	1         	130B3     	RST_PLD_CPU1_DRAM_EF_N
          	               	2         	130B3     	RST_M_EF_CPU1_FPGA_N

R819      	Q_RES_0402LF   	          	          	                    
          	               	1         	130A2     	PVCCD_HV_CPU1       
          	               	2         	130A2     	RST_M_GH_CPU1_FPGA_N

R820      	Q_RES_0402LF   	          	          	                    
          	               	1         	130B2     	PVCCD_HV_CPU1       
          	               	2         	130B2     	RST_M_AB_CPU1_FPGA_N

R821      	Q_RES_0402LF   	          	          	                    
          	               	1         	130B2     	PVCCD_HV_CPU1       
          	               	2         	130B2     	RST_M_CD_CPU1_FPGA_N

R822      	Q_RES_0402LF   	          	          	                    
          	               	1         	130B2     	PVCCD_HV_CPU1       
          	               	2         	130B2     	RST_M_EF_CPU1_FPGA_N

R835      	Q_RES_0402LF   	          	          	                    
          	               	1         	129A3     	RST_PLD_CPU0_DRAM_GH_N
          	               	2         	129A3     	RST_M_GH_CPU0_FPGA_N

R836      	Q_RES_0402LF   	          	          	                    
          	               	1         	129B3     	RST_PLD_CPU0_DRAM_AB_N
          	               	2         	129B3     	RST_M_AB_CPU0_FPGA_N

R837      	Q_RES_0402LF   	          	          	                    
          	               	1         	129B3     	RST_PLD_CPU0_DRAM_CD_N
          	               	2         	129B3     	RST_M_CD_CPU0_FPGA_N

R838      	Q_RES_0402LF   	          	          	                    
          	               	1         	129A3     	RST_PLD_CPU0_DRAM_EF_N
          	               	2         	129A3     	RST_M_EF_CPU0_FPGA_N

R839      	Q_RES_0402LF   	          	          	                    
          	               	1         	129A2     	PVCCD_HV_CPU0       
          	               	2         	129A2     	RST_M_GH_CPU0_FPGA_N

R840      	Q_RES_0402LF   	          	          	                    
          	               	1         	129B2     	PVCCD_HV_CPU0       
          	               	2         	129B2     	RST_M_AB_CPU0_FPGA_N

R841      	Q_RES_0402LF   	          	          	                    
          	               	1         	129B2     	PVCCD_HV_CPU0       
          	               	2         	129B2     	RST_M_CD_CPU0_FPGA_N

R842      	Q_RES_0402LF   	          	          	                    
          	               	1         	129B2     	PVCCD_HV_CPU0       
          	               	2         	129B2     	RST_M_EF_CPU0_FPGA_N

R851      	Q_RES_0402LF   	          	          	                    
          	               	1         	128B4     	RST_CPU0_DRAM_AB_N  
          	               	2         	128B4     	RST_CPU0_DRAM_AB_PLD_N

R852      	Q_RES_0402LF   	          	          	                    
          	               	1         	128B4     	RST_CPU0_DRAM_CD_N  
          	               	2         	128B4     	RST_CPU0_DRAM_CD_PLD_N

R853      	Q_RES_0402LF   	          	          	                    
          	               	1         	128B4     	RST_CPU0_DRAM_EF_N  
          	               	2         	128B4     	RST_CPU0_DRAM_EF_PLD_N

R854      	Q_RES_0402LF   	          	          	                    
          	               	1         	128B4     	RST_CPU0_DRAM_GH_N  
          	               	2         	128B4     	RST_CPU0_DRAM_GH_PLD_N

R859      	Q_RES_0402LF   	          	          	                    
          	               	1         	128A4     	RST_CPU1_DRAM_AB_N  
          	               	2         	128A4     	RST_CPU1_DRAM_AB_PLD_N

R860      	Q_RES_0402LF   	          	          	                    
          	               	1         	128A4     	RST_CPU1_DRAM_CD_N  
          	               	2         	128A4     	RST_CPU1_DRAM_CD_PLD_N

R861      	Q_RES_0402LF   	          	          	                    
          	               	1         	128A4     	RST_CPU1_DRAM_EF_N  
          	               	2         	128A4     	RST_CPU1_DRAM_EF_PLD_N

R880      	Q_RES_0402LF   	          	          	                    
          	               	1         	114B4     	PWRGD_CHB_CPU0_DIMM2
          	               	2         	114B4     	PWRGD_FAIL_CPU0_AB  

R884      	Q_RES_0402LF   	          	          	                    
          	               	1         	114B4     	PWRGD_CHD_CPU0_DIMM2
          	               	2         	114B4     	PWRGD_FAIL_CPU0_CD  

R885      	Q_RES_0402LF   	          	          	                    
          	               	1         	114B4     	PWRGD_CHE_CPU0_DIMM1
          	               	2         	114B4     	PWRGD_FAIL_CPU0_EF  

R886      	Q_RES_0402LF   	          	          	                    
          	               	1         	114B4     	PWRGD_CHE_CPU0_DIMM2
          	               	2         	114B4     	PWRGD_FAIL_CPU0_EF  

R889      	Q_RES_0402LF   	          	          	                    
          	               	1         	114B4     	PWRGD_CHG_CPU0_DIMM1
          	               	2         	114B4     	PWRGD_FAIL_CPU0_GH  

R890      	Q_RES_0402LF   	          	          	                    
          	               	1         	114B4     	PWRGD_CHG_CPU0_DIMM2
          	               	2         	114B4     	PWRGD_FAIL_CPU0_GH  

R893      	Q_RES_0402LF   	          	          	                    
          	               	1         	114B2     	PWRGD_CHA_CPU1_DIMM1
          	               	2         	114B2     	PWRGD_FAIL_CPU1_AB  

R894      	Q_RES_0402LF   	          	          	                    
          	               	1         	114B2     	PWRGD_CHA_CPU1_DIMM2
          	               	2         	114B2     	PWRGD_FAIL_CPU1_AB  

R895      	Q_RES_0402LF   	          	          	                    
          	               	1         	114B2     	PWRGD_CHB_CPU1_DIMM1
          	               	2         	114B2     	PWRGD_FAIL_CPU1_AB  

R896      	Q_RES_0402LF   	          	          	                    
          	               	1         	114B2     	PWRGD_CHB_CPU1_DIMM2
          	               	2         	114B2     	PWRGD_FAIL_CPU1_AB  

R897      	Q_RES_0402LF   	          	          	                    
          	               	1         	114B2     	PWRGD_CHC_CPU1_DIMM1
          	               	2         	114B2     	PWRGD_FAIL_CPU1_CD  

R898      	Q_RES_0402LF   	          	          	                    
          	               	1         	114B2     	PWRGD_CHC_CPU1_DIMM2
          	               	2         	114B2     	PWRGD_FAIL_CPU1_CD  

R899      	Q_RES_0402LF   	          	          	                    
          	               	1         	114B2     	PWRGD_CHD_CPU1_DIMM1
          	               	2         	114B2     	PWRGD_FAIL_CPU1_CD  

R900      	Q_RES_0402LF   	          	          	                    
          	               	1         	114B2     	PWRGD_CHD_CPU1_DIMM2
          	               	2         	114B2     	PWRGD_FAIL_CPU1_CD  

R901      	Q_RES_0402LF   	          	          	                    
          	               	1         	114B2     	PWRGD_CHE_CPU1_DIMM1
          	               	2         	114B2     	PWRGD_FAIL_CPU1_EF  

R902      	Q_RES_0402LF   	          	          	                    
          	               	1         	114B2     	PWRGD_CHE_CPU1_DIMM2
          	               	2         	114B2     	PWRGD_FAIL_CPU1_EF  

R903      	Q_RES_0402LF   	          	          	                    
          	               	1         	114B2     	PWRGD_CHF_CPU1_DIMM1
          	               	2         	114B2     	PWRGD_FAIL_CPU1_EF  

R905      	Q_RES_0402LF   	          	          	                    
          	               	1         	114B2     	PWRGD_CHG_CPU1_DIMM1
          	               	2         	114B2     	PWRGD_FAIL_CPU1_GH  

R906      	Q_RES_0402LF   	          	          	                    
          	               	1         	114B2     	PWRGD_CHG_CPU1_DIMM2
          	               	2         	114B2     	PWRGD_FAIL_CPU1_GH  

R907      	Q_RES_0402LF   	          	          	                    
          	               	1         	114B2     	PWRGD_CHH_CPU1_DIMM1
          	               	2         	114B2     	PWRGD_FAIL_CPU1_GH  

R908      	Q_RES_0402LF   	          	          	                    
          	               	1         	114B2     	PWRGD_CHH_CPU1_DIMM2
          	               	2         	114B2     	PWRGD_FAIL_CPU1_GH  

R909      	Q_RES_0402LF   	          	          	                    
          	               	1         	235B4     	SMB_PEHPCPU0_GTL_SDA
          	               	2         	235B4     	SMB_PEHPCPU0_GTL_R_SDA

R910      	Q_RES_0402LF   	          	          	                    
          	               	1         	235B4     	PVNN_TERM_CPU0      
          	               	2         	235B4     	SMB_PEHPCPU0_GTL_R_SCL

R911      	Q_RES_0402LF   	          	          	                    
          	               	1         	235B4     	PVNN_TERM_CPU0      
          	               	2         	235B4     	SMB_PEHPCPU0_GTL_R_SDA

R912      	Q_RES_0402LF   	          	          	                    
          	               	1         	208B4     	P3V3_AUX            
          	               	2         	208B4     	CLK_CK440_SMB_ADDR0 

R913      	Q_RES_0402LF   	          	          	                    
          	               	1         	183A2     	PU_OC6_USB_N        
          	               	2         	183A1     	P3V3_AUX            

R915      	Q_RES_0402LF   	          	          	                    
          	               	1         	185A2     	SPI_PCH_IO0         
          	               	2         	185A2     	SPI_SYS_MOSI        

R916      	Q_RES_0402LF   	          	          	                    
          	               	1         	185A2     	SPI_PCH_IO1         
          	               	2         	185A2     	SPI_SYS_MISO        

R917      	Q_RES_0402LF   	          	          	                    
          	               	1         	185A2     	SPI_PCH_IO3         
          	               	2         	185A2     	SPI_SYS_HOLD_IO3    

R918      	Q_RES_0402LF   	          	          	                    
          	               	1         	185A2     	SPI_PCH_IO2         
          	               	2         	185A2     	SPI_SYS_WP_IO2      

R919      	Q_RES_0402LF   	          	          	                    
          	               	1         	221B2     	P3V3_AUX            
          	               	2         	221B2     	JTAG_PLD_JTAGEN     

R920      	Q_RES_0402LF   	          	          	                    
          	               	1         	221B2     	JTAG_PLD_JTAGEN     
          	               	2         	221A2     	GND                 

R927      	Q_RES_0402LF   	          	          	                    
          	               	1         	221B3     	P3V3_AUX            
          	               	2         	221B3     	JTAG_BMC_PLD_TDI    

R928      	Q_RES_0402LF   	          	          	                    
          	               	1         	221B3     	P3V3_AUX            
          	               	2         	221B3     	JTAG_BMC_PLD_TDO    

R929      	Q_RES_0402LF   	          	          	                    
          	               	1         	221B3     	P3V3_AUX            
          	               	2         	221B3     	JTAG_BMC_PLD_TMS    

R930      	Q_RES_0402LF   	          	          	                    
          	               	1         	221B3     	JTAG_BMC_PLD_TCK    
          	               	2         	221B3     	GND                 

R932      	Q_RES_0402LF   	          	          	                    
          	               	1         	128B4     	RST_CPU0_DRAM_AB_N  
          	               	2         	128B4     	GND                 

R933      	Q_RES_0402LF   	          	          	                    
          	               	1         	128A4     	RST_CPU1_DRAM_AB_N  
          	               	2         	128A4     	GND                 

R934      	Q_RES_0402LF   	          	          	                    
          	               	1         	128B4     	RST_CPU0_DRAM_CD_N  
          	               	2         	128B4     	GND                 

R935      	Q_RES_0402LF   	          	          	                    
          	               	1         	128A4     	RST_CPU1_DRAM_CD_N  
          	               	2         	128A4     	GND                 

R936      	Q_RES_0402LF   	          	          	                    
          	               	1         	128B4     	RST_CPU0_DRAM_EF_N  
          	               	2         	128B4     	GND                 

R937      	Q_RES_0402LF   	          	          	                    
          	               	1         	128A4     	RST_CPU1_DRAM_EF_N  
          	               	2         	128A4     	GND                 

R938      	Q_RES_0402LF   	          	          	                    
          	               	1         	128B4     	RST_CPU0_DRAM_GH_N  
          	               	2         	128B4     	GND                 

R939      	Q_RES_0402LF   	          	          	                    
          	               	1         	128A4     	RST_CPU1_DRAM_GH_N  
          	               	2         	128A4     	GND                 

R940      	Q_RES_0402LF   	          	          	                    
          	               	1         	115B4     	P3V3_AUX            
          	               	2         	115B4     	PWRGD_FAIL_CPU0_AB_R1

R941      	Q_RES_0402LF   	          	          	                    
          	               	1         	115B4     	P3V3_AUX            
          	               	2         	115B4     	PWRGD_FAIL_CPU0_CD_R1

R942      	Q_RES_0402LF   	          	          	                    
          	               	1         	115B4     	P3V3_AUX            
          	               	2         	115B4     	PWRGD_FAIL_CPU0_EF_R1

R943      	Q_RES_0402LF   	          	          	                    
          	               	1         	115B4     	P3V3_AUX            
          	               	2         	115B4     	PWRGD_FAIL_CPU0_GH_R1

R944      	Q_RES_0402LF   	          	          	                    
          	               	1         	115B4     	P3V3_AUX            
          	               	2         	115B4     	PWRGD_FAIL_CPU1_AB_R1

R945      	Q_RES_0402LF   	          	          	                    
          	               	1         	115B4     	P3V3_AUX            
          	               	2         	115B4     	PWRGD_FAIL_CPU1_CD_R1

R946      	Q_RES_0402LF   	          	          	                    
          	               	1         	115A4     	P3V3_AUX            
          	               	2         	115A4     	PWRGD_FAIL_CPU1_EF_R1

R947      	Q_RES_0402LF   	          	          	                    
          	               	1         	115A4     	P3V3_AUX            
          	               	2         	115A4     	PWRGD_FAIL_CPU1_GH_R1

R953      	Q_RES_0402LF   	          	          	                    
          	               	1         	208B4     	CLK_CK440_SMB_ADDR0 
          	               	2         	208B4     	GND                 

R960      	Q_RES_0402LF   	          	          	                    
          	               	1         	235B4     	SMB_PEHPCPU0_GTL_SCL
          	               	2         	235B4     	SMB_PEHPCPU0_GTL_R_SCL

R961      	Q_RES_0402LF   	          	          	                    
          	               	1         	235B4     	SMB_PEHPCPU1_GTL_SCL
          	               	2         	235B4     	SMB_PEHPCPU1_GTL_R_SCL

R962      	Q_RES_0402LF   	          	          	                    
          	               	1         	235B4     	SMB_PEHPCPU1_GTL_SDA
          	               	2         	235B4     	SMB_PEHPCPU1_GTL_R_SDA

R963      	Q_RES_0402LF   	          	          	                    
          	               	1         	235B4     	PVNN_TERM_CPU1      
          	               	2         	235B4     	SMB_PEHPCPU1_GTL_R_SCL

R964      	Q_RES_0402LF   	          	          	                    
          	               	1         	235B4     	PVNN_TERM_CPU1      
          	               	2         	235B4     	SMB_PEHPCPU1_GTL_R_SDA

R965      	Q_RES_0402LF   	          	          	                    
          	               	1         	235B1     	P3V3_AUX            
          	               	2         	235B1     	SMB_PEHPCPU0_LVC3_SCL

R966      	Q_RES_0402LF   	          	          	                    
          	               	1         	235B1     	P3V3_AUX            
          	               	2         	235B1     	SMB_PEHPCPU1_LVC3_SCL

R967      	Q_RES_0402LF   	          	          	                    
          	               	1         	235B1     	P3V3_AUX            
          	               	2         	235B1     	SMB_PEHPCPU0_LVC3_SDA

R968      	Q_RES_0402LF   	          	          	                    
          	               	1         	235B1     	P3V3_AUX            
          	               	2         	235B1     	SMB_PEHPCPU1_LVC3_SDA

R969      	Q_RES_0402LF   	          	          	                    
          	               	1         	236B4     	PVNN_TERM_CPU0      
          	               	2         	236B4     	SMB_S3M_CPU0_R_SCL  

R970      	Q_RES_0402LF   	          	          	                    
          	               	1         	236A4     	PVNN_TERM_CPU1      
          	               	2         	236A4     	SMB_S3M_CPU1_R_SCL  

R971      	Q_RES_0402LF   	          	          	                    
          	               	1         	236B4     	PVNN_TERM_CPU0      
          	               	2         	236B4     	SMB_S3M_CPU0_R_SDA  

R972      	Q_RES_0402LF   	          	          	                    
          	               	1         	236A4     	PVNN_TERM_CPU1      
          	               	2         	236A4     	SMB_S3M_CPU1_R_SDA  

R977      	Q_RES_0402LF   	          	          	                    
          	               	1         	236B2     	P3V3_AUX            
          	               	2         	236B2     	SMB_S3M_CPU0_3V3AUX_SCL

R978      	Q_RES_0402LF   	          	          	                    
          	               	1         	236A2     	P3V3_AUX            
          	               	2         	236A2     	SMB_S3M_CPU1_3V3AUX_SCL

R979      	Q_RES_0402LF   	          	          	                    
          	               	1         	236B2     	P3V3_AUX            
          	               	2         	236B2     	SMB_S3M_CPU0_3V3AUX_SDA

R980      	Q_RES_0402LF   	          	          	                    
          	               	1         	236A2     	P3V3_AUX            
          	               	2         	236A2     	SMB_S3M_CPU1_3V3AUX_SDA

R981      	Q_RES_0402LF   	          	          	                    
          	               	1         	222B4     	FM_PVCCIN_CPU0_R_EN 
          	               	2         	222B4     	FM_PVCCIN_CPU0_EN   

R982      	Q_RES_0402LF   	          	          	                    
          	               	1         	222B4     	FM_PVCCFA_EHV_CPU0_R_EN
          	               	2         	222B4     	FM_PVCCFA_EHV_CPU0_EN

R983      	Q_RES_0402LF   	          	          	                    
          	               	1         	222B4     	FM_PVCCINFAON_CPU0_R_EN
          	               	2         	222B4     	FM_PVCCINFAON_CPU0_EN

R984      	Q_RES_0402LF   	          	          	                    
          	               	1         	222B4     	FM_PVCCFA_EHV_FIVRA_CPU0_R_EN
          	               	2         	222B4     	FM_PVCCFA_EHV_FIVRA_CPU0_EN

R985      	Q_RES_0402LF   	          	          	                    
          	               	1         	222B4     	FM_PVCCIN_CPU1_R_EN 
          	               	2         	222B4     	FM_PVCCIN_CPU1_EN   

R986      	Q_RES_0402LF   	          	          	                    
          	               	1         	222B4     	FM_PVCCFA_EHV_CPU1_R_EN
          	               	2         	222B4     	FM_PVCCFA_EHV_CPU1_EN

R987      	Q_RES_0402LF   	          	          	                    
          	               	1         	222B4     	FM_PVCCINFAON_CPU1_R_EN
          	               	2         	222B4     	FM_PVCCINFAON_CPU1_EN

R988      	Q_RES_0402LF   	          	          	                    
          	               	1         	222B4     	FM_PVCCFA_EHV_FIVRA_CPU1_R_EN
          	               	2         	222B4     	FM_PVCCFA_EHV_FIVRA_CPU1_EN

R990      	Q_RES_0402LF   	          	          	                    
          	               	1         	219B4     	FM_PLD_CLK_25M_R_EN 
          	               	2         	219B4     	GND                 

R991      	Q_RES_0402LF   	          	          	                    
          	               	1         	219B4     	FM_AUX_SW_EN        
          	               	2         	219B4     	GND                 

R992      	Q_RES_0402LF   	          	          	                    
          	               	1         	219B4     	PWRGD_CPU0_LVC1_R   
          	               	2         	219B4     	GND                 

R993      	Q_RES_0402LF   	          	          	                    
          	               	1         	236B4     	SMB_S3M_CPU0_SCL    
          	               	2         	236B4     	SMB_S3M_CPU0_R_SCL  

R994      	Q_RES_0402LF   	          	          	                    
          	               	1         	236B4     	SMB_S3M_CPU0_SDA    
          	               	2         	236B4     	SMB_S3M_CPU0_R_SDA  

R995      	Q_RES_0402LF   	          	          	                    
          	               	1         	236A4     	SMB_S3M_CPU1_SCL    
          	               	2         	236A4     	SMB_S3M_CPU1_R_SCL  

R996      	Q_RES_0402LF   	          	          	                    
          	               	1         	236A4     	SMB_S3M_CPU1_SDA    
          	               	2         	236A4     	SMB_S3M_CPU1_R_SDA  

R997      	Q_RES_0402LF   	          	          	                    
          	               	1         	127B4     	PU_PIROM_CPU0_SM_WP 
          	               	2         	127B4     	GND                 

R998      	Q_RES_0402LF   	          	          	                    
          	               	1         	235A3     	FM_SMB_PEHPCPU0_PCIE_ALERT_N
          	               	2         	235A3     	FM_SMB_PEHPCPU0_PCIE_ALERT_R_N

R999      	Q_RES_0402LF   	          	          	                    
          	               	1         	235A4     	FM_SMB_PEHPCPU1_PCIE_ALERT_N
          	               	2         	235A4     	FM_SMB_PEHPCPU1_PCIE_ALERT_R_N

R1000     	Q_RES_0402LF   	          	          	                    
          	               	1         	235B3     	P3V3                
          	               	2         	235B3     	FM_SMB_PEHPCPU0_PCIE_ALERT_R_N

R1001     	Q_RES_0402LF   	          	          	                    
          	               	1         	235A3     	P3V3                
          	               	2         	235A3     	FM_SMB_PEHPCPU1_PCIE_ALERT_R_N

R1002     	Q_RES_0402LF   	          	          	                    
          	               	1         	235B2     	P3V3                
          	               	2         	235B2     	FM_SMB_CPU0_ALERT_R1

R1003     	Q_RES_0402LF   	          	          	                    
          	               	1         	235A2     	P3V3                
          	               	2         	235A2     	FM_SMB_CPU1_ALERT_R1

R1004     	Q_RES_0402LF   	          	          	                    
          	               	1         	127B3     	P3V3_AUX            
          	               	2         	127B3     	PU_PIROM_CPU1_SM_WP 

R1005     	Q_RES_0402LF   	          	          	                    
          	               	1         	127B3     	PU_PIROM_CPU1_SM_WP 
          	               	2         	127B3     	GND                 

R1006     	Q_RES_0402LF   	          	          	                    
          	               	1         	235B2     	PVNN_TERM_CPU0      
          	               	2         	235B2     	FM_PEHPCPU0_ALERT_N 

R1007     	Q_RES_0402LF   	          	          	                    
          	               	1         	235A2     	PVNN_TERM_CPU1      
          	               	2         	235A2     	FM_PEHPCPU1_ALERT_N 

R1008     	Q_RES_0402LF   	          	          	                    
          	               	1         	119A4     	PVNN_TERM_CPU1      
          	               	2         	119A4     	PU_TAP_ODT_CPU1_EN  

R1009     	Q_RES_0402LF   	          	          	                    
          	               	1         	119B4     	PVNN_TERM_CPU0      
          	               	2         	119B4     	PU_TAP_ODT_CPU0_EN  

R1010     	Q_RES_0402LF   	          	          	                    
          	               	1         	209A4     	CLK_25M_CK440_ISCLK_REF_DP
          	               	2         	209A4     	CLK_25M_PCH_REF_NS_DP

R1011     	Q_RES_0402LF   	          	          	                    
          	               	1         	209A4     	CLK_25M_CK440_ISCLK_REF_DN
          	               	2         	209A4     	CLK_25M_PCH_REF_NS_DN

R1012     	Q_RES_0402LF   	          	          	                    
          	               	1         	209B4     	CLK_25M_CK440_CPU0_DP
          	               	2         	209B4     	CLK_25M_CK440_CPU0_R_DP

R1013     	Q_RES_0402LF   	          	          	                    
          	               	1         	209B4     	CLK_25M_PCH_CPU0_DP 
          	               	2         	209B4     	CLK_25M_NSSC_CPU0_DP

R1014     	Q_RES_0402LF   	          	          	                    
          	               	1         	209B4     	CLK_25M_CK440_CPU0_DN
          	               	2         	209B4     	CLK_25M_CK440_CPU0_R_DN

R1015     	Q_RES_0402LF   	          	          	                    
          	               	1         	209B4     	CLK_25M_PCH_CPU0_DN 
          	               	2         	209B4     	CLK_25M_NSSC_CPU0_DN

R1016     	Q_RES_0402LF   	          	          	                    
          	               	1         	209A4     	CLK_25M_CK440_CPU1_DP
          	               	2         	209A4     	CLK_25M_CK440_CPU1_R_DP

R1017     	Q_RES_0402LF   	          	          	                    
          	               	1         	209A4     	CLK_25M_PCH_CPU1_DP 
          	               	2         	209A4     	CLK_25M_NSSC_CPU1_DP

R1018     	Q_RES_0402LF   	          	          	                    
          	               	1         	209A4     	CLK_25M_CK440_CPU1_DN
          	               	2         	209A4     	CLK_25M_CK440_CPU1_R_DN

R1019     	Q_RES_0402LF   	          	          	                    
          	               	1         	209A4     	CLK_25M_PCH_CPU1_DN 
          	               	2         	209A4     	CLK_25M_NSSC_CPU1_DN

R1020     	Q_RES_0402LF   	          	          	                    
          	               	1         	209B3     	CLK_25M_CK440_CPU0_R_DP
          	               	2         	209B3     	CLK_25M_NSSC_CPU0_DP

R1021     	Q_RES_0402LF   	          	          	                    
          	               	1         	209B3     	CLK_25M_CK440_CPU0_R_DN
          	               	2         	209B3     	CLK_25M_NSSC_CPU0_DN

R1022     	Q_RES_0402LF   	          	          	                    
          	               	1         	209A3     	CLK_25M_CK440_CPU1_R_DP
          	               	2         	209A3     	CLK_25M_NSSC_CPU1_DP

R1023     	Q_RES_0402LF   	          	          	                    
          	               	1         	209A3     	CLK_25M_CK440_CPU1_R_DN
          	               	2         	209A3     	CLK_25M_NSSC_CPU1_DN

R1024     	Q_RES_0402LF   	          	          	                    
          	               	1         	182B4     	JTAG_DBP_TCK_PCH    
          	               	2         	182B4     	GND                 

R1025     	Q_RES_0402LF   	          	          	                    
          	               	1         	182B4     	JTAG_DBP_CPU_GTL_TCK
          	               	2         	182B4     	GND                 

R1026     	Q_RES_0402LF   	          	          	                    
          	               	1         	182B3     	JTAG_DBP_PMODE      
          	               	2         	182B3     	P1V05_PCH_AUX       

R1044     	Q_RES_0402LF   	          	          	                    
          	               	1         	255B3     	LED_PWRGD_CPUPWRGD_GTL
          	               	2         	255B3     	P3V3_AUX            

R1089     	Q_RES_0402LF   	          	          	                    
          	               	1         	231A2     	P3V3_AUX            
          	               	2         	231A2     	SMB_SENSOR_M2_P0_3V3AUX_SCL

R1090     	Q_RES_0402LF   	          	          	                    
          	               	1         	231A2     	P3V3_AUX            
          	               	2         	231A2     	SMB_SENSOR_M2_P0_3V3AUX_SDA

R1099     	Q_RES_0402LF   	          	          	                    
          	               	1         	214A4     	P3V3_AUX            
          	               	2         	214A4     	PU_CLK25M_OSC_FPGA_EN

R1100     	Q_RES_0402LF   	          	          	                    
          	               	1         	214A3     	CLK_25M_OSC_FPGA_R  
          	               	2         	214A3     	CLK_25M_OSC_MAIN_FPGA

R1106     	Q_RES_0402LF   	          	          	                    
          	               	1         	215B1     	P3V3_AUX            
          	               	2         	215B1     	FM_PLD_REV_R_N      

R1117     	Q_RES_0402LF   	          	          	                    
          	               	1         	301A2     	MB0_P12V_STBY_PWRGD 
          	               	2         	301A2     	AGND_HSC            

R1123     	Q_RES_0402LF   	          	          	                    
          	               	1         	158B4     	P3V3_AUX            
          	               	2         	158B4     	PD_SMB_OCP1_HP_ADD2 

R1124     	Q_RES_0402LF   	          	          	                    
          	               	1         	158B4     	PD_SMB_OCP1_HP_ADD2 
          	               	2         	158B4     	GND                 

R1126     	Q_RES_0402LF   	          	          	                    
          	               	1         	158B4     	PD_SMB_OCP1_HP_ADD1 
          	               	2         	158B4     	GND                 

R1127     	Q_RES_0402LF   	          	          	                    
          	               	1         	158B4     	P3V3_AUX            
          	               	2         	158B4     	PD_SMB_OCP1_HP_ADD0 

R1128     	Q_RES_0402LF   	          	          	                    
          	               	1         	158B4     	PD_SMB_OCP1_HP_ADD0 
          	               	2         	158B4     	GND                 

R1129     	Q_RES_0402LF   	          	          	                    
          	               	1         	158A4     	P3V3_AUX            
          	               	2         	158A4     	HP_LVC3_OCP_V3_1_PRSNT2

R1130     	Q_RES_0402LF   	          	          	                    
          	               	1         	158B4     	SMB_PEHPCPU0_LVC3_SCL
          	               	2         	158B4     	SMB_PEHPCPU0_LVC3_R_SCL

R1131     	Q_RES_0402LF   	          	          	                    
          	               	1         	158B4     	SMB_PEHPCPU0_LVC3_SDA
          	               	2         	158B4     	SMB_PEHPCPU0_LVC3_R_SDA

R1132     	Q_RES_0402LF   	          	          	                    
          	               	1         	164B3     	P3V3_AUX            
          	               	2         	164B3     	HP_OCP_V3_2_RST_R   

R1138     	Q_RES_0402LF   	          	          	                    
          	               	1         	155A4     	P3V3_AUX            
          	               	2         	155A4     	CLK_50M_EN          

R1139     	Q_RES_0402LF   	          	          	                    
          	               	1         	155A4     	CLK_50M_RMII        
          	               	2         	155A4     	CLK_50M_RMII_R      

R1140     	Q_RES_0402LF   	          	          	                    
          	               	1         	155A3     	CLK_50M_BMC_MAC_R   
          	               	2         	155A3     	CLK_50M_RMII_BMC_OCP

R1141     	Q_RES_0402LF   	          	          	                    
          	               	1         	155A3     	CLK_50M_NCSI_OCP_1  
          	               	2         	155A3     	CLK_50M_NCSI_OCP_SFF

R1147     	Q_RES_0402LF   	          	          	                    
          	               	1         	156A3     	HP_LVC3_OCP_V3_1_PRSNT2_N_R
          	               	2         	156A2     	HP_LVC3_OCP_V3_1_ATTN_OUT_SW_N

R1148     	Q_RES_0402LF   	          	          	                    
          	               	1         	156A3     	HP_LVC3_OCP_V3_1_PRSNT2_N_R
          	               	2         	156A3     	HP_LVC3_OCP_V3_1_PRSNT2_N

R1149     	Q_RES_0402LF   	          	          	                    
          	               	1         	156A2     	P3V3_AUX            
          	               	2         	156A2     	HP_LVC3_OCP_V3_1_ATTN_OUT_SW_N

R1150     	Q_RES_0402LF   	          	          	                    
          	               	1         	156A2     	P3V3_AUX            
          	               	2         	156A2     	HP_LVC3_OCP_V3_1_PRSNT2_N

R1184     	Q_RES_0402LF   	          	          	                    
          	               	1         	239B2     	JTAG_BMC_DBP_TMS_R  
          	               	2         	239B2     	JTAG_BMC_DBP_TMS    

R1194     	Q_RES_0402LF   	          	          	                    
          	               	1         	208B4     	P3V3_AUX            
          	               	2         	208B4     	FM_CK440_MXCK_25M_100M

R1195     	Q_RES_0402LF   	          	          	                    
          	               	1         	218B4     	P3V3_AUX            
          	               	2         	218B4     	PU_PLD_HEARTBEAT_LVC3

R1196     	Q_RES_0402LF   	          	          	                    
          	               	1         	208B4     	FM_CK440_MXCK_25M_100M
          	               	2         	208B4     	GND                 

R1197     	Q_RES_0402LF   	          	          	                    
          	               	1         	182B4     	GND                 
          	               	2         	182B4     	PD_SUSCLK           

R1198     	Q_RES_0402LF   	          	          	                    
          	               	1         	182B4     	P3V3_AUX            
          	               	2         	182B4     	PU_ACPRESENT        

R1200     	Q_RES_0402LF   	          	          	                    
          	               	1         	182B2     	FM_PCH_TRIGGER0_N   
          	               	2         	182B2     	FM_PCH_TRIGGER0_R_N 

R1201     	Q_RES_0402LF   	          	          	                    
          	               	1         	182B2     	FM_PCH_TRIGGER1_N   
          	               	2         	182B2     	FM_PCH_TRIGGER1_R_N 

R1202     	Q_RES_0402LF   	          	          	                    
          	               	1         	185B4     	P3V3_RTC_AUX        
          	               	2         	185B4     	RST_SRTCRST_N       

R1203     	Q_RES_0402LF   	          	          	                    
          	               	1         	185B2     	P3V_BAT             
          	               	2         	185B2     	P3V_BAT_R           

R1204     	Q_RES_0402LF   	          	          	                    
          	               	1         	208B4     	P3V3_AUX            
          	               	2         	208B4     	PU_CK440_SHFT_LD_N  

R1205     	Q_RES_0402LF   	          	          	                    
          	               	1         	223B4     	RST_PLTRST_N        
          	               	2         	223B4     	RST_PLTRST_PLD_N    

R1206     	Q_RES_0402LF   	          	          	                    
          	               	1         	223B4     	RST_MB_STBY_R_N     
          	               	2         	223B4     	RST_MB_STBY_N       

R1207     	Q_RES_0402LF   	          	          	                    
          	               	1         	223B4     	RST_RSMRST_PLD_R_N  
          	               	2         	223B4     	RST_RSMRST_PCH_N    

R1214     	Q_RES_0402LF   	          	          	                    
          	               	1         	202B4     	IRQ_LPC_PIRQA_N_ESPI_ALERT0_N
          	               	2         	202B4     	IRQ_LPC_PIRQA_N_ESPI_ALERT0_R_N

R1215     	Q_RES_0402LF   	          	          	                    
          	               	1         	202B2     	IRQ_ESPI_LPC_SERIRQ_ALERT_N
          	               	2         	202B2     	IRQ_ESPI_LPC_SERIRQ_ALERT_R_N

R1216     	Q_RES_0402LF   	          	          	                    
          	               	1         	80A4      	P3V3_AUX            
          	               	2         	80A4      	FM_S3M_CPU0_CPLD_CRC_ERROR

R1217     	Q_RES_0402LF   	          	          	                    
          	               	1         	80A2      	P3V3_AUX            
          	               	2         	80A2      	FM_S3M_CPU1_CPLD_CRC_ERROR

R1220     	Q_RES_0402LF   	          	          	                    
          	               	1         	200A4     	P3V3_AUX            
          	               	2         	200A4     	FM_PCH_MCRO_LDO     

R1221     	Q_RES_0402LF   	          	          	                    
          	               	1         	200A4     	FM_PCH_MCRO_LDO     
          	               	2         	200A4     	GND                 

R1226     	Q_RES_0402LF   	          	          	                    
          	               	1         	43B2      	PD_JTAG_CPU0_PLD_TCK
          	               	2         	43B2      	GND                 

R1227     	Q_RES_0402LF   	          	          	                    
          	               	1         	43B2      	PD_JTAG_CPU1_PLD_TCK
          	               	2         	43B2      	GND                 

R1229     	Q_RES_0402LF   	          	          	                    
          	               	1         	119A4     	PVNN_TERM_CPU1      
          	               	2         	119A4     	PUD_XTAL_CPU1_MODE0 

R1230     	Q_RES_0402LF   	          	          	                    
          	               	1         	119A4     	PVNN_TERM_CPU1      
          	               	2         	119A4     	PUD_XTAL_CPU1_MODE1 

R1232     	Q_RES_0402LF   	          	          	                    
          	               	1         	119B4     	PVNN_TERM_CPU0      
          	               	2         	119B4     	PUD_XTAL_CPU0_MODE0 

R1233     	Q_RES_0402LF   	          	          	                    
          	               	1         	119B4     	PVNN_TERM_CPU0      
          	               	2         	119B4     	PUD_XTAL_CPU0_MODE1 

R1235     	Q_RES_0402LF   	          	          	                    
          	               	1         	119A4     	GND                 
          	               	2         	119A4     	PUD_XTAL_CPU1_MODE0 

R1236     	Q_RES_0402LF   	          	          	                    
          	               	1         	119A4     	GND                 
          	               	2         	119A4     	PUD_XTAL_CPU1_MODE1 

R1237     	Q_RES_0402LF   	          	          	                    
          	               	1         	119B4     	GND                 
          	               	2         	119B4     	PD_EXT_CLK_SEL_CPU0 

R1238     	Q_RES_0402LF   	          	          	                    
          	               	1         	119B4     	GND                 
          	               	2         	119B4     	PUD_XTAL_CPU0_MODE0 

R1239     	Q_RES_0402LF   	          	          	                    
          	               	1         	119B4     	GND                 
          	               	2         	119B4     	PUD_XTAL_CPU0_MODE1 

R1240     	Q_RES_0402LF   	          	          	                    
          	               	1         	117B4     	H_CPU0_PM_FAST_WAKE_N
          	               	2         	117B4     	H_CPU_PM_FAST_WAKE_N

R1241     	Q_RES_0402LF   	          	          	                    
          	               	1         	117B4     	H_PMAX_TRIGGER_IO_CPU0
          	               	2         	117B4     	GND                 

R1242     	Q_RES_0402LF   	          	          	                    
          	               	1         	117B4     	PVNN_TERM_CPU0      
          	               	2         	117B4     	H_CPU_PM_FAST_WAKE_N

R1243     	Q_RES_0402LF   	          	          	                    
          	               	1         	117B4     	H_PMAX_TRIGGER_IO_CPU1
          	               	2         	117B4     	GND                 

R1244     	Q_RES_0402LF   	          	          	                    
          	               	1         	117B3     	PVNN_TERM_CPU1      
          	               	2         	117B3     	H_CPU_PM_FAST_WAKE_N

R1247     	Q_RES_0402LF   	          	          	                    
          	               	1         	203A4     	FM_PCH_CPU_PWR_DEBUG_N
          	               	2         	203A4     	FM_CPU_FBRK_DEBUG_N 

R1249     	Q_RES_0402LF   	          	          	                    
          	               	1         	203B4     	FM_THERMTRIP_DLY_LVC1_N
          	               	2         	203B4     	H_THERMTRIP_LVC1_N  

R1253     	Q_RES_0402LF   	          	          	                    
          	               	1         	204B4     	PGPPA_AUX           
          	               	2         	204B4     	IRQ_LPC_PIRQA_N_ESPI_ALERT0_N

R1254     	Q_RES_0402LF   	          	          	                    
          	               	1         	204B4     	PGPPA_AUX           
          	               	2         	204B4     	IRQ_LPC_SERIRQ_ESPI_CS1_N

R1255     	Q_RES_0402LF   	          	          	                    
          	               	1         	204B4     	PGPPA_AUX           
          	               	2         	204B4     	ESPI_ALERT1_N_LPC_RCIN_N

R1257     	Q_RES_0402LF   	          	          	                    
          	               	1         	204B2     	P3V3_AUX            
          	               	2         	204B2     	PU_PCH_VRALERT_N    

R1259     	Q_RES_0402LF   	          	          	                    
          	               	1         	204B2     	P3V3_AUX            
          	               	2         	204B2     	PU_LPC_PME_N        

R1260     	Q_RES_0402LF   	          	          	                    
          	               	1         	204B2     	P1V05_PCH_AUX       
          	               	2         	204B2     	H_CPU_ERR0_PCH_R_N  

R1262     	Q_RES_0402LF   	          	          	                    
          	               	1         	204B2     	P1V05_PCH_AUX       
          	               	2         	204B2     	H_CPU_ERR2_PCH_R_N  

R1263     	Q_RES_0402LF   	          	          	                    
          	               	1         	203B4     	FM_PLT_BMC_THERMTRIP_R_N
          	               	2         	203B4     	FM_PCH_BMC_THERMTRIP_N

R1266     	Q_RES_0402LF   	          	          	                    
          	               	1         	203B3     	P1V05_PCH_AUX       
          	               	2         	203B3     	H_THERMTRIP_LVC1_N  

R1267     	Q_RES_0402LF   	          	          	                    
          	               	1         	208B4     	PU_CK440_SHFT_LD_N  
          	               	2         	208B4     	GND                 

R1268     	Q_RES_0402LF   	          	          	                    
          	               	1         	183A4     	IRQ_BMC_PCH_NMI_R   
          	               	2         	183A4     	IRQ_BMC_PCH_NMI     

R1269     	Q_RES_0402LF   	          	          	                    
          	               	1         	183A4     	IRQ_BMC_PCH_NMI     
          	               	2         	183A4     	GND                 

R1270     	Q_RES_0402LF   	          	          	                    
          	               	1         	44B1      	PD_CPU1_PROCDIS_COD_GTL_N
          	               	2         	44A1      	GND                 

R1271     	Q_RES_0402LF   	          	          	                    
          	               	1         	194A4     	P3V3_AUX            
          	               	2         	194A4     	FM_PCH_SATA_RAID_KEY

R1273     	Q_RES_0402LF   	          	          	                    
          	               	1         	209B4     	CLK_100M_OCP_SFF_2_R_DP
          	               	2         	209B4     	CLK_100M_OCP_SFF_2_DP

R1274     	Q_RES_0402LF   	          	          	                    
          	               	1         	209B4     	CLK_100M_OCP_SFF_2_R_DN
          	               	2         	209B4     	CLK_100M_OCP_SFF_2_DN

R1275     	Q_RES_0402LF   	          	          	                    
          	               	1         	209B4     	CLK_100M_OCP_SFF_3_R_DP
          	               	2         	209B4     	CLK_100M_OCP_SFF_3_DP

R1276     	Q_RES_0402LF   	          	          	                    
          	               	1         	209B4     	CLK_100M_OCP_SFF_3_R_DN
          	               	2         	209B4     	CLK_100M_OCP_SFF_3_DN

R1289     	Q_RES_0402LF   	          	          	                    
          	               	1         	154B3     	FB_BMC_ISOLATE      
          	               	2         	154B3     	GND                 

R1290     	Q_RES_0402LF   	          	          	                    
          	               	1         	154B1     	OCP_SFF_RBT_ARB_IN_R
          	               	2         	154B1     	OCP_SFF_RBT_ARB_IN  

R1291     	Q_RES_0402LF   	          	          	                    
          	               	1         	154B2     	NCSI_BMC_CRS_DV_R   
          	               	2         	154B2     	RMII_OCP_BMC_CRSDV  

R1292     	Q_RES_0402LF   	          	          	                    
          	               	1         	154B2     	NCSI_BMC_RXD0_R     
          	               	2         	154B2     	RMII_OCP_BMC_RXD_0  

R1293     	Q_RES_0402LF   	          	          	                    
          	               	1         	154B2     	NCSI_BMC_RXD1_R     
          	               	2         	154B2     	RMII_OCP_BMC_RXD_1  

R1294     	Q_RES_0402LF   	          	          	                    
          	               	1         	154B2     	NCSI_BMC_TX_EN_R    
          	               	2         	154B2     	RMII_BMC_OCP_TX_EN  

R1295     	Q_RES_0402LF   	          	          	                    
          	               	1         	154B2     	NCSI_BMC_TXD0_R     
          	               	2         	154B2     	RMII_BMC_OCP_TXD_0  

R1296     	Q_RES_0402LF   	          	          	                    
          	               	1         	154B2     	NCSI_BMC_TXD1_R     
          	               	2         	154B2     	RMII_BMC_OCP_TXD_1  

R1297     	Q_RES_0402LF   	          	          	                    
          	               	1         	197B3     	PECI_BMC_R          
          	               	2         	197B3     	PECI_BMC_B1         

R1298     	Q_RES_0402LF   	          	          	                    
          	               	1         	200B4     	P1V05_PCH_AUX       
          	               	2         	200B4     	FM_MFG_MODE         

R1299     	Q_RES_0402LF   	          	          	                    
          	               	1         	200B4     	FM_MFG_MODE         
          	               	2         	200B4     	GND                 

R1300     	Q_RES_0402LF   	          	          	                    
          	               	1         	205B4     	FM_BIOS_POST_CMPLT_N
          	               	2         	205B4     	FM_BIOS_POST_CMPLT_BMC_N

R1302     	Q_RES_0402LF   	          	          	                    
          	               	1         	219B4     	PWRGD_DRAMPWRGD_CPU0_AB_R_LVC1
          	               	2         	219B4     	GND                 

R1305     	Q_RES_0402LF   	          	          	                    
          	               	1         	208B4     	P3V3_AUX            
          	               	2         	208B4     	FM_PLD_CLKS_DEV_EN  

R1306     	Q_RES_0402LF   	          	          	                    
          	               	1         	205B4     	FM_PS_PWROK_DLY_R_SEL
          	               	2         	205B4     	FM_PS_PWROK_DLY_SEL 

R1307     	Q_RES_0402LF   	          	          	                    
          	               	1         	205B4     	FM_THROTTLE_N       
          	               	2         	205B4     	FM_THROTTLE_R_N     

R1308     	Q_RES_0402LF   	          	          	                    
          	               	1         	220A2     	FM_RST_PERST_BIT1   
          	               	2         	220A2     	GND                 

R1309     	Q_RES_0402LF   	          	          	                    
          	               	1         	205B4     	IRQ_SMI_ACTIVE_N    
          	               	2         	205B4     	IRQ_SMI_ACTIVE_BMC_N

R1310     	Q_RES_0402LF   	          	          	                    
          	               	1         	205B4     	IRQ_PCH_CPU_NMI_EVENT_R_N
          	               	2         	205B4     	IRQ_PCH_CPU_NMI_EVENT_N

R1311     	Q_RES_0402LF   	          	          	                    
          	               	1         	200B3     	FM_XTAL_INPUT_FREQUENCY_0_MGPIO
          	               	2         	200B3     	GND                 

R1312     	Q_RES_0402LF   	          	          	                    
          	               	1         	220A2     	FM_RST_PERST_BIT2   
          	               	2         	220A2     	GND                 

R1313     	Q_RES_0402LF   	          	          	                    
          	               	1         	205B4     	FM_PCH_GLB_RST_WARN_N
          	               	2         	205B4     	FM_PCH_PLD_GLB_RST_WARN_N

R1316     	Q_RES_0603LF   	          	          	                    
          	               	1         	179A4     	XTAL_PCH_25M_IN_R   
          	               	2         	179A4     	XTAL_PCH_25M_OUT    

R1317     	Q_RES_0402LF   	          	          	                    
          	               	1         	201B3     	P1V05_PCH_AUX       
          	               	2         	201B3     	PU_BIOS_RCVR_BOOT   

R1318     	Q_RES_0402LF   	          	          	                    
          	               	1         	223B2     	FM_THERMTRIP_DLY_LVC1_R_N
          	               	2         	223B2     	FM_THERMTRIP_DLY_LVC1_N

R1319     	Q_RES_0402LF   	          	          	                    
          	               	1         	241B1     	SMB_HOST_3V3AUX_SCL 
          	               	2         	241B1     	P3V3_AUX            

R1320     	Q_RES_0402LF   	          	          	                    
          	               	1         	201B3     	P3V3_AUX            
          	               	2         	201B3     	PU_SWAP_OVERRIDE_N  

R1324     	Q_RES_0402LF   	          	          	                    
          	               	1         	201B3     	GND                 
          	               	2         	201B3     	PD_BIOS_IMAGE_SWAP_N

R1325     	Q_RES_0402LF   	          	          	                    
          	               	1         	201B3     	P3V3_AUX            
          	               	2         	201B3     	PU_FLASH_SECURITY_STRAP

R1326     	Q_RES_0402LF   	          	          	                    
          	               	1         	219B4     	PWRGD_DRAMPWRGD_CPU0_CD_R_LVC1
          	               	2         	219B4     	GND                 

R1327     	Q_RES_0402LF   	          	          	                    
          	               	1         	219B4     	PWRGD_DRAMPWRGD_CPU0_EF_R_LVC1
          	               	2         	219B4     	GND                 

R1328     	Q_RES_0402LF   	          	          	                    
          	               	1         	219B4     	PWRGD_DRAMPWRGD_CPU0_GH_R_LVC1
          	               	2         	219B4     	GND                 

R1329     	Q_RES_0402LF   	          	          	                    
          	               	1         	219B4     	PWRGD_DRAMPWRGD_CPU1_AB_R_LVC1
          	               	2         	219B4     	GND                 

R1330     	Q_RES_0402LF   	          	          	                    
          	               	1         	219B4     	PWRGD_DRAMPWRGD_CPU1_CD_R_LVC1
          	               	2         	219B4     	GND                 

R1331     	Q_RES_0402LF   	          	          	                    
          	               	1         	243B4     	P3V3_AUX            
          	               	2         	243B4     	SMB_FRU_3V3AUX_SCL  

R1332     	Q_RES_0402LF   	          	          	                    
          	               	1         	243B4     	P3V3_AUX            
          	               	2         	243B4     	SMB_FRU_3V3AUX_SDA  

R1333     	Q_RES_0402LF   	          	          	                    
          	               	1         	201B3     	GND                 
          	               	2         	201B3     	PD_RST_RTCRST_N     

R1335     	Q_RES_0402LF   	          	          	                    
          	               	1         	201B3     	GND                 
          	               	2         	201B3     	PD_PASSWORD_CLEAR   

R1336     	Q_RES_0402LF   	          	          	                    
          	               	1         	241B1     	I3C_BMC_SWB_SCL     
          	               	2         	241B1     	P3V3_AUX            

R1338     	Q_RES_0402LF   	          	          	                    
          	               	1         	201B2     	FM_PCH_BIOS_RCVR_MODE
          	               	2         	201B2     	GND                 

R1339     	Q_RES_0402LF   	          	          	                    
          	               	1         	201B1     	P3V3_AUX            
          	               	2         	201B1     	FM_BIOS_IMAGE_SWAP_N

R1340     	Q_RES_0402LF   	          	          	                    
          	               	1         	201B2     	P3V3_RTC_AUX        
          	               	2         	201B2     	RST_RTCRST_N        

R1341     	Q_RES_0402LF   	          	          	                    
          	               	1         	201B2     	FM_ADR_COMPLETE     
          	               	2         	201B2     	GND                 

R1342     	Q_RES_0402LF   	          	          	                    
          	               	1         	201B1     	P1V05_PCH_AUX       
          	               	2         	201B1     	FM_ME_RCVR_N        

R1343     	Q_RES_0402LF   	          	          	                    
          	               	1         	201B1     	P1V05_PCH_AUX       
          	               	2         	201B1     	FM_PASSWORD_CLEAR_N 

R1345     	Q_RES_0402LF   	          	          	                    
          	               	1         	239B2     	JTAG_BMC_DBP_TDI_R  
          	               	2         	239B2     	JTAG_BMC_DBP_TDI    

R1346     	Q_RES_0402LF   	          	          	                    
          	               	1         	239B2     	P0V7_JTAG_VREF_2    
          	               	2         	239B2     	GND                 

R1347     	Q_RES_0402LF   	          	          	                    
          	               	1         	239B2     	PD_GTL2014_BMC_JTAG_VREF_1
          	               	2         	239B2     	GND                 

R1348     	Q_RES_0402LF   	          	          	                    
          	               	1         	134B2     	JTAG_DBP_CPU_GTL_TCK_R1
          	               	2         	134B2     	JTAG_DBP_CPU_GTL_TCK

R1349     	Q_RES_0402LF   	          	          	                    
          	               	1         	134B2     	JTAG_DBP_TCK_PCH_R  
          	               	2         	134B2     	JTAG_DBP_TCK_PCH    

R1350     	Q_RES_0402LF   	          	          	                    
          	               	1         	154B1     	RMII_OCP_BMC_CRSDV  
          	               	2         	154B1     	GND                 

R1351     	Q_RES_0402LF   	          	          	                    
          	               	1         	154B1     	RMII_OCP_BMC_RXD_0  
          	               	2         	154B1     	GND                 

R1352     	Q_RES_0402LF   	          	          	                    
          	               	1         	154B1     	RMII_OCP_BMC_RXD_1  
          	               	2         	154B1     	GND                 

R1353     	Q_RES_0402LF   	          	          	                    
          	               	1         	154B1     	RMII_BMC_OCP_TX_EN  
          	               	2         	154B1     	GND                 

R1354     	Q_RES_0402LF   	          	          	                    
          	               	1         	154B1     	RMII_BMC_OCP_TXD_0  
          	               	2         	154B1     	GND                 

R1355     	Q_RES_0402LF   	          	          	                    
          	               	1         	154B1     	RMII_BMC_OCP_TXD_1  
          	               	2         	154B1     	GND                 

R1356     	Q_RES_0402LF   	          	          	                    
          	               	1         	154A1     	RMII_BMC_OCP_RX_ER  
          	               	2         	154A1     	GND                 

R1365     	Q_RES_0402LF   	          	          	                    
          	               	1         	134B4     	FM_JTAG_TCK_MUX_SEL 
          	               	2         	134B4     	GND                 

R1366     	Q_RES_0402LF   	          	          	                    
          	               	1         	239B4     	JTAG_DBP_TDO        
          	               	2         	239B4     	JTAG_DBP_FB_TDO     

R1367     	Q_RES_0402LF   	          	          	                    
          	               	1         	239B4     	JTAG_DBP_PRDY_N     
          	               	2         	239B4     	JTAG_DBP_PRDY_R_N   

R1368     	Q_RES_0402LF   	          	          	                    
          	               	1         	239B4     	PD_JTAG_DBP_B2      
          	               	2         	239B4     	GND                 

R1369     	Q_RES_0402LF   	          	          	                    
          	               	1         	239B3     	PD_JTAG_DBP_B0      
          	               	2         	239B3     	GND                 

R1370     	Q_RES_0402LF   	          	          	                    
          	               	1         	134B4     	P3V3_AUX            
          	               	2         	134B4     	FM_REMOTE_DEBUG_DET_R

R1371     	Q_RES_0402LF   	          	          	                    
          	               	1         	256B3     	LED_RST_PLD_CPU0_DRAM_AB_N
          	               	2         	256B3     	P3V3_AUX            

R1374     	Q_RES_0402LF   	          	          	                    
          	               	1         	134B3     	PD_JTAG_BMC_NTRST_N 
          	               	2         	134B3     	GND                 

R1375     	Q_RES_0402LF   	          	          	                    
          	               	1         	134B3     	FM_BMC_EN_DET       
          	               	2         	134B3     	GND                 

R1380     	Q_RES_0402LF   	          	          	                    
          	               	1         	239B1     	P3V3_AUX            
          	               	2         	239B1     	JTAG_BMC_DBP_TDO    

R1381     	Q_RES_0402LF   	          	          	                    
          	               	1         	239B1     	P3V3_AUX            
          	               	2         	239B1     	FM_BMC_CPU_FBRK_OUT_N

R1382     	Q_RES_0402LF   	          	          	                    
          	               	1         	239B1     	P3V3_AUX            
          	               	2         	239B1     	JTAG_DBP_BMC_PRDY_N 

R1383     	Q_RES_0402LF   	          	          	                    
          	               	1         	239B1     	P3V3_AUX            
          	               	2         	239B1     	JTAG_BMC_DBP_PREQ_N 

R1384     	Q_RES_0402LF   	          	          	                    
          	               	1         	241B1     	SMB_SML0_3V3AUX_SCL 
          	               	2         	241B1     	P3V3_AUX            

R1385     	Q_RES_0402LF   	          	          	                    
          	               	1         	241B1     	SMB_SML0_3V3AUX_SDA 
          	               	2         	241B1     	P3V3_AUX            

R1386     	Q_RES_0402LF   	          	          	                    
          	               	1         	241B1     	SMB_SML1_PMBUS_3V3AUX_PCH_SCL
          	               	2         	241B1     	P3V3_AUX            

R1387     	Q_RES_0402LF   	          	          	                    
          	               	1         	241B1     	SMB_SML1_PMBUS_3V3AUX_PCH_SDA
          	               	2         	241B1     	P3V3_AUX            

R1388     	Q_RES_0402LF   	          	          	                    
          	               	1         	219B4     	PWRGD_DRAMPWRGD_CPU1_EF_R_LVC1
          	               	2         	219B4     	GND                 

R1389     	Q_RES_0402LF   	          	          	                    
          	               	1         	262B4     	FM_P1V05_PCH_AUX_EN 
          	               	2         	262B4     	FM_P1V05_PCH_AUX_R_EN

R1390     	Q_RES_0402LF   	          	          	                    
          	               	1         	208B4     	FM_PLD_CLKS_DEV_EN  
          	               	2         	208B4     	GND                 

R1391     	Q_RES_0402LF   	          	          	                    
          	               	1         	120B3     	GND                 
          	               	2         	120B3     	FM_S3M_CPU0_LVC1_GPIO_2

R1392     	Q_RES_0402LF   	          	          	                    
          	               	1         	120B3     	GND                 
          	               	2         	120B3     	FM_S3M_CPU0_LVC1_GPIO_3

R1393     	Q_RES_0402LF   	          	          	                    
          	               	1         	120B3     	GND                 
          	               	2         	120B3     	FM_S3M_CPU1_LVC1_GPIO_2

R1394     	Q_RES_0402LF   	          	          	                    
          	               	1         	120B3     	GND                 
          	               	2         	120B3     	FM_S3M_CPU1_LVC1_GPIO_3

R1395     	Q_RES_0402LF   	          	          	                    
          	               	1         	185A2     	SPI_PCH_TPM_CS_N    
          	               	2         	185A2     	SPI_TPM_CS_N        

R1396     	Q_RES_0402LF   	          	          	                    
          	               	1         	190B2     	FM_M2_SSD_0_PEDET   
          	               	2         	190B2     	P3V3_AUX            

R1398     	Q_RES_0402LF   	          	          	                    
          	               	1         	219B4     	PWRGD_CPU1_LVC1_R   
          	               	2         	219B4     	GND                 

R1399     	Q_RES_0402LF   	          	          	                    
          	               	1         	220B4     	FM_PFR_DSW_PWROK_N  
          	               	2         	220B4     	P3V3_AUX            

R1401     	Q_RES_0402LF   	          	          	                    
          	               	1         	220B4     	PU_MAIN_FPGA_CONFIG_DONE
          	               	2         	220B4     	P3V3_AUX            

R1402     	Q_RES_0402LF   	          	          	                    
          	               	1         	219B4     	PWRGD_SYS_PWROK     
          	               	2         	219B4     	GND                 

R1403     	Q_RES_0402LF   	          	          	                    
          	               	1         	219B4     	PWRGD_PCH_PWROK     
          	               	2         	219B4     	GND                 

R1404     	Q_RES_0402LF   	          	          	                    
          	               	1         	219A4     	FM_PCH_P1V8_AUX_EN  
          	               	2         	219A4     	GND                 

R1405     	Q_RES_0402LF   	          	          	                    
          	               	1         	219A4     	FM_PVCCIN_CPU0_R_EN 
          	               	2         	219A4     	GND                 

R1406     	Q_RES_0402LF   	          	          	                    
          	               	1         	219A4     	FM_PVCCIN_CPU1_R_EN 
          	               	2         	219A4     	GND                 

R1407     	Q_RES_0402LF   	          	          	                    
          	               	1         	219A4     	FM_PVCCINFAON_CPU0_R_EN
          	               	2         	219A4     	GND                 

R1408     	Q_RES_0402LF   	          	          	                    
          	               	1         	219A4     	FM_PVCCINFAON_CPU1_R_EN
          	               	2         	219A4     	GND                 

R1409     	Q_RES_0402LF   	          	          	                    
          	               	1         	219A4     	FM_PVCCFA_EHV_CPU0_R_EN
          	               	2         	219A4     	GND                 

R1410     	Q_RES_0402LF   	          	          	                    
          	               	1         	219A4     	FM_PVCCFA_EHV_CPU1_R_EN
          	               	2         	219A4     	GND                 

R1411     	Q_RES_0402LF   	          	          	                    
          	               	1         	219A4     	FM_PVCCFA_EHV_FIVRA_CPU0_R_EN
          	               	2         	219A4     	GND                 

R1412     	Q_RES_0402LF   	          	          	                    
          	               	1         	219A4     	FM_PVCCFA_EHV_FIVRA_CPU1_R_EN
          	               	2         	219A4     	GND                 

R1413     	Q_RES_0402LF   	          	          	                    
          	               	1         	219A4     	FM_PVCCD_HV_CPU0_EN 
          	               	2         	219A4     	GND                 

R1414     	Q_RES_0402LF   	          	          	                    
          	               	1         	219A4     	FM_PVCCD_HV_CPU1_EN 
          	               	2         	219A4     	GND                 

R1415     	Q_RES_0402LF   	          	          	                    
          	               	1         	219B4     	RST_CPU0_LVC1_R_N   
          	               	2         	219B4     	GND                 

R1416     	Q_RES_0402LF   	          	          	                    
          	               	1         	219B4     	RST_CPU1_LVC1_R_N   
          	               	2         	219B4     	GND                 

R1417     	Q_RES_0402LF   	          	          	                    
          	               	1         	219B4     	RST_PCIE_CPU0_DEV_PERST_N
          	               	2         	219B4     	GND                 

R1418     	Q_RES_0402LF   	          	          	                    
          	               	1         	219B4     	RST_PCIE_CPU1_DEV_PERST_N
          	               	2         	219B4     	GND                 

R1419     	Q_RES_0402LF   	          	          	                    
          	               	1         	219B4     	RST_PCIE_PCH_DEV_PERST_N
          	               	2         	219B4     	GND                 

R1420     	Q_RES_0402LF   	          	          	                    
          	               	1         	219B4     	RST_PLTRST_PLD_B_N  
          	               	2         	219B4     	GND                 

R1421     	Q_RES_0402LF   	          	          	                    
          	               	1         	219B4     	RST_RSMRST_PLD_R_N  
          	               	2         	219B4     	GND                 

R1423     	Q_RES_0402LF   	          	          	                    
          	               	1         	222B4     	PWRGD_SYS_PWROK_R   
          	               	2         	222B4     	PWRGD_SYS_PWROK     

R1434     	Q_RES_0402LF   	          	          	                    
          	               	1         	220B2     	FM_SYS_THROTTLE_R_N 
          	               	2         	220B2     	P3V3_AUX            

R1435     	Q_RES_0402LF   	          	          	                    
          	               	1         	220B2     	FM_ADR_TRIGGER_N    
          	               	2         	220B2     	P3V3_AUX            

R1437     	Q_RES_0402LF   	          	          	                    
          	               	1         	220B2     	FM_PLD_HEARTBEAT_LVC3
          	               	2         	220B2     	P3V3_AUX            

R1440     	Q_RES_0402LF   	          	          	                    
          	               	1         	220B2     	JTAG_PLD_TDO_R      
          	               	2         	220B2     	P3V3_AUX            

R1442     	Q_RES_0402LF   	          	          	                    
          	               	1         	222B4     	PWRGD_PCH_PWROK_R   
          	               	2         	222B4     	PWRGD_PCH_PWROK     

R1443     	Q_RES_0402LF   	          	          	                    
          	               	1         	222B4     	PWRGD_CPUPWRGD_LVC1 
          	               	2         	222B4     	PWRGD_CPUPWRGD_LVC1_R

R1444     	Q_RES_0402LF   	          	          	                    
          	               	1         	222B4     	PWRGD_P1V8_PCH_AUX  
          	               	2         	222B4     	PWRGD_P1V8_PCH_AUX_PLD

R1445     	Q_RES_0402LF   	          	          	                    
          	               	1         	282B4     	FM_PVNN_MAIN_CPU0_EN
          	               	2         	282B4     	GND                 

R1446     	Q_RES_0402LF   	          	          	                    
          	               	1         	224B2     	PWRGD_PS_PWROK_PLD_ISO
          	               	2         	224B2     	PWRGD_PS_PWROK_PLD_ISO_R

R1447     	Q_RES_0402LF   	          	          	                    
          	               	1         	222A4     	FM_CPU0_SKTOCC_LVT3_N
          	               	2         	222A4     	FM_CPU0_SKTOCC_LVT3_PLD_N

R1448     	Q_RES_0402LF   	          	          	                    
          	               	1         	222A4     	FM_CPU1_SKTOCC_LVT3_N
          	               	2         	222A4     	FM_CPU1_SKTOCC_LVT3_PLD_N

R1449     	Q_RES_0402LF   	          	          	                    
          	               	1         	204B3     	P3V3_AUX            
          	               	2         	204B3     	FM_BIOS_POST_CMPLT_N

R1450     	Q_RES_0402LF   	          	          	                    
          	               	1         	204B3     	P3V3_AUX            
          	               	2         	204B3     	FM_THROTTLE_N       

R1451     	Q_RES_0402LF   	          	          	                    
          	               	1         	183A2     	PU_SMB_SML3_3V3AUX_PCH_SCL
          	               	2         	183A1     	P3V3_AUX            

R1452     	Q_RES_0402LF   	          	          	                    
          	               	1         	183A2     	PU_SMB_SML3_3V3AUX_PCH_SDA
          	               	2         	183A1     	P3V3_AUX            

R1453     	Q_RES_0402LF   	          	          	                    
          	               	1         	183A2     	PU_SMB_SML4_3V3AUX_PCH_SCL
          	               	2         	183A1     	P3V3_AUX            

R1454     	Q_RES_0402LF   	          	          	                    
          	               	1         	183A2     	PU_SMB_SML4_3V3AUX_PCH_SDA
          	               	2         	183A1     	P3V3_AUX            

R1455     	Q_RES_0402LF   	          	          	                    
          	               	1         	205B4     	FM_ADR_MODE0_R      
          	               	2         	205B4     	FM_ADR_MODE0        

R1456     	Q_RES_0402LF   	          	          	                    
          	               	1         	205B4     	FM_CPU_RMCA_CATERR_DLY_LVT3_R_N
          	               	2         	205B4     	FM_CPU_RMCA_CATERR_DLY_N

R1457     	Q_RES_0402LF   	          	          	                    
          	               	1         	200B2     	FM_XTAL_INPUT_FREQUENCY_1_MGPIO
          	               	2         	200B2     	GND                 

R1458     	Q_RES_0402LF   	          	          	                    
          	               	1         	204A2     	P3V3_AUX            
          	               	2         	204A2     	IRQ_SMI_ACTIVE_N    

R1459     	Q_RES_0402LF   	          	          	                    
          	               	1         	204A2     	P3V3_AUX            
          	               	2         	204A2     	IRQ_PCH_CPU_NMI_EVENT_R_N

R1460     	Q_RES_0402LF   	          	          	                    
          	               	1         	241B1     	I3C_BMC_SWB_SDA     
          	               	2         	241B1     	P3V3_AUX            

R1461     	Q_RES_0402LF   	          	          	                    
          	               	1         	185A2     	FM_EUP_LOT6_N       
          	               	2         	185A2     	FM_SUSACK_N         

R1462     	Q_RES_0402LF   	          	          	                    
          	               	1         	208B4     	PD_CK440_SBI_CLK    
          	               	2         	208B4     	GND                 

R1463     	Q_RES_0402LF   	          	          	                    
          	               	1         	189B2     	P1V05_PCH_AUX       
          	               	2         	189B2     	P1V05_PCH_PLL_AUX   

R1464     	Q_RES_0402LF   	          	          	                    
          	               	1         	189B2     	P1V8_PCH_AUX        
          	               	2         	189B2     	P1V8_PCH_PLL_AUX    

R1465     	Q_RES_0402LF   	          	          	                    
          	               	1         	215B2     	P3V3_AUX            
          	               	2         	215B2     	IRQ_BMC_CPU_NMI_R1  

R1467     	Q_RES_0402LF   	          	          	                    
          	               	1         	213B2     	P3V3_AUX            
          	               	2         	213B2     	SMB_1_PLD_3V3AUX_SCL_R1

R1469     	Q_RES_0402LF   	          	          	                    
          	               	1         	223B2     	RST_PLTRST_PLD_B_N  
          	               	2         	223B2     	RST_PLTRST_B_N      

R1470     	Q_RES_0402LF   	          	          	                    
          	               	1         	223B2     	RST_PLTRST_PLD_B_N  
          	               	2         	223B2     	RST_PLTRST_B_MUX_N  

R1471     	Q_RES_0402LF   	          	          	                    
          	               	1         	208B4     	P3V3_AUX            
          	               	2         	208B4     	FM_CLK_CK440_SS_EN  

R1472     	Q_RES_0402LF   	          	          	                    
          	               	1         	131A3     	JTAG_DBP_PRESENT_R_N
          	               	2         	131A3     	FM_BMC_DBP_PRESENT_R_N

R1473     	Q_RES_0402LF   	          	          	                    
          	               	1         	220B2     	FM_RST_PERST_BIT1   
          	               	2         	220B2     	P3V3_AUX            

R1474     	Q_RES_0402LF   	          	          	                    
          	               	1         	220A2     	FM_RST_PERST_BIT2   
          	               	2         	220A2     	P3V3_AUX            

R1475     	Q_RES_0402LF   	          	          	                    
          	               	1         	200B3     	P3V3_AUX            
          	               	2         	200B3     	FM_PCH_RING_OSC_BYPASS_MGPIO_TE

R1476     	Q_RES_0402LF   	          	          	                    
          	               	1         	200B3     	FM_PCH_RING_OSC_BYPASS_MGPIO_TE
          	               	2         	200B3     	GND                 

R1477     	Q_RES_0402LF   	          	          	                    
          	               	1         	200B2     	P3V3_AUX            
          	               	2         	200B2     	FM_PCH_XTAL_INPUT_MODE_MGPIO_TE

R1478     	Q_RES_0402LF   	          	          	                    
          	               	1         	200B2     	FM_PCH_XTAL_INPUT_MODE_MGPIO_TE
          	               	2         	200B2     	GND                 

R1479     	Q_RES_0402LF   	          	          	                    
          	               	1         	202A4     	ESPI_LFRAME_N_BMC_CS0_N
          	               	2         	202A4     	ESPI_HOST_LPC_BMC_LFRAME_N

R1483     	Q_RES_0402LF   	          	          	                    
          	               	1         	208B4     	P3V3_AUX            
          	               	2         	208B4     	FM_CK440Q_DEV_25M_EN

R1484     	Q_RES_0402LF   	          	          	                    
          	               	1         	208B4     	FM_CK440Q_DEV_25M_EN
          	               	2         	208B4     	GND                 

R1485     	Q_RES_0402LF   	          	          	                    
          	               	1         	182B1     	PVNN_TERM_CPU0      
          	               	2         	182B1     	FM_PCH_TRIGGER0_R_N 

R1486     	Q_RES_0402LF   	          	          	                    
          	               	1         	182B1     	PVNN_TERM_CPU0      
          	               	2         	182B1     	FM_PCH_TRIGGER1_R_N 

R1487     	Q_RES_0402LF   	          	          	                    
          	               	1         	183A2     	FM_PCH_SATA_RAID_KEY
          	               	2         	183A2     	GND                 

R1492     	Q_RES_0402LF   	          	          	                    
          	               	1         	220A2     	FM_DIS_PS_PWROK_DLY 
          	               	2         	220A2     	P3V3_AUX            

R1493     	Q_RES_0402LF   	          	          	                    
          	               	1         	215B4     	P3V3_AUX            
          	               	2         	215B4     	PU_FORCE_PWRON      

R1494     	Q_RES_0402LF   	          	          	                    
          	               	1         	220A2     	FM_DIS_PS_PWROK_DLY 
          	               	2         	220A2     	GND                 

R1495     	Q_RES_0402LF   	          	          	                    
          	               	1         	215B4     	PD_FORCE_PWRON      
          	               	2         	215B4     	GND                 

R1496     	Q_RES_0402LF   	          	          	                    
          	               	1         	200A3     	P3V3_AUX            
          	               	2         	200A3     	FM_PCH_DFXTESTMODE  

R1497     	Q_RES_0402LF   	          	          	                    
          	               	1         	200A3     	FM_PCH_DFXTESTMODE  
          	               	2         	200A3     	GND                 

R1498     	Q_RES_0402LF   	          	          	                    
          	               	1         	200A2     	P1V05_PCH_AUX       
          	               	2         	200A2     	FM_BIOS_ADV_FUNCTIONS

R1499     	Q_RES_0402LF   	          	          	                    
          	               	1         	200A2     	FM_BIOS_ADV_FUNCTIONS
          	               	2         	200A2     	GND                 

R1500     	Q_RES_0402LF   	          	          	                    
          	               	1         	208B4     	PD_CK440_SBI_DATA_IN
          	               	2         	208B4     	GND                 

R1502     	Q_RES_0402LF   	          	          	                    
          	               	1         	208B4     	FM_CLK_CK440_SS_EN  
          	               	2         	208B4     	GND                 

R1504     	Q_RES_0402LF   	          	          	                    
          	               	1         	155B3     	RST_OCP_V3_1_BUF_N  
          	               	2         	155B3     	RST_PERST2_OCP_SFF_N

R1505     	Q_RES_0402LF   	          	          	                    
          	               	1         	155B3     	RST_OCP_V3_1_BUF_N  
          	               	2         	155B3     	RST_PERST3_OCP_SFF_N

R1514     	Q_RES_0402LF   	          	          	                    
          	               	1         	223B2     	RST_PCIE_CPU0_DEV_PERST_N
          	               	2         	223B2     	RST_OCP_V3_1_N      

R1520     	Q_RES_0402LF   	          	          	                    
          	               	1         	223B2     	RST_PCIE_CPU1_DEV_PERST_N
          	               	2         	223B2     	RST_OCP_V3_2_N      

R1525     	Q_RES_0402LF   	          	          	                    
          	               	1         	241B4     	SMB_HOST_3V3AUX_SCL_R
          	               	2         	241B4     	SMB_HOST_CLK_3V3AUX_SCL

R1526     	Q_RES_0402LF   	          	          	                    
          	               	1         	241B4     	SMB_HOST_3V3AUX_SDA_R
          	               	2         	241B4     	SMB_HOST_CLK_3V3AUX_SDA

R1527     	Q_RES_0402LF   	          	          	                    
          	               	1         	208B4     	FM_CLK_GEN1_OE0_N   
          	               	2         	208B4     	GND                 

R1541     	Q_RES_0402LF   	          	          	                    
          	               	1         	223B4     	GND                 
          	               	2         	223B4     	RST_PLTRST_N        

R1543     	Q_RES_0402LF   	          	          	                    
          	               	1         	206B3     	OCP_SFF_CLK_OE_N    
          	               	2         	206B3     	FM_DB2000_9_OE_N    

R1545     	Q_RES_0402LF   	          	          	                    
          	               	1         	183A2     	SMB_SML0B_3V3AUX_SCL
          	               	2         	183A1     	P3V3_AUX            

R1546     	Q_RES_0402LF   	          	          	                    
          	               	1         	183A2     	SMB_SML0B_3V3AUX_SDA
          	               	2         	183A1     	P3V3_AUX            

R1547     	Q_RES_0402LF   	          	          	                    
          	               	1         	213B2     	FM_TPM_PRSNT_R_N    
          	               	2         	213B2     	FM_TPM_PRSNT_N      

R1551     	Q_RES_0402LF   	          	          	                    
          	               	1         	213B2     	P3V3_AUX            
          	               	2         	213B2     	SMB_1_PLD_3V3AUX_SDA_R1

R1554     	Q_RES_0402LF   	          	          	                    
          	               	1         	204B4     	P3V3_AUX            
          	               	2         	204B4     	FM_ME_AUTHN_FAIL    

R1558     	Q_RES_0402LF   	          	          	                    
          	               	1         	220B4     	FM_CPU_RMCA_CATERR_LVT3_R_N
          	               	2         	220B4     	P3V3_AUX            

R1571     	Q_RES_0402LF   	          	          	                    
          	               	1         	259A4     	MB0_P12V_STBY_PWRGD 
          	               	2         	259A4     	P3V3_AUX_EN         

R1581     	Q_RES_0402LF   	          	          	                    
          	               	1         	183A2     	PU_SMB_PCH_PLD_3V3AUX_SCL
          	               	2         	183A1     	P3V3_AUX            

R1582     	Q_RES_0402LF   	          	          	                    
          	               	1         	183A2     	PU_SMB_PCH_PLD_3V3AUX_SDA
          	               	2         	183A1     	P3V3_AUX            

R1583     	Q_RES_0402LF   	          	          	                    
          	               	1         	183A2     	PU_PCH_PLD_3V3AUX_ALERT_N
          	               	2         	183A1     	P3V3_AUX            

R1592     	Q_RES_0402LF   	          	          	                    
          	               	1         	155B4     	P3V3_OCP_SFF        
          	               	2         	155B4     	PU_OCP_SFF_WAKE_OE  

R1593     	Q_RES_0402LF   	          	          	                    
          	               	1         	155B3     	P3V3_AUX            
          	               	2         	155B3     	OCP_SFF_PWRBRK_BUFF_N

R1594     	Q_RES_0402LF   	          	          	                    
          	               	1         	155B3     	OCP_SFF_WAKE_BUFF_N 
          	               	2         	155B3     	OCP_SFF_WAKE_BUFF_R_N

R1595     	Q_RES_0402LF   	          	          	                    
          	               	1         	155B3     	OCP_SFF_PWRBRK_BUFF_N
          	               	2         	155B2     	OCP_SFF_PWRBRK_N    

R1600     	Q_RES_0402LF   	          	          	                    
          	               	1         	183B2     	IRQ_SML0_ALERT_N    
          	               	2         	183B2     	IRQ_SML0_ALERT_R_N  

R1601     	Q_RES_0402LF   	          	          	                    
          	               	1         	183A2     	IRQ_SML0_ALERT_N    
          	               	2         	183A1     	P3V3_AUX            

R1605     	Q_RES_0402LF   	          	          	                    
          	               	1         	190B1     	PD_M2_0_DEVSLP      
          	               	2         	190B1     	GND                 

R1606     	Q_RES_0402LF   	          	          	                    
          	               	1         	213A2     	FM_OCP_SFF_PWR_GOOD 
          	               	2         	213A2     	FM_OCP_SFF_PWR_GOOD_R

R1607     	Q_RES_0402LF   	          	          	                    
          	               	1         	260B4     	FM_PS_EN_PLD_R      
          	               	2         	260B4     	VR_P5V_EN           

R1640     	Q_RES_0402LF   	          	          	                    
          	               	1         	260B4     	FM_P5V_EN           
          	               	2         	260B4     	VR_P5V_EN           

R1641     	Q_RES_0402LF   	          	          	                    
          	               	1         	260B4     	VR_P5V_EN           
          	               	2         	260B4     	GND                 

R1642     	Q_RES_0402LF   	          	          	                    
          	               	1         	260B4     	P12V_AUX            
          	               	2         	260B4     	VR_P5V_EN_D_R       

R1643     	Q_RES_0402LF   	          	          	                    
          	               	1         	260B4     	P12V_AUX            
          	               	2         	260B4     	VR_P5V_EN_N         

R1648     	Q_RES_0402LF   	          	          	                    
          	               	1         	236A2     	SMB_S3M_CPU0_3V3AUX_SDA
          	               	2         	236A2     	SMB_S3M_CPU1_3V3AUX_SDA

R1650     	Q_RES_0402LF   	          	          	                    
          	               	1         	262B2     	PWRGD_P1V05_PCH_AUX_R
          	               	2         	262B2     	PWRGD_P1V05_PCH_AUX 

R1652     	Q_RES_0402LF   	          	          	                    
          	               	1         	282B2     	PWRGD_PVNN_MAIN_CPU0_R
          	               	2         	282B2     	PWRGD_PVNN_MAIN_CPU0

R1654     	Q_RES_0402LF   	          	          	                    
          	               	1         	260B3     	VR_P5V_EN_D_R       
          	               	2         	260B3     	VR_P5V_EN_D_R1      

R1655     	Q_RES_0402LF   	          	          	                    
          	               	1         	260B2     	P12V_AUX            
          	               	2         	260B2     	PWRGD_P5V_ISO_R     

R1656     	Q_RES_0402LF   	          	          	                    
          	               	1         	183B2     	IRQ_SML1_PMBUS_ALERT_N
          	               	2         	183B2     	IRQ_SML1_PMBUS_PLD_ALERT_N

R1657     	Q_RES_0402LF   	          	          	                    
          	               	1         	183B2     	IRQ_SML1_PMBUS_ALERT_N
          	               	2         	183B2     	IRQ_SML1_PMBUS_BMC_ALERT_N

R1659     	Q_RES_0402LF   	          	          	                    
          	               	1         	183A2     	FM_PMBUS_ALERT_B_EN 
          	               	2         	183A1     	P3V3_AUX            

R1660     	Q_RES_0402LF   	          	          	                    
          	               	1         	220B4     	FM_SLP_SUS_RSM_RST_N
          	               	2         	220B4     	P3V3_AUX            

R1661     	Q_RES_0402LF   	          	          	                    
          	               	1         	241A4     	SMB_VR_3V3AUX_SCL   
          	               	2         	241A4     	SMB_VR_3V3AUX_SCL_R 

R1662     	Q_RES_0402LF   	          	          	                    
          	               	1         	241A4     	SMB_VR_3V3AUX_SDA   
          	               	2         	241A4     	SMB_VR_3V3AUX_SDA_R 

R1671     	Q_RES_0402LF   	          	          	                    
          	               	1         	153B4     	OCP_SFF_AUX_PWR_EN  
          	               	2         	153B4     	OCP_SFF_AUX_PWR_EN_R

R1673     	Q_RES_0402LF   	          	          	                    
          	               	1         	191B2     	P3V3_E1S_0          
          	               	2         	191B2     	RST_SMB_E1S_0_N     

R1675     	Q_RES_0402LF   	          	          	                    
          	               	1         	182A2     	FM_PCIE_EV_BIF_EN   
          	               	2         	182A2     	P3V3_AUX            

R1676     	Q_RES_0402LF   	          	          	                    
          	               	1         	182A2     	FM_PCIE_EV_BIF_EN   
          	               	2         	182A2     	GND                 

R1680     	Q_RES_0402LF   	          	          	                    
          	               	1         	208A3     	FM_PLD_CLK_25M_EN   
          	               	2         	208A3     	FM_CK440Q_DEV_25M_EN

R1681     	Q_RES_0402LF   	          	          	                    
          	               	1         	213B4     	P3V3_AUX            
          	               	2         	213B4     	PU_RST_DEDI_BUSY_PLD_N

R1688     	Q_RES_0402LF   	          	          	                    
          	               	1         	244B4     	P12V_AUX            
          	               	2         	244B4     	FM_COMP_P3V3_AUX_VIN

R1689     	Q_RES_0402LF   	          	          	                    
          	               	1         	244B4     	FM_COMP_P3V3_AUX_VIN
          	               	2         	244B4     	GND                 

R1690     	Q_RES_0402LF   	          	          	                    
          	               	1         	244B4     	P3V3_AUX            
          	               	2         	244B4     	FM_COMP_P3V3_AUX_ENIN

R1691     	Q_RES_0402LF   	          	          	                    
          	               	1         	244A4     	P3V3_AUX            
          	               	2         	244A4     	PWRGD_DSW_PWROK_R1  

R1692     	Q_RES_0402LF   	          	          	                    
          	               	1         	244A4     	PWRGD_DSW_PWROK_R1  
          	               	2         	244A4     	GND                 

R1693     	Q_RES_0402LF   	          	          	                    
          	               	1         	244A3     	PWRGD_DSW_PWROK_R2  
          	               	2         	244A3     	PWRGD_DSW_PWROK     

R1694     	Q_RES_0402LF   	          	          	                    
          	               	1         	244A2     	P3V3_AUX            
          	               	2         	244A2     	PWRGD_DSW_PWROK     

R1695     	Q_RES_0402LF   	          	          	                    
          	               	1         	244A2     	PWRGD_DSW_PWROK     
          	               	2         	244A2     	RST_RSMRST_PCH_N    

R1700     	Q_RES_0402LF   	          	          	                    
          	               	1         	194B3     	P3V3_AUX            
          	               	2         	194B3     	SMB_PCIE_M2_0_EN    

R1702     	Q_RES_0402LF   	          	          	                    
          	               	1         	194B2     	P1V8_PCH_AUX        
          	               	2         	194B2     	SMB_M2_P0_1V8AUX_SDA_R

R1703     	Q_RES_0402LF   	          	          	                    
          	               	1         	194B2     	P1V8_PCH_AUX        
          	               	2         	194B2     	SMB_M2_P0_1V8AUX_SCL_R

R1706     	Q_RES_0402LF   	          	          	                    
          	               	1         	260A4     	P3V3                
          	               	2         	260A4     	PWRGD_P3V3_R1       

R1710     	Q_RES_0402LF   	          	          	                    
          	               	1         	215B2     	FM_PLD_REV_N        
          	               	2         	215B1     	FM_PLD_REV_R_N      

R1712     	Q_RES_0402LF   	          	          	                    
          	               	1         	266B4     	SMB_VR_3V3AUX_SDA_R3
          	               	2         	266B4     	P3V3_AUX            

R1713     	Q_RES_0402LF   	          	          	                    
          	               	1         	266B4     	SMB_VR_3V3AUX_SCL_R3
          	               	2         	266B4     	P3V3_AUX            

R1714     	Q_RES_0402LF   	          	          	                    
          	               	1         	301B4     	SMB_SML1_PMBUS_HSC_SDA
          	               	2         	301B4     	SMB_SML1_PMBUS_HSC_R_SDA

R1717     	Q_RES_0402LF   	          	          	                    
          	               	1         	278B4     	PVNN_TERM_CPU0      
          	               	2         	278B4     	SVID_CLK1_CPU0_R    

R1718     	Q_RES_0402LF   	          	          	                    
          	               	1         	296B4     	PVNN_TERM_CPU1      
          	               	2         	296B4     	SVID_CLK1_CPU1_R    

R1719     	Q_RES_0402LF   	          	          	                    
          	               	1         	154B4     	OCP_SFF_AUX_PWR_EN  
          	               	2         	154B4     	OCP_SFF_AUX_PWR_EN_R1

R1720     	Q_RES_0402LF   	          	          	                    
          	               	1         	179A4     	XTAL_PCH_25M_IN_R   
          	               	2         	179A4     	XTAL_PCH_25M_IN     

R1721     	Q_RES_0402LF   	          	          	                    
          	               	1         	179A2     	XTAL_PCH_RTC2_R     
          	               	2         	179A2     	XTAL_PCH_RTC2       

R1724     	Q_RES_0402LF   	          	          	                    
          	               	1         	208A4     	XTAL_CLK_GEN1_25M_X1_R
          	               	2         	208A4     	XTAL_CLK_GEN1_25M_X1

R1735     	Q_RES_0402LF   	          	          	                    
          	               	1         	278B4     	PVNN_TERM_CPU0      
          	               	2         	278B4     	SVID_DIO1_CPU0_R    

R1736     	Q_RES_0402LF   	          	          	                    
          	               	1         	182A4     	FM_PCH_SLP_SUS_N    
          	               	2         	182A4     	FM_SLP_SUS_RSM_RST_N

R1741     	Q_RES_0402LF   	          	          	                    
          	               	1         	220B2     	FM_RST_PERST_BIT0   
          	               	2         	220B2     	P3V3_AUX            

R1742     	Q_RES_0402LF   	          	          	                    
          	               	1         	220A2     	FM_RST_PERST_BIT0   
          	               	2         	220A2     	GND                 

R1744     	Q_RES_0402LF   	          	          	                    
          	               	1         	223B4     	FM_BMC_PWRBTN_OUT_N 
          	               	2         	223B4     	FM_BMC_PWRBTN_N     

R1745     	Q_RES_0402LF   	          	          	                    
          	               	1         	244B4     	FM_COMP_P3V3_AUX_ENIN
          	               	2         	244B4     	FM_PFR_DSW_PWROK_N  

R1747     	Q_RES_0805LF   	          	          	                    
          	               	1         	257B2     	P1V8_PCH_AUX        
          	               	2         	257B2     	PGPPA_AUX           

R1748     	Q_RES_0402LF   	          	          	                    
          	               	1         	202B2     	FM_ESPI_PLD_EN      
          	               	2         	202B2     	FM_ESPI_PLD_R_EN_BUF

R1749     	Q_RES_0402LF   	          	          	                    
          	               	1         	202B3     	FM_ESPI_PLD_R1_EN   
          	               	2         	202A3     	GND                 

R1750     	Q_RES_0402LF   	          	          	                    
          	               	1         	202B2     	PGPPA_AUX           
          	               	2         	202B2     	FM_ESPI_PLD_R_EN_BUF

R1751     	Q_RES_0402LF   	          	          	                    
          	               	1         	222B2     	SGPIO_DO_0          
          	               	2         	222B2     	SGPIO_DEBUG_PLD_DOUT

R1752     	Q_RES_0402LF   	          	          	                    
          	               	1         	222B2     	SGPIO_CLK_0         
          	               	2         	222B2     	SGPIO_DEBUG_PLD_CLK 

R1753     	Q_RES_0402LF   	          	          	                    
          	               	1         	222B2     	SGPIO_DI_0          
          	               	2         	222B2     	SGPIO_DEBUG_PLD_DIN 

R1754     	Q_RES_0402LF   	          	          	                    
          	               	1         	222B2     	SGPIO_LD_0          
          	               	2         	222B2     	SGPIO_DEBUG_PLD_LD_N

R1755     	Q_RES_0402LF   	          	          	                    
          	               	1         	222B2     	SGPIO_DO_1          
          	               	2         	222B2     	SGPIO_BMC_DOUT      

R1756     	Q_RES_0402LF   	          	          	                    
          	               	1         	222B2     	SGPIO_CLK_1         
          	               	2         	222B2     	SGPIO_BMC_CLK       

R1757     	Q_RES_0402LF   	          	          	                    
          	               	1         	222B2     	SGPIO_DI_1          
          	               	2         	222B2     	SGPIO_BMC_DIN_R     

R1758     	Q_RES_0402LF   	          	          	                    
          	               	1         	222B2     	SGPIO_LD_1          
          	               	2         	222B2     	SGPIO_BMC_LD_N      

R1763     	Q_RES_0402LF   	          	          	                    
          	               	1         	257B4     	PGPPA_AUX           
          	               	2         	257B4     	FM_LPC_ESPI_SEL     

R1764     	Q_RES_0402LF   	          	          	                    
          	               	1         	257B4     	FM_LPC_ESPI_SEL     
          	               	2         	257B4     	GND                 

R1765     	Q_RES_0805LF   	          	          	                    
          	               	1         	257A2     	PGPPA_AUX           
          	               	2         	257A2     	P3V3_AUX            

R1785     	Q_RES_0402LF   	          	          	                    
          	               	1         	250B4     	P3V3_AUX_ADC        
          	               	2         	250B4     	GND                 

R1791     	Q_RES_0402LF   	          	          	                    
          	               	1         	250B4     	P5V_ADC             
          	               	2         	250B4     	GND                 

R1792     	Q_RES_0402LF   	          	          	                    
          	               	1         	250B2     	SMB_VR_3V3AUX_SDA_R1
          	               	2         	250B2     	SMB_SEN_MAM_3V3AUX_SDA

R1793     	Q_RES_0402LF   	          	          	                    
          	               	1         	250B2     	SMB_VR_3V3AUX_SCL_R1
          	               	2         	250B2     	SMB_SEN_MAM_3V3AUX_SCL

R1798     	Q_RES_0402LF   	          	          	                    
          	               	1         	240A4     	ROT_P1_RST_IND_N_R  
          	               	2         	240A4     	ROT_P1_RST_IND_N    

R1799     	Q_RES_0402LF   	          	          	                    
          	               	1         	250B4     	P12V_AUX            
          	               	2         	250A4     	P12V_AUX_ADC        

R1800     	Q_RES_0402LF   	          	          	                    
          	               	1         	250A4     	P12V_AUX_ADC        
          	               	2         	250A4     	GND                 

R1801     	Q_RES_0402LF   	          	          	                    
          	               	1         	240B1     	PRSNT0_N            
          	               	2         	240B1     	GND                 

R1809     	Q_RES_0402LF   	          	          	                    
          	               	1         	198B4     	P3V3_AUX            
          	               	2         	198B4     	FM_ADR_MODE0        

R1810     	Q_RES_0402LF   	          	          	                    
          	               	1         	198B4     	FM_ADR_MODE0        
          	               	2         	198B4     	GND                 

R1811     	Q_RES_0402LF   	          	          	                    
          	               	1         	222B2     	RST_SGPIO_RESET_N   
          	               	2         	222B2     	RST_SGPIO_RESET_N_R 

R1812     	Q_RES_0402LF   	          	          	                    
          	               	1         	222B2     	IRQ_SGPIO_INTR_N    
          	               	2         	222B2     	IRQ_SGPIO_INTR_N_R  

R1813     	Q_RES_0402LF   	          	          	                    
          	               	1         	239A4     	P3V3_AUX            
          	               	2         	239A4     	FM_JTAG_BMC_MUX_SEL 

R1814     	Q_RES_0402LF   	          	          	                    
          	               	1         	239A4     	FM_JTAG_BMC_MUX_SEL 
          	               	2         	239A4     	GND                 

R1815     	Q_RES_0402LF   	          	          	                    
          	               	1         	240A4     	FM_BMC_PWRBTN_OUT_N 
          	               	2         	240A4     	FM_BMC_PWRBTN_OUT_R_N

R1816     	Q_RES_0402LF   	          	          	                    
          	               	1         	240B4     	PWRGD_PS_PWROK      
          	               	2         	240B4     	PWRGD_PS_PWROK_R    

R1820     	Q_RES_0402LF   	          	          	                    
          	               	1         	203B4     	P3V3_AUX            
          	               	2         	203B4     	FM_PLT_BMC_THERMTRIP_R_N

R1821     	Q_RES_0402LF   	          	          	                    
          	               	1         	229A4     	FM_SPD_REMOTE_EN_R  
          	               	2         	229A4     	FM_SPD_REMOTE_EN    

R1822     	Q_RES_0402LF   	          	          	                    
          	               	1         	231B4     	P3V3_AUX            
          	               	2         	231B4     	RST_SMB_SWITCH_N    

R1823     	Q_RES_0402LF   	          	          	                    
          	               	1         	216B1     	P3V3_AUX            
          	               	2         	216B1     	RST_MB_STBY_R_N     

R1824     	Q_RES_0402LF   	          	          	                    
          	               	1         	155B4     	P3V3_OCP_SFF        
          	               	2         	155B4     	IRQ_LVC3_OCP_SFF_WAKE_N

R1827     	Q_RES_0402LF   	          	          	                    
          	               	1         	183B2     	USB_OC1_REAR_R_N    
          	               	2         	183B2     	USB_OC1_REAR_N      

R1828     	Q_RES_0402LF   	          	          	                    
          	               	1         	183A2     	USB_OC1_REAR_R_N    
          	               	2         	183A1     	P3V3_AUX            

R1831     	Q_RES_0402LF   	          	          	                    
          	               	1         	239B2     	JTAG_DBP_BMC_PRDY_N 
          	               	2         	239B2     	JTAG_DBP_BMC_PRDY_R_N

R1832     	Q_RES_0402LF   	          	          	                    
          	               	1         	239B2     	JTAG_BMC_DBP_PREQ_N 
          	               	2         	239B2     	JTAG_DBP_BMC_PREQ_R_N

R1833     	Q_RES_0402LF   	          	          	                    
          	               	1         	214A2     	FM_JTAG_BMC_MUX_SEL_R
          	               	2         	214A2     	FM_JTAG_BMC_MUX_SEL 

R1837     	Q_RES_4P_12    	          	          	                    
          	               	1         	251A4     	P12V_AUX            
          	               	2         	251A4     	P12V_S3_AUX_CPU1_NVDIMM
          	               	3         	251A4     	P12V_AUX_CPU1_DIMM_ISEN_P
          	               	4         	251A4     	P12V_AUX_CPU1_DIMM_ISEN_N

R1838     	Q_RES_4P_12    	          	          	                    
          	               	1         	251A4     	P12V_AUX            
          	               	2         	251A4     	P12V_S3_AUX_CPU0_NVDIMM
          	               	3         	251A4     	P12V_AUX_CPU0_DIMM_ISEN_P
          	               	4         	251A4     	P12V_AUX_CPU0_DIMM_ISEN_N

R1839     	Q_RES_0402LF   	          	          	                    
          	               	1         	185A4     	RST_PFR_OVR_RTC     
          	               	2         	185A4     	RST_RTCRST_N        

R1840     	Q_RES_0402LF   	          	          	                    
          	               	1         	185A4     	RST_PFR_OVR_SRTC    
          	               	2         	185A4     	RST_SRTCRST_N       

R1841     	Q_RES_0402LF   	          	          	                    
          	               	1         	218B4     	P3V3_AUX            
          	               	2         	218A4     	FM_CPU_RMCA_CATERR_LVT3_R_N

R1843     	Q_RES_0402LF   	          	          	                    
          	               	1         	222A2     	RST_PFR_OVR_RTC_R   
          	               	2         	222A2     	RST_PFR_OVR_RTC     

R1844     	Q_RES_0402LF   	          	          	                    
          	               	1         	222A2     	RST_PFR_OVR_SRTC_R  
          	               	2         	222A2     	RST_PFR_OVR_SRTC    

R1853     	Q_RES_0402LF   	          	          	                    
          	               	1         	213B2     	VIRTUAL_RESEAT_FPGA_R_N
          	               	2         	213B2     	VIRTUAL_RESEAT_FPGA_N

R1854     	Q_RES_0402LF   	          	          	                    
          	               	1         	242B4     	P3V3_AUX            
          	               	2         	242B4     	FM_SCM_PRSNT1_N     

R1856     	Q_RES_0402LF   	          	          	                    
          	               	1         	242B4     	FM_SCM_PRSNT1_N     
          	               	2         	242B4     	FM_SCM_PRSNT1_R_N   

R1857     	Q_RES_0402LF   	          	          	                    
          	               	1         	242B4     	P3V3_AUX            
          	               	2         	242B4     	P12V_SCM_EN         

R1868     	Q_RES_0402LF   	          	          	                    
          	               	1         	202A4     	ESPI_LAD0_DATA_IO3  
          	               	2         	202A4     	ESPI_LPC_LAD0_IO3   

R1869     	Q_RES_0402LF   	          	          	                    
          	               	1         	202A4     	ESPI_LAD0_DATA_IO2  
          	               	2         	202A4     	ESPI_LPC_LAD0_IO2   

R1870     	Q_RES_0402LF   	          	          	                    
          	               	1         	202A4     	ESPI_LAD0_DATA_IO1  
          	               	2         	202A4     	ESPI_LPC_LAD0_IO1   

R1871     	Q_RES_0402LF   	          	          	                    
          	               	1         	202A4     	ESPI_LAD0_DATA_IO0  
          	               	2         	202A4     	ESPI_LPC_LAD0_IO0   

R1872     	Q_RES_0402LF   	          	          	                    
          	               	1         	202A4     	CLK_24M_66M_LPC0_ESPI
          	               	2         	202A4     	ESPI_HOST_LPC_BMC_CLK

R1895     	Q_RES_0402LF   	          	          	                    
          	               	1         	153B1     	OCP_SFF_PRSNTA_R_N  
          	               	2         	153B1     	GND                 

R1896     	Q_RES_0402LF   	          	          	                    
          	               	1         	154A2     	OCP_SFF_ISO_BIF0_EN 
          	               	2         	154A2     	GND                 

R1897     	Q_RES_0402LF   	          	          	                    
          	               	1         	154A2     	OCP_SFF_ISO_BIF1_EN 
          	               	2         	154A2     	GND                 

R1898     	Q_RES_0402LF   	          	          	                    
          	               	1         	154A1     	OCP_SFF_ISO_BIF2_EN 
          	               	2         	154A1     	GND                 

R1905     	Q_RES_0402LF   	          	          	                    
          	               	1         	156A4     	P3V3_AUX            
          	               	2         	156A4     	OCP_SFF_PRSNT0_R_N  

R1906     	Q_RES_0402LF   	          	          	                    
          	               	1         	156A4     	P3V3_AUX            
          	               	2         	156A4     	OCP_SFF_PRSNT2_R_N  

R1907     	Q_RES_0402LF   	          	          	                    
          	               	1         	156A4     	P3V3_AUX            
          	               	2         	156A4     	OCP_SFF_PRSNT1_R_N  

R1908     	Q_RES_0402LF   	          	          	                    
          	               	1         	156A4     	P3V3_AUX            
          	               	2         	156A4     	OCP_SFF_PRSNT3_R_N  

R1919     	Q_RES_0402LF   	          	          	                    
          	               	1         	222A4     	PWRGD_P3V3_AUX      
          	               	2         	222A4     	PWRGD_P3V3_AUX_PLD  

R1921     	Q_RES_0402LF   	          	          	                    
          	               	1         	158B4     	FM_SMB_CPU0_ALERT   
          	               	2         	158B4     	FM_SMB_PEHPCPU0_PCIE_ALERT_N

R1929     	Q_RES_0402LF   	          	          	                    
          	               	1         	153B4     	GND                 
          	               	2         	153B4     	OCP_SFF_AUX_PWR_EN  

R1930     	Q_RES_0402LF   	          	          	                    
          	               	1         	153B4     	GND                 
          	               	2         	153B4     	OCP_SFF_MAIN_PWR_EN 

R1932     	Q_RES_0402LF   	          	          	                    
          	               	1         	14B4      	SMB_S3M_CPU0_PIROM_3V3AUX_SCL
          	               	2         	14B4      	SMB_S3M_CPU0_PIROM_3V3AUX_SCL_1

R1933     	Q_RES_0402LF   	          	          	                    
          	               	1         	14B4      	SMB_S3M_CPU0_PIROM_3V3AUX_SDA
          	               	2         	14B4      	SMB_S3M_CPU0_PIROM_3V3AUX_SDA_1

R1934     	Q_RES_0402LF   	          	          	                    
          	               	1         	45B4      	SMB_S3M_CPU1_PIROM_3V3AUX_SCL
          	               	2         	45B4      	SMB_S3M_CPU1_PIROM_3V3AUX_SCL_1

R1935     	Q_RES_0402LF   	          	          	                    
          	               	1         	45B4      	SMB_S3M_CPU1_PIROM_3V3AUX_SDA
          	               	2         	45B4      	SMB_S3M_CPU1_PIROM_3V3AUX_SDA_1

R1944     	Q_RES_0402LF   	          	          	                    
          	               	1         	215A2     	IRQ_PCH_SCI_WHEA_R_N
          	               	2         	215A2     	IRQ_PCH_SCI_WHEA_N  

R1950     	Q_RES_0402LF   	          	          	                    
          	               	1         	244B4     	FM_COMP_P3V3_AUX_VIN
          	               	2         	244B4     	FM_COMP_P3V3_AUX_VIN_R

R1955     	Q_RES_0402LF   	          	          	                    
          	               	1         	204B2     	P3V3_AUX            
          	               	2         	204B2     	FM_PCHHOT_N         

R1958     	Q_RES_0402LF   	          	          	                    
          	               	1         	208A4     	P3V3_AUX            
          	               	2         	208A4     	PU_CLK_PFT_LOST_N   

R1959     	Q_RES_0402LF   	          	          	                    
          	               	1         	14B4      	H_CPU0_PMDOWN_PCH_R2
          	               	2         	14B3      	H_CPU0_PMDOWN_PCH_R 

R1960     	Q_RES_0402LF   	          	          	                    
          	               	1         	14A4      	H_CPU0_PMSYNC_PCH_R2
          	               	2         	14A3      	H_CPU0_PMSYNC_PCH_R 

R1961     	Q_RES_0402LF   	          	          	                    
          	               	1         	202A4     	PGPPA_AUX           
          	               	2         	202A4     	ESPI_LFRAME_N_BMC_CS0_N

R1962     	Q_RES_0402LF   	          	          	                    
          	               	1         	198B2     	FM_PCH_CONSENT_STRAP_N
          	               	2         	198B2     	GND                 

R1995     	Q_RES_0402LF   	          	          	                    
          	               	1         	223B4     	FM_PCH_SLP_S3_N     
          	               	2         	223B4     	FM_SLPS3_PLD_N      

R1996     	Q_RES_0402LF   	          	          	                    
          	               	1         	223B4     	FM_PCH_SLP_S4_N     
          	               	2         	223B4     	FM_SLPS4_PLD_N      

R2071     	Q_RES_0402LF   	          	          	                    
          	               	1         	213A2     	FM_BMC_SUSACK_R_N   
          	               	2         	213A2     	FM_SUSACK_N         

R2113     	Q_RES_0402LF   	          	          	                    
          	               	1         	190A2     	RST_PCIE_PCH_DEV_BUF_M2_0_PERST
          	               	2         	190A2     	RST_PCIE_PCH_DEV_0_N

R2114     	Q_RES_0402LF   	          	          	                    
          	               	1         	191A2     	SMB_PCIE_E1S_ISO_EN_R2
          	               	2         	191A2     	SMB_PCIE_E1S_ISO_EN 

R2121     	Q_RES_0402LF   	          	          	                    
          	               	1         	190A2     	P3V3_AUX            
          	               	2         	190A2     	RST_PCIE_PCH_DEV_BUF_M2_0_PERST

R2125     	Q_RES_0402LF   	          	          	                    
          	               	1         	191A1     	P3V3_AUX            
          	               	2         	191A1     	SMB_PCIE_E1S_ISO_EN 

R2132     	Q_RES_0402LF   	          	          	                    
          	               	1         	202A4     	JTAG_TRC_PCH_PTI<6> 
          	               	2         	202A3     	FM_ESPI_PLD_R1_EN   

R2133     	Q_RES_0402LF   	          	          	                    
          	               	1         	201B3     	P3V3_AUX            
          	               	2         	201B3     	PU_ESPI_ENABLE_STRAP

R2134     	Q_RES_0402LF   	          	          	                    
          	               	1         	201B2     	JTAG_TRC_PCH_PTI<6> 
          	               	2         	201B2     	GND                 

R2155     	Q_RES_0402LF   	          	          	                    
          	               	1         	215A2     	FM_BMC_READY_R_PLD_N
          	               	2         	215A2     	FM_BMC_READY_R_N    

R2204     	Q_RES_0402LF   	          	          	                    
          	               	1         	231B2     	P3V3_AUX            
          	               	2         	231B2     	SMB_PCIE0_3V3AUX_SCL

R2205     	Q_RES_0402LF   	          	          	                    
          	               	1         	231B2     	P3V3_AUX            
          	               	2         	231B2     	SMB_PCIE0_3V3AUX_SDA

R2208     	Q_RES_0402LF   	          	          	                    
          	               	1         	236B2     	SMB_S3M_CPU0_3V3AUX_SDA_R
          	               	2         	236B2     	SMB_S3M_CPU0_3V3AUX_SDA

R2209     	Q_RES_0402LF   	          	          	                    
          	               	1         	236B2     	SMB_S3M_CPU0_3V3AUX_SCL_R
          	               	2         	236B2     	SMB_S3M_CPU0_3V3AUX_SCL

R2210     	Q_RES_0402LF   	          	          	                    
          	               	1         	236B2     	SMB_S3M_CPU1_3V3AUX_SDA_R
          	               	2         	236B2     	SMB_S3M_CPU1_3V3AUX_SDA

R2211     	Q_RES_0402LF   	          	          	                    
          	               	1         	236B2     	SMB_S3M_CPU1_3V3AUX_SCL_R
          	               	2         	236B2     	SMB_S3M_CPU1_3V3AUX_SCL

R2212     	Q_RES_0402LF   	          	          	                    
          	               	1         	241B1     	SMB_S3M_CPU_3V3AUX_SCL
          	               	2         	241B1     	P3V3_AUX            

R2213     	Q_RES_0402LF   	          	          	                    
          	               	1         	241B1     	SMB_S3M_CPU_3V3AUX_SDA
          	               	2         	241B1     	P3V3_AUX            

R2219     	Q_RES_0402LF   	          	          	                    
          	               	1         	306A4     	P12V_AUX            
          	               	2         	306A4     	A_P12V_STBY_ADR_TRIGGER

R2221     	Q_RES_0402LF   	          	          	                    
          	               	1         	306A3     	P12V_AUX            
          	               	2         	306A3     	A_P12V_STBY_FP_TRIGGER

R2222     	Q_RES_0402LF   	          	          	                    
          	               	1         	306A3     	A_P12V_STBY_FP_TRIGGER
          	               	2         	306A3     	GND                 

R2227     	Q_RES_0402LF   	          	          	                    
          	               	1         	306A4     	A_P12V_STBY_ADR_TRIGGER
          	               	2         	306A4     	GND                 

R2230     	Q_RES_0402LF   	          	          	                    
          	               	1         	306A2     	P3V3_AUX            
          	               	2         	306A2     	A_P12V_STBY_FPH_GATE

R2232     	Q_RES_0402LF   	          	          	                    
          	               	1         	195B1     	P1V05_PCH_AUX       
          	               	2         	195B1     	FAB_REV_ID0         

R2233     	Q_RES_0402LF   	          	          	                    
          	               	1         	306A2     	P3V3_AUX            
          	               	2         	306A2     	FM_UV_ADR_TRIGGER_N 

R2234     	Q_RES_0402LF   	          	          	                    
          	               	1         	195B3     	P1V05_PCH_AUX       
          	               	2         	195B3     	FM_BOARD_SKU_ID4    

R2235     	Q_RES_0402LF   	          	          	                    
          	               	1         	195B3     	FM_BOARD_SKU_ID4    
          	               	2         	195B3     	GND                 

R2236     	Q_RES_0402LF   	          	          	                    
          	               	1         	306A4     	P12V_AUX            
          	               	2         	306A4     	A_HSC_INAP          

R2238     	Q_RES_0402LF   	          	          	                    
          	               	1         	306A4     	A_HSC_INAP          
          	               	2         	306A4     	GND                 

R2240     	Q_RES_0402LF   	          	          	                    
          	               	1         	195B3     	P1V05_PCH_AUX       
          	               	2         	195B3     	FM_BOARD_SKU_ID1    

R2241     	Q_RES_0402LF   	          	          	                    
          	               	1         	195B3     	FM_BOARD_SKU_ID1    
          	               	2         	195B3     	GND                 

R2242     	Q_RES_0402LF   	          	          	                    
          	               	1         	195B3     	P1V05_PCH_AUX       
          	               	2         	195B3     	FM_BOARD_SKU_ID0    

R2243     	Q_RES_0402LF   	          	          	                    
          	               	1         	195B3     	FM_BOARD_SKU_ID0    
          	               	2         	195B3     	GND                 

R2244     	Q_RES_0402LF   	          	          	                    
          	               	1         	220B2     	ROT_P1_RST_IND_N_R  
          	               	2         	220B2     	P3V3_AUX            

R2252     	Q_RES_0402LF   	          	          	                    
          	               	1         	197B2     	PECI_MUX_SEL_R      
          	               	2         	197B2     	GND                 

R2253     	Q_RES_0402LF   	          	          	                    
          	               	1         	197B2     	P3V3_AUX            
          	               	2         	197B2     	PECI_MUX_SEL_R      

R2255     	Q_RES_0402LF   	          	          	                    
          	               	1         	197B2     	PECI_MUX_SEL_R      
          	               	2         	197B2     	FM_PECI_MUX_SEL_N   

R2256     	Q_RES_0402LF   	          	          	                    
          	               	1         	240B2     	USB2_7_R_DP         
          	               	2         	240B2     	USB2_7_DP           

R2257     	Q_RES_0402LF   	          	          	                    
          	               	1         	240B2     	USB2_7_R_DN         
          	               	2         	240B2     	USB2_7_DN           

R2268     	Q_RES_0402LF   	          	          	                    
          	               	1         	231B3     	RST_SMB_SWITCH_N    
          	               	2         	231B3     	PU_RST_SMB_PCIE0_N  

R2282     	Q_RES_0402LF   	          	          	                    
          	               	1         	191B2     	P3V3_AUX            
          	               	2         	191B2     	E1S_0_PRSNT         

R2287     	Q_RES_0402LF   	          	          	                    
          	               	1         	191B1     	P3V3_E1S_0          
          	               	2         	191B1     	E1S_0_PERST1_CLKREQ_N

R2296     	Q_RES_0402LF   	          	          	                    
          	               	1         	191B4     	E1S_0_PWRDIS        
          	               	2         	191B4     	GND                 

R2304     	Q_RES_0402LF   	          	          	                    
          	               	1         	191B2     	P3V3_AUX            
          	               	2         	191B2     	E1S_0_PRSNT_N       

R2308     	Q_RES_0402LF   	          	          	                    
          	               	1         	236B4     	P3V3_AUX            
          	               	2         	236B4     	PCA9543_S3M_ADDR1   

R2309     	Q_RES_0402LF   	          	          	                    
          	               	1         	236B4     	PCA9543_S3M_ADDR1   
          	               	2         	236B4     	GND                 

R2310     	Q_RES_0402LF   	          	          	                    
          	               	1         	236B4     	P3V3_AUX            
          	               	2         	236B4     	PCA9543_S3M_ADDR0   

R2311     	Q_RES_0402LF   	          	          	                    
          	               	1         	236B4     	PCA9543_S3M_ADDR0   
          	               	2         	236B4     	GND                 

R2312     	Q_RES_0402LF   	          	          	                    
          	               	1         	236B4     	P3V3_AUX            
          	               	2         	236B4     	PCA9545_S3M_INT_N   

R2313     	Q_RES_0402LF   	          	          	                    
          	               	1         	236B4     	RST_SMB_SWITCH_N    
          	               	2         	236B4     	RST_SMB_S3M_N       

R2315     	Q_RES_0402LF   	          	          	                    
          	               	1         	236B1     	P3V3_AUX            
          	               	2         	236B1     	PCA9543_S3M_INT0_N  

R2316     	Q_RES_0402LF   	          	          	                    
          	               	1         	258B3     	PWRGD_P5V_AUX_R     
          	               	2         	258B2     	PWRGD_P5V_AUX       

R2317     	Q_RES_0402LF   	          	          	                    
          	               	1         	191B4     	P3V3_E1S_0          
          	               	2         	191B4     	PU_E1S_0_DUALPORT_EN_N

R2322     	Q_RES_0402LF   	          	          	                    
          	               	1         	274B4     	PVNN_TERM_CPU0      
          	               	2         	274B4     	SVID_CLK0_CPU0_R    

R2330     	Q_RES_0402LF   	          	          	                    
          	               	1         	306A3     	PWRGD_DSW_PWROK_R4  
          	               	2         	306A3     	PWRGD_DSW_PWROK     

R2332     	Q_RES_0402LF   	          	          	                    
          	               	1         	281B4     	FM_PVPP_HBM_CPU0_EN 
          	               	2         	281B4     	GND                 

R2338     	Q_RES_0402LF   	          	          	                    
          	               	1         	282B4     	P3V3_AUX            
          	               	2         	282B4     	FM_PVNN_MAIN_CPU0_EN

R2339     	Q_RES_0402LF   	          	          	                    
          	               	1         	218A2     	LED_CPU_RMCA_CATERR_R
          	               	2         	218A2     	GND                 

R2342     	Q_RES_0402LF   	          	          	                    
          	               	1         	204B4     	P3V3_AUX            
          	               	2         	204B4     	FM_DEBUG_PORT_PRSNT_R_N

R2343     	Q_RES_0402LF   	          	          	                    
          	               	1         	213B4     	P5V_AUX_VCC         
          	               	2         	213B4     	PWRGD_P5V_AUX       

R2344     	Q_RES_0402LF   	          	          	                    
          	               	1         	213B4     	P3V3_AUX            
          	               	2         	213B4     	PWRGD_P5V_AUX_R1    

R2345     	Q_RES_0402LF   	          	          	                    
          	               	1         	292B4     	PVNN_TERM_CPU1      
          	               	2         	292B4     	SVID_CLK0_CPU1_R    

R2346     	Q_RES_0402LF   	          	          	                    
          	               	1         	213B4     	P3V3_AUX            
          	               	2         	213B4     	PWRGD_P5V_AUX_R2    

R2347     	Q_RES_0402LF   	          	          	                    
          	               	1         	215A4     	FM_REMOTE_DEBUG_DET_R
          	               	2         	215A4     	FM_REMOTE_DEBUG_DET 

R2348     	Q_RES_0402LF   	          	          	                    
          	               	1         	215A4     	FM_DEBUG_PORT_PRSNT_N
          	               	2         	215A4     	FM_DEBUG_PORT_PRSNT_R_N

R2350     	Q_RES_0402LF   	          	          	                    
          	               	1         	191A2     	FM_PS_EN_PLD_BUF1   
          	               	2         	191A2     	FM_PS_EN_PLD_BUF1_R1

R2354     	Q_RES_0402LF   	          	          	                    
          	               	1         	292B4     	PVNN_TERM_CPU1      
          	               	2         	292B4     	SVID_DIO0_CPU1_R    

R2355     	Q_RES_0402LF   	          	          	                    
          	               	1         	224B2     	P3V3_AUX            
          	               	2         	224B2     	FM_PS_EN_PLD_BUF1   

R2356     	Q_RES_0402LF   	          	          	                    
          	               	1         	258B3     	P5V_AUX_VCC         
          	               	2         	258B3     	PWRGD_P5V_AUX_R     

R2357     	Q_RES_0402LF   	          	          	                    
          	               	1         	262B2     	P3V3_AUX            
          	               	2         	262B2     	PWRGD_P1V05_PCH_AUX_R

R2358     	Q_RES_0402LF   	          	          	                    
          	               	1         	263B4     	FM_PCH_P1V8_AUX_EN  
          	               	2         	263B4     	FM_PCH_P1V8_AUX_EN_R

R2359     	Q_RES_0402LF   	          	          	                    
          	               	1         	263B3     	P3V3_AUX            
          	               	2         	263B3     	PWRGD_P1V8_PCH_AUX_R

R2360     	Q_RES_0402LF   	          	          	                    
          	               	1         	263B2     	PWRGD_P1V8_PCH_AUX_R
          	               	2         	263B2     	PWRGD_P1V8_PCH_AUX  

R2362     	Q_RES_0402LF   	          	          	                    
          	               	1         	14A4      	H_CPU0_PMDOWN_CPU1_R
          	               	2         	14A3      	H_CPU0_PMDOWN_CPU1_R1

R2363     	Q_RES_0402LF   	          	          	                    
          	               	1         	202B4     	RST_ESPI_RESET_N    
          	               	2         	202B4     	RST_ESPI_RESET_N_R  

R2365     	Q_RES_0402LF   	          	          	                    
          	               	1         	266B4     	P3V3_AUX            
          	               	2         	266B4     	PWRGD_PVCCIN_CPU0_R 

R2366     	Q_RES_0402LF   	          	          	                    
          	               	1         	266B4     	PWRGD_PVCCIN_CPU0   
          	               	2         	266B4     	PWRGD_PVCCIN_CPU0_R 

R2367     	Q_RES_0402LF   	          	          	                    
          	               	1         	299B4     	P3V3_AUX            
          	               	2         	299B4     	FM_PVPP_HBM_CPU1_EN 

R2368     	Q_RES_0402LF   	          	          	                    
          	               	1         	266B4     	SVID_CLK0_CPU0_R    
          	               	2         	266B4     	SVID_CLK_PVCCIN_CPU0_R

R2369     	Q_RES_0402LF   	          	          	                    
          	               	1         	266B4     	SVID_DIO0_CPU0_R    
          	               	2         	266B4     	SVID_DIO_PVCCIN_CPU0_R

R2370     	Q_RES_0402LF   	          	          	                    
          	               	1         	266B4     	SVID_ALERT0_CPU0_R_N
          	               	2         	266B4     	SVID_ALERT_PVCCIN_CPU0_R

R2371     	Q_RES_0402LF   	          	          	                    
          	               	1         	266B4     	SMB_VR_3V3AUX_SCL_R3
          	               	2         	266B4     	SMB_CLK_PVCCIN_CPU0 

R2372     	Q_RES_0402LF   	          	          	                    
          	               	1         	266B4     	SMB_VR_3V3AUX_SDA_R3
          	               	2         	266B4     	SMB_DIO_PVCCIN_CPU0 

R2373     	Q_RES_0402LF   	          	          	                    
          	               	1         	266B4     	P3V3_AUX            
          	               	2         	266B4     	IRQ_PVCCIN_CPU0_VRHOT_R_N

R2374     	Q_RES_0402LF   	          	          	                    
          	               	1         	299B4     	FM_PVPP_HBM_CPU1_EN 
          	               	2         	299B4     	GND                 

R2375     	Q_RES_0402LF   	          	          	                    
          	               	1         	266A4     	P3V3_AUX            
          	               	2         	266A4     	PVCCIN_CPU0_PIN_ALERT

R2376     	Q_RES_0402LF   	          	          	                    
          	               	1         	266A4     	IRQ_PSYS_CRIT_N     
          	               	2         	266A4     	PVCCIN_CPU0_PIN_ALERT

R2377     	Q_RES_0402LF   	          	          	                    
          	               	1         	266A4     	P3V3_AUX            
          	               	2         	266A4     	PWRGD_PVCCFA_EHV_FIVRA_CPU0_R

R2379     	Q_RES_0402LF   	          	          	                    
          	               	1         	266A4     	PWRGD_PVCCFA_EHV_FIVRA_CPU0
          	               	2         	266A4     	PWRGD_PVCCFA_EHV_FIVRA_CPU0_R

R2380     	Q_RES_0402LF   	          	          	                    
          	               	1         	299B2     	PWRGD_PVPP_HBM_CPU1_R
          	               	2         	299B2     	PWRGD_PVPP_HBM_CPU1 

R2381     	Q_RES_0402LF   	          	          	                    
          	               	1         	266A1     	SVID_CLK0_CPU0_R    
          	               	2         	266A1     	PVNN_TERM_CPU0      

R2382     	Q_RES_0402LF   	          	          	                    
          	               	1         	266A1     	SVID_ALERT0_CPU0_R_N
          	               	2         	266A1     	PVNN_TERM_CPU0      

R2383     	Q_RES_0402LF   	          	          	                    
          	               	1         	274B4     	P3V3_AUX            
          	               	2         	274B4     	PWRGD_PVCCINFAON_CPU0_R

R2384     	Q_RES_0402LF   	          	          	                    
          	               	1         	300B4     	P3V3_AUX            
          	               	2         	300B4     	FM_PVNN_MAIN_CPU1_EN

R2385     	Q_RES_0402LF   	          	          	                    
          	               	1         	300B4     	FM_PVNN_MAIN_CPU1_EN
          	               	2         	300B4     	GND                 

R2386     	Q_RES_0402LF   	          	          	                    
          	               	1         	274B4     	PVNN_TERM_CPU0      
          	               	2         	274B4     	SVID_DIO0_CPU0_R    

R2387     	Q_RES_0402LF   	          	          	                    
          	               	1         	300B2     	PWRGD_PVNN_MAIN_CPU1_R
          	               	2         	300B2     	PWRGD_PVNN_MAIN_CPU1

R2388     	Q_RES_0402LF   	          	          	                    
          	               	1         	274B4     	SVID_DIO0_CPU0_R    
          	               	2         	274B4     	SVID_DIO_PVCCINFAON_CPU0_R

R2389     	Q_RES_0402LF   	          	          	                    
          	               	1         	274B4     	SVID_ALERT0_CPU0_R_N
          	               	2         	274B4     	SVID_ALERT_PVCCINFAON_CPU0_R

R2390     	Q_RES_0402LF   	          	          	                    
          	               	1         	274B4     	SMB_VR_3V3AUX_SCL_R2
          	               	2         	274B4     	SMB_CLK_PVCCINFAON_CPU0

R2391     	Q_RES_0402LF   	          	          	                    
          	               	1         	274B4     	SMB_VR_3V3AUX_SDA_R2
          	               	2         	274B4     	SMB_DIO_PVCCINFAON_CPU0

R2392     	Q_RES_0402LF   	          	          	                    
          	               	1         	274A4     	P3V3_AUX            
          	               	2         	274A4     	PVCCINFAON_CPU0_VR_FAULT

R2393     	Q_RES_0402LF   	          	          	                    
          	               	1         	274A4     	P3V3_AUX            
          	               	2         	274A4     	PVCCINFAON_CPU0_PIN_ALERT

R2394     	Q_RES_0402LF   	          	          	                    
          	               	1         	274A4     	FM_PVCCFA_EHV_CPU0_EN
          	               	2         	274A4     	PVCCFA_EHV_CPU0_EN_R

R2396     	Q_RES_0402LF   	          	          	                    
          	               	1         	274A4     	P3V3_AUX            
          	               	2         	274A4     	PWRGD_PVCCFA_EHV_CPU0_R

R2397     	Q_RES_0402LF   	          	          	                    
          	               	1         	274A4     	PWRGD_PVCCFA_EHV_CPU0
          	               	2         	274A4     	PWRGD_PVCCFA_EHV_CPU0_R

R2398     	Q_RES_0402LF   	          	          	                    
          	               	1         	274A1     	P3V3_AUX            
          	               	2         	274A1     	IRQ_PVCCFA_CPU0_VRHOT_R_N

R2399     	Q_RES_0402LF   	          	          	                    
          	               	1         	278B4     	SVID_CLK1_CPU0_R    
          	               	2         	278B4     	SVID_CLK_PVCCD_HV_CPU0_R

R2400     	Q_RES_0402LF   	          	          	                    
          	               	1         	278B4     	SVID_DIO1_CPU0_R    
          	               	2         	278B4     	SVID_DIO_PVCCD_HV_CPU0_R

R2401     	Q_RES_0402LF   	          	          	                    
          	               	1         	278B4     	SVID_ALERT1_CPU0_R_N
          	               	2         	278B4     	SVID_ALERT_PVCCD_HV_CPU0_R

R2402     	Q_RES_0402LF   	          	          	                    
          	               	1         	278B4     	SMB_VR_3V3AUX_SCL_R2
          	               	2         	278B4     	SMB_CLK_PVCCD_HV_CPU0

R2403     	Q_RES_0402LF   	          	          	                    
          	               	1         	278B4     	SMB_VR_3V3AUX_SDA_R2
          	               	2         	278B4     	SMB_DIO_PVCCD_HV_CPU0

R2404     	Q_RES_0402LF   	          	          	                    
          	               	1         	278A1     	P3V3_AUX            
          	               	2         	278A1     	IRQ_PVCCD_CPU0_VRHOT_LVC3_N

R2405     	Q_RES_0402LF   	          	          	                    
          	               	1         	278A2     	IRQ_PVCCD_CPU0_VRHOT_LVC3_R_N
          	               	2         	278A2     	IRQ_PVCCD_CPU0_VRHOT_LVC3_N

R2406     	Q_RES_0402LF   	          	          	                    
          	               	1         	281B4     	P3V3_AUX            
          	               	2         	281B4     	FM_PVPP_HBM_CPU0_EN 

R2407     	Q_RES_0402LF   	          	          	                    
          	               	1         	281B3     	P3V3_AUX            
          	               	2         	281B3     	PWRGD_PVPP_HBM_CPU0_R

R2408     	Q_RES_0402LF   	          	          	                    
          	               	1         	281B2     	PWRGD_PVPP_HBM_CPU0_R
          	               	2         	281B2     	PWRGD_PVPP_HBM_CPU0 

R2409     	Q_RES_0402LF   	          	          	                    
          	               	1         	282B3     	P3V3_AUX            
          	               	2         	282B3     	PWRGD_PVNN_MAIN_CPU0_R

R2410     	Q_RES_0402LF   	          	          	                    
          	               	1         	194B2     	SMB_M2_P0_1V8AUX_SDA_R
          	               	2         	194B2     	SMB_M2_P0_1V8AUX_SDA

R2411     	Q_RES_0402LF   	          	          	                    
          	               	1         	194B2     	SMB_M2_P0_1V8AUX_SCL_R
          	               	2         	194B2     	SMB_M2_P0_1V8AUX_SCL

R2412     	Q_RES_0402LF   	          	          	                    
          	               	1         	214B2     	PWRGD_DSW_PWROK     
          	               	2         	214B2     	PWRGD_DSW_PWROK_R3  

R2413     	Q_RES_0402LF   	          	          	                    
          	               	1         	240B4     	SMB_2_BMC_GPU_SCL   
          	               	2         	240B4     	SMB_PCIE2_3V3AUX_SCL_R0

R2414     	Q_RES_0402LF   	          	          	                    
          	               	1         	240B4     	SMB_2_BMC_GPU_SDA   
          	               	2         	240B4     	SMB_PCIE2_3V3AUX_SDA_R0

R2415     	Q_RES_0402LF   	          	          	                    
          	               	1         	240B4     	SMB_1_BMC_GPU_SCL   
          	               	2         	240B4     	SMB_PCIE3_3V3AUX_SCL_R

R2416     	Q_RES_0402LF   	          	          	                    
          	               	1         	240B4     	SMB_1_BMC_GPU_SDA   
          	               	2         	240B4     	SMB_PCIE3_3V3AUX_SDA_R

R2417     	Q_RES_0402LF   	          	          	                    
          	               	1         	240B4     	SMB_S3M_CPU_3V3AUX_SCL
          	               	2         	240B4     	SMB_S3M_CPU_3V3AUX_SCL_R0

R2418     	Q_RES_0402LF   	          	          	                    
          	               	1         	240B4     	SMB_S3M_CPU_3V3AUX_SDA
          	               	2         	240B4     	SMB_S3M_CPU_3V3AUX_SDA_R0

R2419     	Q_RES_0402LF   	          	          	                    
          	               	1         	240B4     	SMB_HOST_3V3AUX_SCL 
          	               	2         	240B4     	SMB_HOST_3V3AUX_SCL_R0

R2420     	Q_RES_0402LF   	          	          	                    
          	               	1         	240B4     	SMB_HOST_3V3AUX_SDA 
          	               	2         	240B4     	SMB_HOST_3V3AUX_SDA_R0

R2421     	Q_RES_0402LF   	          	          	                    
          	               	1         	240B4     	SMB_VR_SENSOR_3V3AUX_SCL
          	               	2         	240B4     	SMB_VR_3V3AUX_SCL_R0

R2422     	Q_RES_0402LF   	          	          	                    
          	               	1         	240B4     	SMB_VR_SENSOR_3V3AUX_SDA
          	               	2         	240B4     	SMB_VR_3V3AUX_SDA_R0

R2423     	Q_RES_0402LF   	          	          	                    
          	               	1         	240B4     	SMB_SML1_PMBUS_3V3AUX_PCH_SCL
          	               	2         	240B4     	SMB_SML1_PMBUS_3V3AUX_PCH_SCL_R

R2424     	Q_RES_0402LF   	          	          	                    
          	               	1         	240B4     	SMB_SML1_PMBUS_3V3AUX_PCH_SDA
          	               	2         	240B4     	SMB_SML1_PMBUS_3V3AUX_PCH_SDA_R

R2425     	Q_RES_0402LF   	          	          	                    
          	               	1         	240B4     	SMB_OCP_V3_2_3V3AUX_SCL
          	               	2         	240B4     	SMB_OCP_V3_2_3V3AUX_SCL_R0

R2426     	Q_RES_0402LF   	          	          	                    
          	               	1         	191B1     	E1S_0_PERST1_CLKREQ_N
          	               	2         	191B1     	GND                 

R2449     	Q_RES_0402LF   	          	          	                    
          	               	1         	241A4     	SMB_VR_3V3AUX_SCL   
          	               	2         	241A4     	SMB_VR_3V3AUX_SCL_R1

R2450     	Q_RES_0402LF   	          	          	                    
          	               	1         	241A4     	SMB_VR_3V3AUX_SDA   
          	               	2         	241A4     	SMB_VR_3V3AUX_SDA_R1

R2451     	Q_RES_0402LF   	          	          	                    
          	               	1         	202B3     	P3V3_AUX            
          	               	2         	202B3     	FM_ESPI_PLD_R1_EN   

R2452     	Q_RES_0402LF   	          	          	                    
          	               	1         	214B2     	FM_ESPI_PLD_R_EN    
          	               	2         	214B2     	FM_ESPI_PLD_R1_EN   

R2453     	Q_RES_0402LF   	          	          	                    
          	               	1         	241A4     	SMB_VR_3V3AUX_SCL_R 
          	               	2         	241A4     	SMB_VR_3V3AUX_SCL_R2

R2454     	Q_RES_0402LF   	          	          	                    
          	               	1         	241A4     	SMB_VR_3V3AUX_SDA_R 
          	               	2         	241A4     	SMB_VR_3V3AUX_SDA_R2

R2455     	Q_RES_0402LF   	          	          	                    
          	               	1         	241A4     	SMB_VR_3V3AUX_SCL_R 
          	               	2         	241A4     	SMB_VR_3V3AUX_SCL_R3

R2456     	Q_RES_0402LF   	          	          	                    
          	               	1         	241A4     	SMB_VR_3V3AUX_SDA_R 
          	               	2         	241A4     	SMB_VR_3V3AUX_SDA_R3

R2457     	Q_RES_0402LF   	          	          	                    
          	               	1         	191A1     	E1S_0_EN            
          	               	2         	191A1     	GND                 

R2473     	Q_RES_0402LF   	          	          	                    
          	               	1         	154B3     	FB_BMC_ISOLATE_R1   
          	               	2         	154B3     	FB_BMC_ISOLATE      

R2474     	Q_RES_0402LF   	          	          	                    
          	               	1         	154A3     	FM_NCSI_OCP_V3_1_R_OE
          	               	2         	154A3     	FB_BMC_ISOLATE      

R2476     	Q_RES_0402LF   	          	          	                    
          	               	1         	194B2     	SMB_PCIE_M2_0_EN    
          	               	2         	194B2     	PWRGD_P1V8_PCH_AUX  

R2477     	Q_RES_0402LF   	          	          	                    
          	               	1         	235B2     	SMB_PEHPCPU0_LVC3_SCL_R0
          	               	2         	235B2     	SMB_PEHPCPU0_LVC3_SCL

R2478     	Q_RES_0402LF   	          	          	                    
          	               	1         	235B2     	SMB_PEHPCPU0_LVC3_SDA_R0
          	               	2         	235B2     	SMB_PEHPCPU0_LVC3_SDA

R2479     	Q_RES_0402LF   	          	          	                    
          	               	1         	235B2     	SMB_PEHPCPU1_LVC3_SCL_R0
          	               	2         	235B2     	SMB_PEHPCPU1_LVC3_SCL

R2480     	Q_RES_0402LF   	          	          	                    
          	               	1         	235B2     	SMB_PEHPCPU1_LVC3_SDA_R0
          	               	2         	235B2     	SMB_PEHPCPU1_LVC3_SDA

R2481     	Q_RES_0402LF   	          	          	                    
          	               	1         	208B4     	P3V3_AUX            
          	               	2         	208B4     	CLK_CK440_SMB_ADDR1 

R2486     	Q_RES_0402LF   	          	          	                    
          	               	1         	244B2     	P3V3_AUX            
          	               	2         	244B2     	PWRGD_P3V3_AUX_R2   

R2487     	Q_RES_0402LF   	          	          	                    
          	               	1         	155B2     	P3V3_AUX            
          	               	2         	155B2     	IRQ_LVC3_WAKE_BUF_N 

R2488     	Q_RES_0402LF   	          	          	                    
          	               	1         	155B3     	P3V3_AUX            
          	               	2         	155B3     	OCP_SFF_WAKE_BUFF_N 

R2489     	Q_RES_0402LF   	          	          	                    
          	               	1         	155A2     	IRQ_LVC3_WAKE_BUF_N 
          	               	2         	155A2     	IRQ_LVC3_WAKE_N     

R2490     	Q_RES_0402LF   	          	          	                    
          	               	1         	115B4     	PWRGD_FAIL_CPU0_AB  
          	               	2         	115B4     	PWRGD_FAIL_CPU0_AB_R1

R2491     	Q_RES_0402LF   	          	          	                    
          	               	1         	115B4     	PWRGD_FAIL_CPU0_CD  
          	               	2         	115B4     	PWRGD_FAIL_CPU0_CD_R1

R2492     	Q_RES_0402LF   	          	          	                    
          	               	1         	115B4     	PWRGD_FAIL_CPU0_EF  
          	               	2         	115B4     	PWRGD_FAIL_CPU0_EF_R1

R2493     	Q_RES_0402LF   	          	          	                    
          	               	1         	115B4     	PWRGD_FAIL_CPU0_GH  
          	               	2         	115B4     	PWRGD_FAIL_CPU0_GH_R1

R2494     	Q_RES_0402LF   	          	          	                    
          	               	1         	115B4     	PWRGD_FAIL_CPU1_AB  
          	               	2         	115B4     	PWRGD_FAIL_CPU1_AB_R1

R2495     	Q_RES_0402LF   	          	          	                    
          	               	1         	115A4     	PWRGD_FAIL_CPU1_CD  
          	               	2         	115A4     	PWRGD_FAIL_CPU1_CD_R1

R2496     	Q_RES_0402LF   	          	          	                    
          	               	1         	115A4     	PWRGD_FAIL_CPU1_EF  
          	               	2         	115A4     	PWRGD_FAIL_CPU1_EF_R1

R2497     	Q_RES_0402LF   	          	          	                    
          	               	1         	115A4     	PWRGD_FAIL_CPU1_GH  
          	               	2         	115A4     	PWRGD_FAIL_CPU1_GH_R1

R2498     	Q_RES_0402LF   	          	          	                    
          	               	1         	115B2     	PWRGD_FAIL_CPU0_AB_R1
          	               	2         	115B2     	PWRGD_FAIL_CPU0_AB_R

R2499     	Q_RES_0402LF   	          	          	                    
          	               	1         	115B2     	PWRGD_FAIL_CPU0_CD_R1
          	               	2         	115B2     	PWRGD_FAIL_CPU0_CD_R

R2500     	Q_RES_0402LF   	          	          	                    
          	               	1         	115B2     	PWRGD_FAIL_CPU0_EF_R1
          	               	2         	115B2     	PWRGD_FAIL_CPU0_EF_R

R2501     	Q_RES_0402LF   	          	          	                    
          	               	1         	115B2     	PWRGD_FAIL_CPU0_GH_R1
          	               	2         	115B2     	PWRGD_FAIL_CPU0_GH_R

R2502     	Q_RES_0402LF   	          	          	                    
          	               	1         	115B2     	PWRGD_FAIL_CPU1_AB_R1
          	               	2         	115B2     	PWRGD_FAIL_CPU1_AB_R

R2503     	Q_RES_0402LF   	          	          	                    
          	               	1         	115A2     	PWRGD_FAIL_CPU1_CD_R1
          	               	2         	115A2     	PWRGD_FAIL_CPU1_CD_R

R2504     	Q_RES_0402LF   	          	          	                    
          	               	1         	115A2     	PWRGD_FAIL_CPU1_EF_R1
          	               	2         	115A2     	PWRGD_FAIL_CPU1_EF_R

R2505     	Q_RES_0402LF   	          	          	                    
          	               	1         	115A2     	PWRGD_FAIL_CPU1_GH_R1
          	               	2         	115A2     	PWRGD_FAIL_CPU1_GH_R

R2506     	Q_RES_0402LF   	          	          	                    
          	               	1         	239B1     	P3V3_AUX            
          	               	2         	239B1     	JTAG_BMC_DBP_TMS    

R2507     	Q_RES_0402LF   	          	          	                    
          	               	1         	239B1     	P3V3_AUX            
          	               	2         	239B1     	JTAG_BMC_DBP_TDI    

R2508     	Q_RES_0402LF   	          	          	                    
          	               	1         	184B4     	P3V3_AUX            
          	               	2         	184B4     	FM_M2_SSD0_E7_PEDET 

R2509     	Q_RES_0402LF   	          	          	                    
          	               	1         	184A4     	FM_M2_SSD0_E7_PEDET 
          	               	2         	184A4     	GND                 

R2510     	Q_RES_0402LF   	          	          	                    
          	               	1         	184B4     	P3V3_AUX            
          	               	2         	184B4     	FM_M2_E1S_E6_PEDET  

R2511     	Q_RES_0402LF   	          	          	                    
          	               	1         	184A4     	FM_M2_E1S_E6_PEDET  
          	               	2         	184A4     	GND                 

R2512     	Q_RES_0402LF   	          	          	                    
          	               	1         	239B2     	P1V05_PCH_AUX       
          	               	2         	239B2     	P0V7_JTAG_VREF_2    

R2513     	Q_RES_0402LF   	          	          	                    
          	               	1         	239B2     	PD_GTL2014_BMC_JTAG_DIR_2
          	               	2         	239B2     	GND                 

R2514     	Q_RES_0402LF   	          	          	                    
          	               	1         	239B2     	PU_GTL2014_BMC_JTAG_DIR_1
          	               	2         	239B2     	GND                 

R2520     	Q_RES_0402LF   	          	          	                    
          	               	1         	284B4     	SMB_VR_3V3AUX_SCL_R3
          	               	2         	284B4     	SMB_CLK_PVCCIN_CPU1 

R2521     	Q_RES_0402LF   	          	          	                    
          	               	1         	284B4     	SMB_VR_3V3AUX_SDA_R3
          	               	2         	284B4     	SMB_DIO_PVCCIN_CPU1 

R2522     	Q_RES_0402LF   	          	          	                    
          	               	1         	284B4     	P3V3_AUX            
          	               	2         	284B4     	IRQ_PVCCIN_CPU1_VRHOT_R_N

R2523     	Q_RES_0402LF   	          	          	                    
          	               	1         	284A4     	IRQ_PVCCIN_CPU1_VRHOT_R_N
          	               	2         	284A4     	IRQ_PVCCIN_CPU1_VRHOT_N

R2524     	Q_RES_0402LF   	          	          	                    
          	               	1         	284A4     	P3V3_AUX            
          	               	2         	284A4     	PVCCIN_CPU1_VR_FAULT

R2525     	Q_RES_0402LF   	          	          	                    
          	               	1         	284A4     	P3V3_AUX            
          	               	2         	284A4     	PVCCIN_CPU1_PIN_ALERT

R2526     	Q_RES_0402LF   	          	          	                    
          	               	1         	190B2     	FM_M2_SSD_0_PEDET   
          	               	2         	190B2     	FM_M2_SSD0_E7_PEDET 

R2528     	Q_RES_0402LF   	          	          	                    
          	               	1         	247B3     	P12V_AUX            
          	               	2         	247B3     	FM_P12V_HSC_EN_N    

R2529     	Q_RES_0402LF   	          	          	                    
          	               	1         	247B3     	FM_P12V_HSC_EN_N    
          	               	2         	247B3     	FM_P12V_HSC_EN_R_N  

R2530     	Q_RES_0402LF   	          	          	                    
          	               	1         	247B2     	P12V_AUX            
          	               	2         	247B2     	P12V_AUX_BLEEDING   

R2531     	Q_RES_0402LF   	          	          	                    
          	               	1         	247B4     	MB0_P12V_STBY_PWRGD 
          	               	2         	247B4     	FM_P12V_HSC_EN_R    

R2550     	Q_RES_0402LF   	          	          	                    
          	               	1         	284A4     	FM_PVCCFA_EHV_FIVRA_CPU1_EN
          	               	2         	284A4     	PVCCFA_EHV_FIVRA_CPU1_EN_R

R2551     	Q_RES_0402LF   	          	          	                    
          	               	1         	284A4     	P3V3_AUX            
          	               	2         	284A4     	PWRGD_PVCCFA_EHV_FIVRA_CPU1_R

R2552     	Q_RES_0402LF   	          	          	                    
          	               	1         	284A4     	PWRGD_PVCCFA_EHV_FIVRA_CPU1
          	               	2         	284A4     	PWRGD_PVCCFA_EHV_FIVRA_CPU1_R

R2553     	Q_RES_0402LF   	          	          	                    
          	               	1         	284A1     	SVID_DIO0_CPU1_R    
          	               	2         	284A1     	PVNN_TERM_CPU1      

R2554     	Q_RES_0402LF   	          	          	                    
          	               	1         	284A1     	SVID_CLK0_CPU1_R    
          	               	2         	284A1     	PVNN_TERM_CPU1      

R2555     	Q_RES_0402LF   	          	          	                    
          	               	1         	284A1     	SVID_ALERT0_CPU1_R_N
          	               	2         	284A1     	PVNN_TERM_CPU1      

R2556     	Q_RES_0402LF   	          	          	                    
          	               	1         	292B4     	P3V3_AUX            
          	               	2         	292B4     	PWRGD_PVCCINFAON_CPU1_R

R2557     	Q_RES_0402LF   	          	          	                    
          	               	1         	296A2     	IRQ_PVCCD_CPU1_VRHOT_LVC3_R_N
          	               	2         	296A2     	IRQ_PVCCD_CPU1_VRHOT_LVC3_N

R2558     	Q_RES_0402LF   	          	          	                    
          	               	1         	292B4     	FM_PVCCINFAON_CPU1_EN
          	               	2         	292B4     	PVCCINFAON_CPU1_EN_R

R2559     	Q_RES_0402LF   	          	          	                    
          	               	1         	292B4     	SVID_CLK0_CPU1_R    
          	               	2         	292B4     	SVID_CLK_PVCCINFAON_CPU1_R

R2560     	Q_RES_0402LF   	          	          	                    
          	               	1         	292B4     	SVID_DIO0_CPU1_R    
          	               	2         	292B4     	SVID_DIO_PVCCINFAON_CPU1_R

R2561     	Q_RES_0402LF   	          	          	                    
          	               	1         	292B4     	SVID_ALERT0_CPU1_R_N
          	               	2         	292B4     	SVID_ALERT_PVCCINFAON_CPU1_R

R2562     	Q_RES_0402LF   	          	          	                    
          	               	1         	206B3     	OCP_SFF_CLK_OE_N    
          	               	2         	206B3     	FM_DB2000_10_OE_N   

R2563     	Q_RES_0402LF   	          	          	                    
          	               	1         	292B4     	SMB_VR_3V3AUX_SDA_R 
          	               	2         	292B4     	SMB_DIO_PVCCINFAON_CPU1

R2565     	Q_RES_0402LF   	          	          	                    
          	               	1         	231B2     	SMB_FRU_3V3AUX_SCL_R
          	               	2         	231B2     	SMB_FRU_3V3AUX_SCL  

R2566     	Q_RES_0402LF   	          	          	                    
          	               	1         	231B2     	SMB_FRU_3V3AUX_SDA_R
          	               	2         	231B2     	SMB_FRU_3V3AUX_SDA  

R2568     	Q_RES_0402LF   	          	          	                    
          	               	1         	292A4     	P3V3_AUX            
          	               	2         	292A4     	PVCCINFAON_CPU1_VR_FAULT

R2569     	Q_RES_0402LF   	          	          	                    
          	               	1         	292A4     	P3V3_AUX            
          	               	2         	292A4     	PVCCINFAON_CPU1_PIN_ALERT

R2570     	Q_RES_0402LF   	          	          	                    
          	               	1         	292A4     	FM_PVCCFA_EHV_CPU1_EN
          	               	2         	292A4     	PVCCFA_EHV_CPU1_EN_R

R2571     	Q_RES_0402LF   	          	          	                    
          	               	1         	292A4     	P3V3_AUX            
          	               	2         	292A4     	PWRGD_PVCCFA_EHV_CPU1_R

R2572     	Q_RES_0402LF   	          	          	                    
          	               	1         	292A4     	PWRGD_PVCCFA_EHV_CPU1
          	               	2         	292A4     	PWRGD_PVCCFA_EHV_CPU1_R

R2573     	Q_RES_0402LF   	          	          	                    
          	               	1         	292A1     	P3V3_AUX            
          	               	2         	292A1     	IRQ_PVCCFA_CPU1_VRHOT_R_N

R2574     	Q_RES_0402LF   	          	          	                    
          	               	1         	292A2     	IRQ_PVCCFA_CPU1_VRHOT_N
          	               	2         	292A2     	IRQ_PVCCFA_CPU1_VRHOT_R_N

R2575     	Q_RES_0402LF   	          	          	                    
          	               	1         	296B4     	P3V3_AUX            
          	               	2         	296B4     	PWRGD_PVCCD_HV_CPU1_R

R2576     	Q_RES_0402LF   	          	          	                    
          	               	1         	296B4     	PWRGD_PVCCD_HV_CPU1 
          	               	2         	296B4     	PWRGD_PVCCD_HV_CPU1_R

R2577     	Q_RES_0402LF   	          	          	                    
          	               	1         	296B4     	FM_PVCCD_HV_CPU1_EN 
          	               	2         	296B4     	PVCCD_HV_CPU1_EN_R  

R2578     	Q_RES_0402LF   	          	          	                    
          	               	1         	296B4     	SVID_CLK1_CPU1_R    
          	               	2         	296B4     	SVID_CLK_PVCCD_HV_CPU1_R

R2579     	Q_RES_0402LF   	          	          	                    
          	               	1         	296B4     	SVID_DIO1_CPU1_R    
          	               	2         	296B4     	SVID_DIO_PVCCD_HV_CPU1_R

R2580     	Q_RES_0402LF   	          	          	                    
          	               	1         	296B4     	SVID_ALERT1_CPU1_R_N
          	               	2         	296B4     	SVID_ALERT_PVCCD_HV_CPU1_R

R2582     	Q_RES_0402LF   	          	          	                    
          	               	1         	296B4     	SMB_VR_3V3AUX_SDA_R 
          	               	2         	296B4     	SMB_DIO_PVCCD_HV_CPU1

R2583     	Q_RES_0402LF   	          	          	                    
          	               	1         	299B3     	P3V3_AUX            
          	               	2         	299B3     	PWRGD_PVPP_HBM_CPU1_R

R2584     	Q_RES_0402LF   	          	          	                    
          	               	1         	300B2     	P3V3_AUX            
          	               	2         	300B2     	PWRGD_PVNN_MAIN_CPU1_R

R2585     	Q_RES_0402LF   	          	          	                    
          	               	1         	301A4     	HSC_EN              
          	               	2         	301A4     	GND                 

R2586     	Q_RES_0402LF   	          	          	                    
          	               	1         	301B4     	HSC_EN              
          	               	2         	301B4     	HSC_EN_R            

R2587     	Q_RES_0402LF   	          	          	                    
          	               	1         	301B1     	HSC_VDD             
          	               	2         	301B1     	IRQ_HSC_FAULT_N     

R2588     	Q_RES_0402LF   	          	          	                    
          	               	1         	301B2     	HSC_FAULT           
          	               	2         	301B1     	IRQ_HSC_FAULT_N     

R2589     	Q_RES_0402LF   	          	          	                    
          	               	1         	266A4     	P3V3_AUX            
          	               	2         	266A4     	PVCCIN_CPU0_VR_FAULT

R2590     	Q_RES_0402LF   	          	          	                    
          	               	1         	266A1     	SVID_DIO0_CPU0_R    
          	               	2         	266A1     	PVNN_TERM_CPU0      

R2591     	Q_RES_0402LF   	          	          	                    
          	               	1         	266B4     	FM_PVCCIN_CPU0_EN   
          	               	2         	266B4     	PVCCIN_CPU0_EN_R    

R2593     	Q_RES_0402LF   	          	          	                    
          	               	1         	296B4     	PVNN_TERM_CPU1      
          	               	2         	296B4     	SVID_DIO1_CPU1_R    

R2594     	Q_RES_0402LF   	          	          	                    
          	               	1         	274B4     	FM_PVCCINFAON_CPU0_EN
          	               	2         	274B4     	PVCCINFAON_CPU0_EN_R

R2595     	Q_RES_0402LF   	          	          	                    
          	               	1         	274B4     	PWRGD_PVCCINFAON_CPU0
          	               	2         	274B4     	PWRGD_PVCCINFAON_CPU0_R

R2596     	Q_RES_0402LF   	          	          	                    
          	               	1         	274B4     	SVID_CLK0_CPU0_R    
          	               	2         	274B4     	SVID_CLK_PVCCINFAON_CPU0_R

R2597     	Q_RES_0402LF   	          	          	                    
          	               	1         	274A2     	IRQ_PVCCFA_CPU0_VRHOT_N
          	               	2         	274A2     	IRQ_PVCCFA_CPU0_VRHOT_R_N

R2656     	Q_RES_0402LF   	          	          	                    
          	               	1         	144A1     	HGX_DETECT_N_ISO    
          	               	2         	144A1     	GND                 

R2659     	Q_RES_0402LF   	          	          	                    
          	               	1         	207B4     	CLK_100M_SWB_R_DP   
          	               	2         	207B4     	CLK_100M_SWB_DP     

R2660     	Q_RES_0402LF   	          	          	                    
          	               	1         	207B4     	CLK_100M_SWB_R_DN   
          	               	2         	207B4     	CLK_100M_SWB_DN     

R2661     	Q_RES_0402LF   	          	          	                    
          	               	1         	213A2     	FM_SWB_PWR_EN       
          	               	2         	213A2     	FM_SWB_PWR_EN_R     

R2662     	Q_RES_0402LF   	          	          	                    
          	               	1         	213A2     	FM_GPU_PWR_EN       
          	               	2         	213A2     	FM_GPU_PWR_EN_R     

R2663     	Q_RES_0402LF   	          	          	                    
          	               	1         	213A2     	FM_SWB_PWRGD_ISO    
          	               	2         	213A2     	FM_SWB_PWRGD_ISO_R  

R2664     	Q_RES_0402LF   	          	          	                    
          	               	1         	213A2     	FM_GPU_PWRGD_ISO    
          	               	2         	213A2     	FM_GPU_PWRGD_ISO_R  

R2666     	Q_RES_0402LF   	          	          	                    
          	               	1         	234A4     	SMB_BMC_SWB_EN      
          	               	2         	234A4     	GND                 

R2667     	Q_RES_0402LF   	          	          	                    
          	               	1         	234B3     	P3V3_AUX            
          	               	2         	234B3     	SMB_BMC_SWB_BUF_R_SCL

R2668     	Q_RES_0402LF   	          	          	                    
          	               	1         	234A2     	P3V3_AUX            
          	               	2         	234A2     	I3C_BMC_SWB_BUF_R_SDA

R2669     	Q_RES_0402LF   	          	          	                    
          	               	1         	234B3     	P3V3_AUX            
          	               	2         	234B3     	SMB_BMC_SWB_BUF_R_SDA

R2670     	Q_RES_0402LF   	          	          	                    
          	               	1         	234A2     	P3V3_AUX            
          	               	2         	234A2     	I3C_BMC_SWB_BUF_R_SCL

R2671     	Q_RES_0402LF   	          	          	                    
          	               	1         	234B3     	SMB_BMC_SWB_BUF_R_SCL
          	               	2         	234B3     	SMB_BMC_SWB_BUF_SCL 

R2672     	Q_RES_0402LF   	          	          	                    
          	               	1         	234B3     	SMB_BMC_SWB_BUF_R_SDA
          	               	2         	234B3     	SMB_BMC_SWB_BUF_SDA 

R2674     	Q_RES_0402LF   	          	          	                    
          	               	1         	234A2     	I3C_BMC_SWB_BUF_R_SDA
          	               	2         	234A1     	I3C_BMC_SWB_BUF_SDA 

R2675     	Q_RES_0402LF   	          	          	                    
          	               	1         	234A2     	I3C_BMC_SWB_BUF_R_SCL
          	               	2         	234A1     	I3C_BMC_SWB_BUF_SCL 

R2676     	Q_RES_0402LF   	          	          	                    
          	               	1         	234A3     	SMB_BMC_SWB_EN      
          	               	2         	234A3     	SMB_BMC_SWB_EN_R2   

R2693     	Q_RES_0402LF   	          	          	                    
          	               	1         	227B4     	P3V3_AUX            
          	               	2         	227B4     	TCA9539_0_ADD1      

R2694     	Q_RES_0402LF   	          	          	                    
          	               	1         	227A4     	TCA9539_0_ADD1      
          	               	2         	227A4     	GND                 

R2695     	Q_RES_0402LF   	          	          	                    
          	               	1         	227B4     	P3V3_AUX            
          	               	2         	227B4     	TCA9539_0_ADD0      

R2696     	Q_RES_0402LF   	          	          	                    
          	               	1         	227A4     	TCA9539_0_ADD0      
          	               	2         	227A4     	GND                 

R2703     	Q_RES_0402LF   	          	          	                    
          	               	1         	231B2     	SMB_BMC_SWB_SCL_R4  
          	               	2         	231B2     	SMB_BMC_SWB_SCL     

R2704     	Q_RES_0402LF   	          	          	                    
          	               	1         	231B2     	SMB_BMC_SWB_SDA_R4  
          	               	2         	231B2     	SMB_BMC_SWB_SDA     

R2705     	Q_RES_0402LF   	          	          	                    
          	               	1         	234B4     	SMB_BMC_SWB_R_SCL   
          	               	2         	234B4     	SMB_BMC_SWB_BUF_R_SCL

R2706     	Q_RES_0402LF   	          	          	                    
          	               	1         	234A3     	I3C_BMC_SWB_R_SDA   
          	               	2         	234A3     	I3C_BMC_SWB_BUF_R_SDA

R2707     	Q_RES_0402LF   	          	          	                    
          	               	1         	234B4     	SMB_BMC_SWB_EN      
          	               	2         	234B4     	SMB_BMC_SWB_EN_R    

R2724     	Q_RES_0402LF   	          	          	                    
          	               	1         	234B4     	SMB_BMC_SWB_R_SDA   
          	               	2         	234B4     	SMB_BMC_SWB_BUF_R_SDA

R2725     	Q_RES_0402LF   	          	          	                    
          	               	1         	234A3     	I3C_BMC_SWB_R_SCL   
          	               	2         	234A3     	I3C_BMC_SWB_BUF_R_SCL

R2726     	Q_RES_0402LF   	          	          	                    
          	               	1         	114B4     	PWRGD_CHA_CPU0_DIMM1
          	               	2         	114B4     	PWRGD_FAIL_CPU0_AB  

R2727     	Q_RES_0402LF   	          	          	                    
          	               	1         	114B4     	PWRGD_CHA_CPU0_DIMM2
          	               	2         	114B4     	PWRGD_FAIL_CPU0_AB  

R2728     	Q_RES_0402LF   	          	          	                    
          	               	1         	114B4     	PWRGD_CHB_CPU0_DIMM1
          	               	2         	114B4     	PWRGD_FAIL_CPU0_AB  

R2729     	Q_RES_0402LF   	          	          	                    
          	               	1         	114B4     	PWRGD_CHC_CPU0_DIMM1
          	               	2         	114B4     	PWRGD_FAIL_CPU0_CD  

R2730     	Q_RES_0402LF   	          	          	                    
          	               	1         	114B4     	PWRGD_CHC_CPU0_DIMM2
          	               	2         	114B4     	PWRGD_FAIL_CPU0_CD  

R2731     	Q_RES_0402LF   	          	          	                    
          	               	1         	114B4     	PWRGD_CHD_CPU0_DIMM1
          	               	2         	114B4     	PWRGD_FAIL_CPU0_CD  

R2732     	Q_RES_0402LF   	          	          	                    
          	               	1         	114B4     	PWRGD_CHF_CPU0_DIMM1
          	               	2         	114B4     	PWRGD_FAIL_CPU0_EF  

R2733     	Q_RES_0402LF   	          	          	                    
          	               	1         	114B4     	PWRGD_CHF_CPU0_DIMM2
          	               	2         	114B4     	PWRGD_FAIL_CPU0_EF  

R2734     	Q_RES_0402LF   	          	          	                    
          	               	1         	114B4     	PWRGD_CHH_CPU0_DIMM1
          	               	2         	114B4     	PWRGD_FAIL_CPU0_GH  

R2735     	Q_RES_0402LF   	          	          	                    
          	               	1         	114B4     	PWRGD_CHH_CPU0_DIMM2
          	               	2         	114B4     	PWRGD_FAIL_CPU0_GH  

R2736     	Q_RES_0402LF   	          	          	                    
          	               	1         	114B2     	PWRGD_CHF_CPU1_DIMM2
          	               	2         	114B2     	PWRGD_FAIL_CPU1_EF  

R2738     	Q_RES_0402LF   	          	          	                    
          	               	1         	223B2     	RST_PERST_SWB_N     
          	               	2         	223B2     	RST_PERST_SWB_R_N   

R2786     	Q_RES_0402LF   	          	          	                    
          	               	1         	152A4     	USB2_HUB_SWB_DP     
          	               	2         	152A4     	USB2_HUB_BUF_SWB_R_DP

R2787     	Q_RES_0402LF   	          	          	                    
          	               	1         	152A4     	USB2_HUB_SWB_DN     
          	               	2         	152A4     	USB2_HUB_BUF_SWB_R_DN

R2788     	Q_RES_0402LF   	          	          	                    
          	               	1         	152A4     	USB2_HOST_BMC_B_BUF_DP
          	               	2         	152A4     	USB2_HUB_BUF_SWB_R_DP

R2789     	Q_RES_0402LF   	          	          	                    
          	               	1         	152A4     	USB2_HOST_BMC_B_BUF_DN
          	               	2         	152A4     	USB2_HUB_BUF_SWB_R_DN

R2790     	Q_RES_0402LF   	          	          	                    
          	               	1         	152B2     	USB2_HOST_BMC_B_DP  
          	               	2         	152B2     	USB2_HOST_BMC_B_BUF_DP

R2791     	Q_RES_0402LF   	          	          	                    
          	               	1         	152B1     	USB2_HOST_BMC_B_DN  
          	               	2         	152B1     	USB2_HOST_BMC_B_BUF_DN

R2792     	Q_RES_0402LF   	          	          	                    
          	               	1         	215A2     	FM_PDB_BUF_EN       
          	               	2         	215A2     	FM_PDB_BUF_EN_R     

R2796     	Q_RES_0402LF   	          	          	                    
          	               	1         	245A3     	FM_PDB_BUF_EN_R     
          	               	2         	245A3     	FM_MB_PDB_SMB9_R_EN 

R2800     	Q_RES_0402LF   	          	          	                    
          	               	1         	245A3     	SMB_FAN_3V3AUX_R_SCL
          	               	2         	245A3     	SMB_FAN_3V3AUX_BUF_SCL

R2801     	Q_RES_0402LF   	          	          	                    
          	               	1         	245A3     	SMB_FAN_3V3AUX_R_SDA
          	               	2         	245A3     	SMB_FAN_3V3AUX_BUF_SDA

R2802     	Q_RES_0402LF   	          	          	                    
          	               	1         	245B2     	HPDB_HSC_PWRGD_R    
          	               	2         	245B2     	HPDB_HSC_PWRGD      

R2803     	Q_RES_0402LF   	          	          	                    
          	               	1         	245B2     	FM_FAN_PWR_EN_R     
          	               	2         	245B2     	FM_FAN_PWR_EN       

R2805     	Q_RES_0402LF   	          	          	                    
          	               	1         	245A2     	P3V3_AUX            
          	               	2         	245A2     	SMB_FAN_3V3AUX_BUF_SCL

R2807     	Q_RES_0402LF   	          	          	                    
          	               	1         	245A2     	P3V3_AUX            
          	               	2         	245A2     	SMB_FAN_3V3AUX_BUF_SDA

R2811     	Q_RES_0402LF   	          	          	                    
          	               	1         	245A2     	SMB_FAN_3V3AUX_BUF_SCL
          	               	2         	245A2     	SMB_FAN_3V3AUX_BUF_R_SCL

R2812     	Q_RES_0402LF   	          	          	                    
          	               	1         	245A2     	SMB_FAN_3V3AUX_BUF_SDA
          	               	2         	245A2     	SMB_FAN_3V3AUX_BUF_R_SDA

R2815     	Q_RES_0402LF   	          	          	                    
          	               	1         	151B4     	P3V3_AUX            
          	               	2         	151B4     	BMC_MONITER_R       

R2820     	Q_RES_0402LF   	          	          	                    
          	               	1         	151B2     	P3V3_AUX            
          	               	2         	151B2     	BMC_MONITER_BUF_R   

R2828     	Q_RES_0402LF   	          	          	                    
          	               	1         	148B4     	P3V3_AUX            
          	               	2         	148B4     	RST_BMC_FROM_SWB_N  

R2829     	Q_RES_0402LF   	          	          	                    
          	               	1         	148B4     	RST_BMC_FROM_SWB_N  
          	               	2         	148B4     	GND                 

R2830     	Q_RES_0402LF   	          	          	                    
          	               	1         	148B4     	P3V3_AUX            
          	               	2         	148B4     	BIC_MONITER         

R2831     	Q_RES_0402LF   	          	          	                    
          	               	1         	148B4     	BIC_MONITER         
          	               	2         	148B4     	GND                 

R2832     	Q_RES_0402LF   	          	          	                    
          	               	1         	148B4     	P3V3_AUX            
          	               	2         	148A4     	FM_SWB_BIC_READY_N  

R2833     	Q_RES_0402LF   	          	          	                    
          	               	1         	148A4     	FM_SWB_BIC_READY_N  
          	               	2         	148A4     	GND                 

R2834     	Q_RES_0402LF   	          	          	                    
          	               	1         	148B4     	P3V3_AUX            
          	               	2         	148B4     	RST_BMC_FROM_SWB    

R2835     	Q_RES_0402LF   	          	          	                    
          	               	1         	148B4     	P3V3_AUX            
          	               	2         	148B4     	BIC_MONITER_N       

R2836     	Q_RES_0402LF   	          	          	                    
          	               	1         	148B4     	P3V3_AUX            
          	               	2         	148B4     	FM_SWB_BIC_READY    

R2837     	Q_RES_0402LF   	          	          	                    
          	               	1         	148B2     	P3V3_AUX            
          	               	2         	148B2     	FM_SWB_PWRGD        

R2838     	Q_RES_0402LF   	          	          	                    
          	               	1         	148B2     	FM_SWB_PWRGD        
          	               	2         	148B2     	GND                 

R2841     	Q_RES_0402LF   	          	          	                    
          	               	1         	148B2     	P3V3_AUX            
          	               	2         	148B2     	FM_SWB_PWRGD_N      

R2842     	Q_RES_0402LF   	          	          	                    
          	               	1         	148B2     	P3V3_AUX            
          	               	2         	148B2     	FM_GPU_PWRGD_N      

R2843     	Q_RES_0402LF   	          	          	                    
          	               	1         	250B4     	P3V3_ADC            
          	               	2         	250B4     	GND                 

R2844     	Q_RES_0402LF   	          	          	                    
          	               	1         	213A2     	FM_SWB_BIC_READY_ISO_N
          	               	2         	213A2     	FM_SWB_BIC_READY_ISO_R_N

R2845     	Q_RES_0402LF   	          	          	                    
          	               	1         	213A2     	BMC_MONITER         
          	               	2         	213A2     	BMC_MONITER_R       

R2846     	Q_RES_0402LF   	          	          	                    
          	               	1         	213A2     	BIC_MONITER_ISO     
          	               	2         	213A2     	BIC_MONITER_ISO_R   

R2847     	Q_RES_0402LF   	          	          	                    
          	               	1         	213A2     	RST_BMC_FROM_SWB_ISO_N
          	               	2         	213A2     	RST_BMC_FROM_SWB_ISO_R_N

R2848     	Q_RES_0402LF   	          	          	                    
          	               	1         	227B3     	RST_SWB_BIC_N       
          	               	2         	227B3     	RST_SWB_BIC_R_N     

R2893     	Q_RES_0402LF   	          	          	                    
          	               	1         	234B3     	SMB_1_BMC_GPU_R_SCL 
          	               	2         	234B3     	SMB_1_BMC_GPU_BUF_R_SCL

R2894     	Q_RES_0402LF   	          	          	                    
          	               	1         	234B3     	SMB_1_BMC_GPU_R_SDA 
          	               	2         	234B3     	SMB_1_BMC_GPU_BUF_R_SDA

R2897     	Q_RES_0402LF   	          	          	                    
          	               	1         	234B2     	SMB_1_BMC_GPU_BUF_R_SCL
          	               	2         	234B2     	SMB_1_BMC_GPU_BUF_SCL

R2898     	Q_RES_0402LF   	          	          	                    
          	               	1         	234B2     	SMB_1_BMC_GPU_BUF_R_SDA
          	               	2         	234B2     	SMB_1_BMC_GPU_BUF_SDA

R2899     	Q_RES_0402LF   	          	          	                    
          	               	1         	234B4     	SMB_BMC_GPU_EN      
          	               	2         	234B3     	SMB_BMC_GPU_EN_R1   

R2900     	Q_RES_0402LF   	          	          	                    
          	               	1         	250B2     	MAX11617_VREF       
          	               	2         	250B2     	MAX11617_VREF_R     

R2905     	Q_RES_0402LF   	          	          	                    
          	               	1         	245B4     	RST_SMB_SWITCH_N    
          	               	2         	245B4     	RST_SMB_SWITCH_R_N  

R2906     	Q_RES_0402LF   	          	          	                    
          	               	1         	245B2     	FM_GPU_HSC_EN_BUF_R1
          	               	2         	245B2     	FM_GPU_HSC_EN_BUF   

R2907     	Q_RES_0402LF   	          	          	                    
          	               	1         	250B4     	P3V3_AUX            
          	               	2         	250B4     	P3V3_AUX_ADC        

R2908     	Q_RES_0402LF   	          	          	                    
          	               	1         	250B4     	P3V3                
          	               	2         	250B4     	P3V3_ADC            

R2909     	Q_RES_0402LF   	          	          	                    
          	               	1         	151B4     	P3V3_AUX            
          	               	2         	151B4     	RST_SWB_BIC_R_N     

R2910     	Q_RES_0402LF   	          	          	                    
          	               	1         	149A4     	P3V3_AUX            
          	               	2         	149A4     	FM_SWB_PWR_EN_R     

R2911     	Q_RES_0402LF   	          	          	                    
          	               	1         	151B2     	P3V3_AUX            
          	               	2         	151B2     	RST_SWB_BIC_BUF_R_N 

R2912     	Q_RES_0402LF   	          	          	                    
          	               	1         	151B2     	P3V3_AUX            
          	               	2         	151B2     	FM_GPU_PWR_EN_R1    

R2914     	Q_RES_0402LF   	          	          	                    
          	               	1         	149A2     	P3V3_AUX            
          	               	2         	149A2     	FM_SWB_PWR_EN_R1_BUF

R2915     	Q_RES_0402LF   	          	          	                    
          	               	1         	151B4     	BMC_MONITER_R       
          	               	2         	151B4     	GND                 

R2916     	Q_RES_0402LF   	          	          	                    
          	               	1         	151B4     	RST_SWB_BIC_R_N     
          	               	2         	151B4     	GND                 

R2917     	Q_RES_0402LF   	          	          	                    
          	               	1         	151B2     	BMC_MONITER_BUF_R   
          	               	2         	151B2     	BMC_MONITER_BUF     

R2918     	Q_RES_0402LF   	          	          	                    
          	               	1         	149A4     	FM_SWB_PWR_EN_R     
          	               	2         	149A4     	GND                 

R2919     	Q_RES_0402LF   	          	          	                    
          	               	1         	148B4     	P3V3_AUX            
          	               	2         	148B4     	RST_BMC_FROM_SWB_ISO_N

R2920     	Q_RES_0402LF   	          	          	                    
          	               	1         	148B4     	P3V3_AUX            
          	               	2         	148B4     	BIC_MONITER_ISO     

R2921     	Q_RES_0402LF   	          	          	                    
          	               	1         	227B4     	P3V3_AUX            
          	               	2         	227B4     	RST_SMB_SWITCH_N    

R2922     	Q_RES_0402LF   	          	          	                    
          	               	1         	227B4     	RST_SMB_SWITCH_N    
          	               	2         	227B4     	PU_RST_SMB_U181_N   

R2923     	Q_RES_0402LF   	          	          	                    
          	               	1         	227B4     	P3V3_AUX            
          	               	2         	227B4     	PU_U181_INT         

R2924     	Q_RES_0402LF   	          	          	                    
          	               	1         	151B2     	RST_SWB_BIC_BUF_R_N 
          	               	2         	151B2     	RST_SWB_BIC_BUF_N   

R2925     	Q_RES_0402LF   	          	          	                    
          	               	1         	151B2     	FM_GPU_PWR_EN_R1    
          	               	2         	151B2     	FM_GPU_PWR_EN_R_BUF 

R2926     	Q_RES_0402LF   	          	          	                    
          	               	1         	151B2     	BMC_MONITER_BUF_R   
          	               	2         	151B2     	GND                 

R2927     	Q_RES_0402LF   	          	          	                    
          	               	1         	151B2     	RST_SWB_BIC_BUF_R_N 
          	               	2         	151B2     	GND                 

R2932     	Q_RES_0402LF   	          	          	                    
          	               	1         	149A2     	FM_SWB_PWR_EN_R1_BUF
          	               	2         	149A2     	GND                 

R2933     	Q_RES_0402LF   	          	          	                    
          	               	1         	148B4     	P3V3_AUX            
          	               	2         	148B4     	FM_SWB_BIC_READY_ISO_N

R2934     	Q_RES_0402LF   	          	          	                    
          	               	1         	148B1     	P3V3_AUX            
          	               	2         	148B1     	FM_SWB_PWRGD_ISO    

R2935     	Q_RES_0402LF   	          	          	                    
          	               	1         	148B1     	P3V3_AUX            
          	               	2         	148B1     	FM_GPU_PWRGD_ISO    

R2936     	Q_RES_0402LF   	          	          	                    
          	               	1         	151B4     	P3V3_AUX            
          	               	2         	151B4     	FM_GPU_PWR_EN_R     

R2937     	Q_RES_0402LF   	          	          	                    
          	               	1         	151B4     	FM_GPU_PWR_EN_R     
          	               	2         	151B4     	GND                 

R2939     	Q_RES_0402LF   	          	          	                    
          	               	1         	213A2     	FM_GPU_HSC_EN_R     
          	               	2         	213A2     	FM_GPU_HSC_EN       

R2940     	Q_RES_0402LF   	          	          	                    
          	               	1         	246B4     	P3V3_AUX            
          	               	2         	246B4     	FM_GPU_HSC_EN       

R2941     	Q_RES_0402LF   	          	          	                    
          	               	1         	246B4     	FM_GPU_HSC_EN       
          	               	2         	246B4     	GND                 

R2944     	Q_RES_0402LF   	          	          	                    
          	               	1         	246B2     	FM_GPU_HSC_EN_BUF_R 
          	               	2         	246B2     	FM_GPU_HSC_EN_BUF   

R2946     	Q_RES_0402LF   	          	          	                    
          	               	1         	246B2     	P3V3_AUX            
          	               	2         	246B2     	FM_GPU_HSC_EN_BUF_R 

R2948     	Q_RES_0402LF   	          	          	                    
          	               	1         	246B2     	FM_GPU_HSC_EN_BUF_R 
          	               	2         	246B2     	GND                 

R2950     	Q_RES_0402LF   	          	          	                    
          	               	1         	245A4     	P3V3_AUX            
          	               	2         	245A4     	FM_PDB_BUF_EN_R     

R2966     	Q_RES_0402LF   	          	          	                    
          	               	1         	182B1     	P3V3_RTC_AUX        
          	               	2         	182B1     	FM_INTRUDER_HDR_PCH_N

R2967     	Q_RES_0402LF   	          	          	                    
          	               	1         	231B3     	SMB_PCIE0_3V3AUX_SCL_R3
          	               	2         	231B3     	SMB_SENSOR_M2_P0_3V3AUX_SCL

R2968     	Q_RES_0402LF   	          	          	                    
          	               	1         	231B3     	SMB_PCIE0_3V3AUX_SDA_R3
          	               	2         	231B3     	SMB_SENSOR_M2_P0_3V3AUX_SDA

R2969     	Q_RES_0402LF   	          	          	                    
          	               	1         	128A4     	RST_CPU1_DRAM_GH_N  
          	               	2         	128A4     	RST_CPU1_DRAM_GH_PLD_N

R2971     	Q_RES_0402LF   	          	          	                    
          	               	1         	183B2     	FM_BIOS_DEBUG_EN_N  
          	               	2         	183B2     	FM_BIOS_DEBUG_EN_R_N

R2972     	Q_RES_0402LF   	          	          	                    
          	               	1         	195B2     	P1V05_PCH_AUX       
          	               	2         	195B2     	FAB_REV_ID2         

R2973     	Q_RES_0402LF   	          	          	                    
          	               	1         	195B2     	FAB_REV_ID2         
          	               	2         	195B2     	GND                 

R2974     	Q_RES_0402LF   	          	          	                    
          	               	1         	195B2     	P1V05_PCH_AUX       
          	               	2         	195B2     	FAB_REV_ID1         

R2975     	Q_RES_0402LF   	          	          	                    
          	               	1         	195B2     	FAB_REV_ID1         
          	               	2         	195B2     	GND                 

R2976     	Q_RES_0402LF   	          	          	                    
          	               	1         	195B3     	P1V05_PCH_AUX       
          	               	2         	195B3     	FM_BOARD_SKU_ID3    

R2977     	Q_RES_0402LF   	          	          	                    
          	               	1         	195B3     	FM_BOARD_SKU_ID3    
          	               	2         	195B3     	GND                 

R2978     	Q_RES_0402LF   	          	          	                    
          	               	1         	195B1     	FAB_REV_ID0         
          	               	2         	195B1     	GND                 

R2979     	Q_RES_0402LF   	          	          	                    
          	               	1         	195B3     	P1V05_PCH_AUX       
          	               	2         	195B3     	FM_BOARD_SKU_ID2    

R2980     	Q_RES_0402LF   	          	          	                    
          	               	1         	195B3     	FM_BOARD_SKU_ID2    
          	               	2         	195B3     	GND                 

R2982     	Q_RES_0402LF   	          	          	                    
          	               	1         	227B3     	SMB_IOEXP_3V3AUX_SCL
          	               	2         	227B3     	SMB_IOEXP_3V3AUX_SCL_R1

R2983     	Q_RES_0402LF   	          	          	                    
          	               	1         	227B3     	SMB_IOEXP_3V3AUX_SDA
          	               	2         	227B3     	SMB_IOEXP_3V3AUX_SDA_R1

R2984     	Q_RES_0402LF   	          	          	                    
          	               	1         	231A2     	P3V3_AUX            
          	               	2         	231A2     	SMB_BMC_SWB_SCL     

R2985     	Q_RES_0402LF   	          	          	                    
          	               	1         	231A2     	P3V3_AUX            
          	               	2         	231A2     	SMB_BMC_SWB_SDA     

R2986     	Q_RES_0402LF   	          	          	                    
          	               	1         	234A4     	SMB_2_BMC_GPU_R_SCL 
          	               	2         	234A4     	SMB_2_BMC_GPU_BUF_R_SCL

R2987     	Q_RES_0402LF   	          	          	                    
          	               	1         	234A4     	SMB_2_BMC_GPU_R_SDA 
          	               	2         	234A4     	SMB_2_BMC_GPU_BUF_R_SDA

R2990     	Q_RES_0402LF   	          	          	                    
          	               	1         	234B3     	SMB_2_BMC_GPU_BUF_R_SCL
          	               	2         	234B3     	SMB_2_BMC_GPU_BUF_SCL

R2991     	Q_RES_0402LF   	          	          	                    
          	               	1         	234B3     	SMB_2_BMC_GPU_BUF_R_SDA
          	               	2         	234B3     	SMB_2_BMC_GPU_BUF_SDA

R2992     	Q_RES_0402LF   	          	          	                    
          	               	1         	234B4     	SMB_BMC_GPU_EN      
          	               	2         	234B4     	SMB_BMC_GPU_EN_R3   

R2994     	Q_RES_0402LF   	          	          	                    
          	               	1         	240B1     	P3V_BAT_R1          
          	               	2         	240B1     	P3V_BAT_R           

R2995     	Q_RES_0402LF   	          	          	                    
          	               	1         	241B4     	SMB_SML1_PMBUS_3V3AUX_PCH_SCL
          	               	2         	241B4     	SMB_SML1_PMBUS_HSC_SCL_R3

R2996     	Q_RES_0402LF   	          	          	                    
          	               	1         	241B4     	SMB_SML1_PMBUS_3V3AUX_PCH_SDA
          	               	2         	241B4     	SMB_SML1_PMBUS_HSC_SDA_R3

R2999     	Q_RES_0402LF   	          	          	                    
          	               	1         	241B1     	SMB_2_BMC_GPU_SCL   
          	               	2         	241B1     	P3V3_AUX            

R3004     	Q_RES_0402LF   	          	          	                    
          	               	1         	241B1     	SMB_2_BMC_GPU_SDA   
          	               	2         	241B1     	P3V3_AUX            

R3005     	Q_RES_0402LF   	          	          	                    
          	               	1         	250B4     	P5V                 
          	               	2         	250B4     	P5V_ADC             

R3023     	Q_RES_0402LF   	          	          	                    
          	               	1         	117B3     	H_CPU_PM_FAST_WAKE_N
          	               	2         	117B3     	H_CPU1_PM_FAST_WAKE_N

R3024     	Q_RES_0402LF   	          	          	                    
          	               	1         	119A4     	GND                 
          	               	2         	119A4     	PD_EXT_CLK_SEL_CPU1 

R3025     	Q_RES_0402LF   	          	          	                    
          	               	1         	134B4     	FM_REMOTE_DEBUG_DET_R
          	               	2         	134B4     	GND                 

R3026     	Q_RES_0402LF   	          	          	                    
          	               	1         	134B4     	JTAG_BMC_PCH_TCK    
          	               	2         	134B4     	GND                 

R3027     	Q_RES_0402LF   	          	          	                    
          	               	1         	134B4     	JTAG_BMC_CPU_TCK    
          	               	2         	134B4     	GND                 

R3028     	Q_RES_0402LF   	          	          	                    
          	               	1         	148A4     	FM_SMB_1_ALERT_GPU_N
          	               	2         	148A4     	GND                 

R3029     	Q_RES_0402LF   	          	          	                    
          	               	1         	148A4     	P3V3_AUX            
          	               	2         	148A4     	FM_SMB_1_ALERT_GPU  

R3030     	Q_RES_0402LF   	          	          	                    
          	               	1         	148A4     	P3V3_AUX            
          	               	2         	148A4     	FM_SMB_1_ALERT_GPU_ISO_N

R3032     	Q_RES_0402LF   	          	          	                    
          	               	1         	148A2     	FM_SMB_2_ALERT_GPU_N
          	               	2         	148A2     	GND                 

R3033     	Q_RES_0402LF   	          	          	                    
          	               	1         	151A4     	UART_BMC_BIC_RX     
          	               	2         	151A4     	UART_BMC_BIC_R_RX   

R3034     	Q_RES_0402LF   	          	          	                    
          	               	1         	148B2     	P3V3_AUX            
          	               	2         	148B2     	FM_SMB_2_ALERT_GPU  

R3035     	Q_RES_0402LF   	          	          	                    
          	               	1         	148B1     	P3V3_AUX            
          	               	2         	148B1     	FM_SMB_2_ALERT_GPU_ISO_N

R3036     	Q_RES_0402LF   	          	          	                    
          	               	1         	151A3     	UART_BMC_BIC_R_BUF_RX
          	               	2         	151A3     	UART_BMC_BIC_BUF_RX 

R3037     	Q_RES_0402LF   	          	          	                    
          	               	1         	158B4     	P3V3_AUX            
          	               	2         	158B4     	PD_SMB_OCP1_HP_ADD1 

R3038     	Q_RES_0402LF   	          	          	                    
          	               	1         	200B4     	P3V3_AUX            
          	               	2         	200B4     	FM_PCH_SPARE0       

R3039     	Q_RES_0402LF   	          	          	                    
          	               	1         	201B3     	GND                 
          	               	2         	201B3     	PD_ME_RCVR_N        

R3040     	Q_RES_0402LF   	          	          	                    
          	               	1         	204B2     	P3V3_AUX            
          	               	2         	204B2     	IRQ_PCH_SCI_WHEA_N  

R3041     	Q_RES_0402LF   	          	          	                    
          	               	1         	204B2     	P3V3_AUX            
          	               	2         	204B2     	FM_PCH_GLB_RST_WARN_N

R3042     	Q_RES_0402LF   	          	          	                    
          	               	1         	204B2     	P1V05_PCH_AUX       
          	               	2         	204B2     	H_CPU_ERR1_PCH_R_N  

R3043     	Q_RES_0402LF   	          	          	                    
          	               	1         	213A2     	IRQ_HSC_FAULT_N     
          	               	2         	213A2     	IRQ_HSC_FAULT_R1_N  

R3045     	Q_RES_0402LF   	          	          	                    
          	               	1         	215A2     	IRQ_UV_DETECT_N     
          	               	2         	215A2     	IRQ_UV_DETECT_R_N   

R3046     	Q_RES_0402LF   	          	          	                    
          	               	1         	215A2     	FM_UV_ADR_TRIGGER_N 
          	               	2         	215A2     	FM_UV_ADR_TRIGGER_R_N

R3047     	Q_RES_0402LF   	          	          	                    
          	               	1         	214A2     	MB0_P12V_STBY_PWRGD 
          	               	2         	214A2     	PWRGD_PS_PWROK_PLD  

R3048     	Q_RES_0402LF   	          	          	                    
          	               	1         	214A2     	MB0_P12V_STBY_PWRGD 
          	               	2         	214A2     	PWRGD_PS_PWROK      

R3049     	Q_RES_0402LF   	          	          	                    
          	               	1         	215A2     	IRQ_SML1_PMBUS_ALERT_N
          	               	2         	215A2     	IRQ_PSU_ALERT_R_N   

R3050     	Q_RES_0402LF   	          	          	                    
          	               	1         	223B4     	RST_RSMRST_PLD_R_N  
          	               	2         	223B4     	RST_RSMRST_NM_HDR_N 

R3051     	Q_RES_0402LF   	          	          	                    
          	               	1         	228B3     	IRQ_SML1_PMBUS_ALERT_R_N
          	               	2         	228B3     	IRQ_SML1_PMBUS_ALERT_N

R3052     	Q_RES_0402LF   	          	          	                    
          	               	1         	228B3     	SMB_HOST_3V3AUX_SCL_R5
          	               	2         	228B3     	SMB_HOST_ME_SCL     

R3053     	Q_RES_0402LF   	          	          	                    
          	               	1         	228A3     	SMB_HOST_3V3AUX_SDA_R5
          	               	2         	228A3     	SMB_HOST_ME_SDA     

R3054     	Q_RES_0402LF   	          	          	                    
          	               	1         	228B2     	PWRGD_PS_PWROK_ME_CONN
          	               	2         	228B2     	PWRGD_PS_PWROK      

R3055     	Q_RES_0402LF   	          	          	                    
          	               	1         	239B2     	P3V3_AUX            
          	               	2         	239B2     	PU_GTL2014_BMC_JTAG_DIR_1

R3056     	Q_RES_0402LF   	          	          	                    
          	               	1         	239B2     	JTAG_DBP_BMC_PRDY_R1_N
          	               	2         	239B2     	JTAG_DBP_BMC_PRDY_N 

R3057     	Q_RES_0402LF   	          	          	                    
          	               	1         	239B2     	JTAG_DBP_BMC_PREQ_R1_N
          	               	2         	239B2     	JTAG_BMC_DBP_PREQ_N 

R3058     	Q_RES_0402LF   	          	          	                    
          	               	1         	241B4     	SMB_SML0_3V3AUX_SCL 
          	               	2         	241B4     	SMB_SML0_ME_SCL     

R3059     	Q_RES_0402LF   	          	          	                    
          	               	1         	241B4     	SMB_SML0_3V3AUX_SDA 
          	               	2         	241B4     	SMB_SML0_ME_SDA     

R3060     	Q_RES_0402LF   	          	          	                    
          	               	1         	241B4     	SMB_SML1_PMBUS_3V3AUX_PCH_SCL
          	               	2         	241B4     	SMB_PMBUS_SML1_ME_SCL

R3061     	Q_RES_0402LF   	          	          	                    
          	               	1         	241B4     	SMB_SML1_PMBUS_3V3AUX_PCH_SDA
          	               	2         	241B4     	SMB_PMBUS_SML1_ME_SDA

R3062     	Q_RES_0402LF   	          	          	                    
          	               	1         	241B1     	SMB_HOST_3V3AUX_SDA 
          	               	2         	241B1     	P3V3_AUX            

R3063     	Q_RES_0402LF   	          	          	                    
          	               	1         	151A4     	FM_PDB_BUF_EN_R     
          	               	2         	151A4     	FM_UART_EN          

R3064     	Q_RES_0402LF   	          	          	                    
          	               	1         	197A2     	PECI_CPU_GTL        
          	               	2         	197A2     	PECI_BMC_ME         

R3065     	Q_RES_0402LF   	          	          	                    
          	               	1         	205B4     	FM_BIOS_POST_CMPLT_N
          	               	2         	205B4     	FM_BIOS_POST_CMPLT_HDR_N

R3066     	Q_RES_0402LF   	          	          	                    
          	               	1         	214B4     	FM_SMB_1_ALERT_GPU_ISO_N
          	               	2         	214B3     	FM_SMB_1_ALERT_GPU_ISO_R_N

R3067     	Q_RES_0402LF   	          	          	                    
          	               	1         	214B4     	FM_SMB_2_ALERT_GPU_ISO_N
          	               	2         	214B3     	FM_SMB_2_ALERT_GPU_ISO_R_N

R3068     	Q_RES_0402LF   	          	          	                    
          	               	1         	255B3     	LED_PWRGD_PCH_PWROK_R
          	               	2         	255B3     	P3V3_AUX            

R3069     	Q_RES_0402LF   	          	          	                    
          	               	1         	255B3     	LED_PWRGD_SYS_PWROK_R
          	               	2         	255B3     	P3V3_AUX            

R3070     	Q_RES_0402LF   	          	          	                    
          	               	1         	255A3     	LED_RST_PLTRST_N    
          	               	2         	255A3     	P3V3_AUX            

R3071     	Q_RES_0402LF   	          	          	                    
          	               	1         	252B3     	LED_PWRGD_P1V8_PCH_AUX
          	               	2         	252B3     	P3V3_AUX            

R3072     	Q_RES_0402LF   	          	          	                    
          	               	1         	252B3     	LED_PWRGD_P1V05_PCH_AUX
          	               	2         	252B3     	P3V3_AUX            

R3073     	Q_RES_0402LF   	          	          	                    
          	               	1         	252A3     	LED_FM_PCH_SLP_S4_N 
          	               	2         	252A3     	P3V3_AUX            

R3074     	Q_RES_0402LF   	          	          	                    
          	               	1         	252B3     	LED_RST_RSMRST_PLD_R_N
          	               	2         	252B3     	P3V3_AUX            

R3075     	Q_RES_0402LF   	          	          	                    
          	               	1         	252B1     	LED_PWRGD_PS_PWROK_PLD
          	               	2         	252B1     	P3V3_AUX            

R3078     	Q_RES_0402LF   	          	          	                    
          	               	1         	252B1     	LED_FM_PCH_SLP_S3_N 
          	               	2         	252B1     	P3V3_AUX            

R3079     	Q_RES_0402LF   	          	          	                    
          	               	1         	256B3     	LED_RST_PLD_CPU0_DRAM_EF_N
          	               	2         	256B3     	P3V3_AUX            

R3080     	Q_RES_0402LF   	          	          	                    
          	               	1         	256B3     	LED_RST_PLD_CPU0_DRAM_CD_N
          	               	2         	256B3     	P3V3_AUX            

R3081     	Q_RES_0402LF   	          	          	                    
          	               	1         	256A3     	LED_RST_PLD_CPU0_DRAM_GH_N
          	               	2         	256A3     	P3V3_AUX            

R3082     	Q_RES_0402LF   	          	          	                    
          	               	1         	256B1     	LED_RST_PLD_CPU1_DRAM_AB_N
          	               	2         	256B1     	P3V3_AUX            

R3083     	Q_RES_0402LF   	          	          	                    
          	               	1         	256B1     	LED_RST_PLD_CPU1_DRAM_EF_N
          	               	2         	256B1     	P3V3_AUX            

R3084     	Q_RES_0402LF   	          	          	                    
          	               	1         	256B1     	LED_RST_PLD_CPU1_DRAM_CD_N
          	               	2         	256B1     	P3V3_AUX            

R3085     	Q_RES_0402LF   	          	          	                    
          	               	1         	256A1     	LED_RST_PLD_CPU1_DRAM_GH_N
          	               	2         	256A1     	P3V3_AUX            

R3086     	Q_RES_0402LF   	          	          	                    
          	               	1         	253B3     	LED_PWRGD_PVCCD_HV_CPU0
          	               	2         	253B3     	P3V3_AUX            

R3087     	Q_RES_0402LF   	          	          	                    
          	               	1         	253B3     	LED_PWRGD_PVPP_HBM_CPU0
          	               	2         	253B3     	P3V3_AUX            

R3088     	Q_RES_0402LF   	          	          	                    
          	               	1         	253A3     	LED_PWRGD_PVCCFA_EHV_FIVRA_CPU0
          	               	2         	253A3     	P3V3_AUX            

R3089     	Q_RES_0402LF   	          	          	                    
          	               	1         	253B3     	LED_PWRGD_PVCCFA_EHV_CPU0
          	               	2         	253B3     	P3V3_AUX            

R3090     	Q_RES_0402LF   	          	          	                    
          	               	1         	253B1     	LED_PWRGD_PVNN_MAIN_CPU0
          	               	2         	253B1     	P3V3_AUX            

R3091     	Q_RES_0402LF   	          	          	                    
          	               	1         	253B1     	LED_PWRGD_PVCCIN_CPU0
          	               	2         	253B1     	P3V3_AUX            

R3092     	Q_RES_0402LF   	          	          	                    
          	               	1         	253B1     	LED_PWRGD_PVCCINFAON_CPU0
          	               	2         	253B1     	P3V3_AUX            

R3093     	Q_RES_0402LF   	          	          	                    
          	               	1         	254B3     	LED_PWRGD_PVCCD_HV_CPU1
          	               	2         	254B3     	P3V3_AUX            

R3094     	Q_RES_0402LF   	          	          	                    
          	               	1         	254B3     	LED_PWRGD_PVPP_HBM_CPU1
          	               	2         	254B3     	P3V3_AUX            

R3095     	Q_RES_0402LF   	          	          	                    
          	               	1         	254A3     	LED_PWRGD_PVCCFA_EHV_FIVRA_CPU1
          	               	2         	254A3     	P3V3_AUX            

R3096     	Q_RES_0402LF   	          	          	                    
          	               	1         	254B3     	LED_PWRGD_PVCCFA_EHV_CPU1
          	               	2         	254B3     	P3V3_AUX            

R3097     	Q_RES_0402LF   	          	          	                    
          	               	1         	254B1     	LED_PWRGD_PVNN_MAIN_CPU1
          	               	2         	254B1     	P3V3_AUX            

R3098     	Q_RES_0402LF   	          	          	                    
          	               	1         	254B1     	LED_PWRGD_PVCCIN_CPU1
          	               	2         	254B1     	P3V3_AUX            

R3099     	Q_RES_0402LF   	          	          	                    
          	               	1         	254B1     	LED_PWRGD_PVCCINFAON_CPU1
          	               	2         	254B1     	P3V3_AUX            

R3100     	Q_RES_0402LF   	          	          	                    
          	               	1         	252A2     	LED_P3V3            
          	               	2         	252A2     	P3V3                

R3101     	Q_RES_0402LF   	          	          	                    
          	               	1         	252B2     	LED_P5V_AUX         
          	               	2         	252B2     	P5V_AUX             

R3102     	Q_RES_0402LF   	          	          	                    
          	               	1         	252A2     	LED_P5V             
          	               	2         	252A2     	P5V                 

R3103     	Q_RES_0402LF   	          	          	                    
          	               	1         	228B3     	IRQ_SML0_ALERT_R_N  
          	               	2         	228B3     	IRQ_SML0_ALERT_R1_N 

R3105     	Q_RES_0402LF   	          	          	                    
          	               	1         	234B4     	SMB_BMC_SWB_SCL     
          	               	2         	234B4     	SMB_BMC_SWB_R_SCL   

R3106     	Q_RES_0402LF   	          	          	                    
          	               	1         	234B4     	SMB_BMC_SWB_SDA     
          	               	2         	234B4     	SMB_BMC_SWB_R_SDA   

R3107     	Q_RES_0402LF   	          	          	                    
          	               	1         	234B4     	SMB_2_BMC_GPU_SCL   
          	               	2         	234B4     	SMB_2_BMC_GPU_R_SCL 

R3108     	Q_RES_0402LF   	          	          	                    
          	               	1         	234B4     	SMB_2_BMC_GPU_SDA   
          	               	2         	234B4     	SMB_2_BMC_GPU_R_SDA 

R3109     	Q_RES_0402LF   	          	          	                    
          	               	1         	234B4     	SMB_1_BMC_GPU_SCL   
          	               	2         	234B3     	SMB_1_BMC_GPU_R_SCL 

R3110     	Q_RES_0402LF   	          	          	                    
          	               	1         	234B4     	SMB_1_BMC_GPU_SDA   
          	               	2         	234B3     	SMB_1_BMC_GPU_R_SDA 

R3111     	Q_RES_0402LF   	          	          	                    
          	               	1         	234A3     	I3C_BMC_SWB_SDA     
          	               	2         	234A3     	I3C_BMC_SWB_R_SDA   

R3112     	Q_RES_0402LF   	          	          	                    
          	               	1         	234A3     	I3C_BMC_SWB_SCL     
          	               	2         	234A3     	I3C_BMC_SWB_R_SCL   

R3113     	Q_RES_0402LF   	          	          	                    
          	               	1         	245A3     	SMB_FAN_3V3AUX_SCL  
          	               	2         	245A3     	SMB_FAN_3V3AUX_R_SCL

R3114     	Q_RES_0402LF   	          	          	                    
          	               	1         	245A3     	SMB_FAN_3V3AUX_SDA  
          	               	2         	245A3     	SMB_FAN_3V3AUX_R_SDA

R3117     	Q_RES_0402LF   	          	          	                    
          	               	1         	259B4     	P12V_AUX            
          	               	2         	259A4     	P3V3_AUX_EN         

R3118     	Q_RES_0402LF   	          	          	                    
          	               	1         	259A4     	P3V3_AUX_EN         
          	               	2         	259A4     	GND                 

R3123     	Q_RES_0402LF   	          	          	                    
          	               	1         	236B2     	SMB_S3M_CPU0_PIROM_3V3AUX_SCL_R
          	               	2         	236B2     	SMB_S3M_CPU0_PIROM_3V3AUX_SCL

R3124     	Q_RES_0402LF   	          	          	                    
          	               	1         	236B2     	SMB_S3M_CPU0_PIROM_3V3AUX_SDA_R
          	               	2         	236B2     	SMB_S3M_CPU0_PIROM_3V3AUX_SDA

R3125     	Q_RES_0402LF   	          	          	                    
          	               	1         	236B2     	SMB_S3M_CPU1_PIROM_3V3AUX_SCL_R
          	               	2         	236B2     	SMB_S3M_CPU1_PIROM_3V3AUX_SCL

R3126     	Q_RES_0402LF   	          	          	                    
          	               	1         	236B2     	SMB_S3M_CPU1_PIROM_3V3AUX_SDA_R
          	               	2         	236B2     	SMB_S3M_CPU1_PIROM_3V3AUX_SDA

R3127     	Q_RES_0402LF   	          	          	                    
          	               	1         	236B1     	P3V3_AUX            
          	               	2         	236B1     	PCA9543_S3M_INT1_N  

R3130     	Q_RES_0402LF   	          	          	                    
          	               	1         	236B1     	P3V3_AUX            
          	               	2         	236B1     	PCA9543_S3M_INT2_N  

R3131     	Q_RES_0402LF   	          	          	                    
          	               	1         	236B1     	P3V3_AUX            
          	               	2         	236B1     	PCA9543_S3M_INT3_N  

R3132     	Q_RES_0402LF   	          	          	                    
          	               	1         	153B4     	GND                 
          	               	2         	153B4     	FM_OCP_SFF_PWR_GOOD 

R3133     	Q_RES_0402LF   	          	          	                    
          	               	1         	162A4     	P3V3_AUX            
          	               	2         	162A4     	OCP_V3_2_PRSNT0_R_N 

R3134     	Q_RES_0402LF   	          	          	                    
          	               	1         	162A4     	P3V3_AUX            
          	               	2         	162A4     	OCP_V3_2_PRSNT2_R_N 

R3135     	Q_RES_0402LF   	          	          	                    
          	               	1         	162A4     	P3V3_AUX            
          	               	2         	162A4     	OCP_V3_2_PRSNT1_R_N 

R3136     	Q_RES_0402LF   	          	          	                    
          	               	1         	162A4     	P3V3_AUX            
          	               	2         	162A4     	OCP_V3_2_PRSNT3_R_N 

R3142     	Q_RES_0402LF   	          	          	                    
          	               	1         	162A3     	HP_LVC3_OCP_V3_2_PRSNT2_N_R
          	               	2         	162A3     	HP_LVC3_OCP_V3_2_PRSNT2_N

R3143     	Q_RES_0402LF   	          	          	                    
          	               	1         	162A3     	HP_LVC3_OCP_V3_2_PRSNT2_N_R
          	               	2         	162A3     	HP_LVC3_OCP_V3_2_ATTN_OUT_SW_N

R3144     	Q_RES_0402LF   	          	          	                    
          	               	1         	156B1     	P12V_OCP_PWRGD_1    
          	               	2         	156B1     	HP_LVC3_OCP_V3_1_P12V_PWRGD

R3145     	Q_RES_0402LF   	          	          	                    
          	               	1         	162A2     	P3V3_AUX            
          	               	2         	162A2     	HP_LVC3_OCP_V3_2_ATTN_OUT_SW_N

R3147     	Q_RES_0402LF   	          	          	                    
          	               	1         	162A2     	P3V3_AUX            
          	               	2         	162A2     	HP_LVC3_OCP_V3_2_PRSNT2_N

R3149     	Q_RES_0402LF   	          	          	                    
          	               	1         	164B4     	P3V3_AUX            
          	               	2         	164B4     	PD_SMB_OCP2_HP_ADD2 

R3150     	Q_RES_0402LF   	          	          	                    
          	               	1         	164B4     	PD_SMB_OCP2_HP_ADD2 
          	               	2         	164B4     	GND                 

R3151     	Q_RES_0402LF   	          	          	                    
          	               	1         	164B4     	P3V3_AUX            
          	               	2         	164B4     	PD_SMB_OCP2_HP_ADD1 

R3152     	Q_RES_0402LF   	          	          	                    
          	               	1         	164B4     	PD_SMB_OCP2_HP_ADD1 
          	               	2         	164B4     	GND                 

R3153     	Q_RES_0402LF   	          	          	                    
          	               	1         	164B4     	P3V3_AUX            
          	               	2         	164B4     	PD_SMB_OCP2_HP_ADD0 

R3154     	Q_RES_0402LF   	          	          	                    
          	               	1         	164B4     	PD_SMB_OCP2_HP_ADD0 
          	               	2         	164B4     	GND                 

R3155     	Q_RES_0402LF   	          	          	                    
          	               	1         	164A4     	P3V3_AUX            
          	               	2         	164A4     	HP_LVC3_OCP_V3_2_PRSNT2

R3156     	Q_RES_0402LF   	          	          	                    
          	               	1         	164B4     	SMB_PEHPCPU1_LVC3_SCL
          	               	2         	164B4     	SMB_PEHPCPU1_LVC3_R3_SCL

R3157     	Q_RES_0402LF   	          	          	                    
          	               	1         	164B4     	SMB_PEHPCPU1_LVC3_SDA
          	               	2         	164B4     	SMB_PEHPCPU1_LVC3_R3_SDA

R3158     	Q_RES_0402LF   	          	          	                    
          	               	1         	164B4     	FM_SMB_CPU1_ALERT   
          	               	2         	164B4     	FM_SMB_PEHPCPU1_PCIE_ALERT_N

R3160     	Q_RES_0402LF   	          	          	                    
          	               	1         	158B3     	P3V3_AUX            
          	               	2         	158B3     	HP_OCP_V3_1_RST_R   

R3162     	Q_RES_0402LF   	          	          	                    
          	               	1         	159A4     	P3V3_OCP_V3_2       
          	               	2         	159A4     	OCP_V3_2_ID0        

R3163     	Q_RES_0402LF   	          	          	                    
          	               	1         	159A4     	OCP_V3_2_ID0        
          	               	2         	159A4     	GND                 

R3164     	Q_RES_0402LF   	          	          	                    
          	               	1         	159B4     	GND                 
          	               	2         	159B4     	OCP_V3_2_AUX_PWR_EN 

R3165     	Q_RES_0402LF   	          	          	                    
          	               	1         	159B4     	GND                 
          	               	2         	159B4     	OCP_V3_2_MAIN_PWR_EN

R3166     	Q_RES_0402LF   	          	          	                    
          	               	1         	159A4     	P3V3_OCP_V3_2       
          	               	2         	159A4     	OCP_V3_2_ID1        

R3167     	Q_RES_0402LF   	          	          	                    
          	               	1         	159A4     	OCP_V3_2_ID1        
          	               	2         	159A4     	GND                 

R3168     	Q_RES_0402LF   	          	          	                    
          	               	1         	159B4     	OCP_V3_2_MAIN_PWR_EN
          	               	2         	159B4     	OCP_V3_2_MAIN_PWR_EN_R

R3169     	Q_RES_0402LF   	          	          	                    
          	               	1         	159B4     	OCP_V3_2_ISO_BIF0_EN
          	               	2         	159B4     	OCP_V3_2_BIF0_R_N   

R3170     	Q_RES_0402LF   	          	          	                    
          	               	1         	159B4     	OCP_V3_2_ISO_BIF1_EN
          	               	2         	159B4     	OCP_V3_2_BIF1_R_N   

R3171     	Q_RES_0402LF   	          	          	                    
          	               	1         	159B4     	OCP_V3_2_ISO_BIF2_EN
          	               	2         	159B4     	OCP_V3_2_BIF2_R_N   

R3172     	Q_RES_0402LF   	          	          	                    
          	               	1         	159B4     	OCP_V3_2_AUX_PWR_EN 
          	               	2         	159B4     	OCP_V3_2_AUX_PWR_EN_R

R3173     	Q_RES_0402LF   	          	          	                    
          	               	1         	159A3     	SGPIO_OCP_V3_2_LD_N 
          	               	2         	159A3     	P3V3_OCP_V3_2       

R3174     	Q_RES_0402LF   	          	          	                    
          	               	1         	159A3     	SGPIO_OCP_V3_2_DATAIN
          	               	2         	159A3     	P3V3_OCP_V3_2       

R3175     	Q_RES_0402LF   	          	          	                    
          	               	1         	159A3     	SGPIO_OCP_V3_2_DATAOUT
          	               	2         	159A3     	GND                 

R3176     	Q_RES_0402LF   	          	          	                    
          	               	1         	159A3     	SGPIO_OCP_V3_2_CLK  
          	               	2         	159A3     	P3V3_OCP_V3_2       

R3177     	Q_RES_0402LF   	          	          	                    
          	               	1         	159A2     	USB2_5_R1_DN        
          	               	2         	159A2     	USB2_5_DN           

R3178     	Q_RES_0402LF   	          	          	                    
          	               	1         	159A2     	USB2_5_R1_DP        
          	               	2         	159A2     	USB2_5_DP           

R3180     	Q_RES_0402LF   	          	          	                    
          	               	1         	159B1     	OCP_V3_1_PRSNTA_R_N 
          	               	2         	159B1     	GND                 

R3181     	Q_RES_0402LF   	          	          	                    
          	               	1         	155A3     	CLK_50M_NCSI_OCP_2  
          	               	2         	155A3     	CLK_50M_NCSI_OCP_V3_2

R3182     	Q_RES_0402LF   	          	          	                    
          	               	1         	161B4     	P3V3_OCP_V3_2       
          	               	2         	161B4     	IRQ_LVC3_OCP_V3_2_WAKE_N

R3183     	Q_RES_0402LF   	          	          	                    
          	               	1         	161B4     	P3V3_OCP_V3_2       
          	               	2         	161B4     	PU_OCP_V3_2_WAKE_OE 

R3184     	Q_RES_0402LF   	          	          	                    
          	               	1         	161B3     	P3V3_AUX            
          	               	2         	161B3     	OCP_V3_2_WAKE_BUFF_N

R3185     	Q_RES_0402LF   	          	          	                    
          	               	1         	161B3     	OCP_V3_2_WAKE_BUFF_N
          	               	2         	161B3     	OCP_V3_2_WAKE_BUFF_R_N

R3186     	Q_RES_0402LF   	          	          	                    
          	               	1         	161B3     	RST_OCP_V3_2_BUF_N  
          	               	2         	161B3     	RST_PERST0_OCP_V3_2_N

R3187     	Q_RES_0402LF   	          	          	                    
          	               	1         	161B3     	RST_OCP_V3_2_BUF_N  
          	               	2         	161B3     	RST_PERST1_OCP_V3_2_N

R3188     	Q_RES_0402LF   	          	          	                    
          	               	1         	161B3     	RST_OCP_V3_2_BUF_N  
          	               	2         	161B3     	RST_PERST2_OCP_V3_2_N

R3189     	Q_RES_0402LF   	          	          	                    
          	               	1         	161B3     	RST_OCP_V3_2_BUF_N  
          	               	2         	161B3     	RST_PERST3_OCP_V3_2_N

R3190     	Q_RES_0402LF   	          	          	                    
          	               	1         	161B3     	P3V3_AUX            
          	               	2         	161B3     	OCP_V3_2_PWRBRK_BUFF_N

R3191     	Q_RES_0402LF   	          	          	                    
          	               	1         	161B3     	OCP_V3_2_PWRBRK_BUFF_N
          	               	2         	161B2     	OCP_V3_2_PWRBRK_N   

R3192     	Q_RES_0402LF   	          	          	                    
          	               	1         	161B2     	P3V3_AUX            
          	               	2         	161B2     	IRQ_LVC3_V3_2_WAKE_BUF_N

R3193     	Q_RES_0402LF   	          	          	                    
          	               	1         	161B2     	IRQ_LVC3_V3_2_WAKE_BUF_N
          	               	2         	161B2     	IRQ_LVC3_WAKE_N     

R3194     	Q_RES_0402LF   	          	          	                    
          	               	1         	207A4     	CLK_100M_OCP_V3_2_A_R_DP
          	               	2         	207A4     	CLK_100M_OCP_V3_2_A_DP

R3195     	Q_RES_0402LF   	          	          	                    
          	               	1         	207A4     	CLK_100M_OCP_V3_2_A_R_DN
          	               	2         	207A4     	CLK_100M_OCP_V3_2_A_DN

R3196     	Q_RES_0402LF   	          	          	                    
          	               	1         	207A4     	CLK_100M_OCP_V3_2_B_R_DP
          	               	2         	207A4     	CLK_100M_OCP_V3_2_B_DP

R3197     	Q_RES_0402LF   	          	          	                    
          	               	1         	207A4     	CLK_100M_OCP_V3_2_B_R_DN
          	               	2         	207A4     	CLK_100M_OCP_V3_2_B_DN

R3198     	Q_RES_0402LF   	          	          	                    
          	               	1         	207A4     	CLK_100M_OCP_V3_2_C_R_DP
          	               	2         	207A4     	CLK_100M_OCP_V3_2_C_DP

R3199     	Q_RES_0402LF   	          	          	                    
          	               	1         	207A4     	CLK_100M_OCP_V3_2_C_R_DN
          	               	2         	207A4     	CLK_100M_OCP_V3_2_C_DN

R3200     	Q_RES_0402LF   	          	          	                    
          	               	1         	207A4     	CLK_100M_OCP_V3_2_D_R_DP
          	               	2         	207A4     	CLK_100M_OCP_V3_2_D_DP

R3201     	Q_RES_0402LF   	          	          	                    
          	               	1         	207A4     	CLK_100M_OCP_V3_2_D_R_DN
          	               	2         	207A4     	CLK_100M_OCP_V3_2_D_DN

R3203     	Q_RES_0402LF   	          	          	                    
          	               	1         	160B4     	OCP_V3_2_AUX_PWR_EN 
          	               	2         	160B4     	OCP_V3_2_AUX_PWR_EN_R1

R3205     	Q_RES_0402LF   	          	          	                    
          	               	1         	160B3     	FB_BMC_ISOLATE_R2   
          	               	2         	160B3     	FB_BMC_ISOLATE1     

R3206     	Q_RES_0402LF   	          	          	                    
          	               	1         	160A3     	FM_NCSI_OCP_V3_2_R_OE
          	               	2         	160A3     	FB_BMC_ISOLATE1     

R3207     	Q_RES_0402LF   	          	          	                    
          	               	1         	160B3     	FB_BMC_ISOLATE1     
          	               	2         	160B3     	GND                 

R3208     	Q_RES_0402LF   	          	          	                    
          	               	1         	160A2     	OCP_V3_2_ISO_BIF0_EN
          	               	2         	160A2     	GND                 

R3209     	Q_RES_0402LF   	          	          	                    
          	               	1         	160B1     	OCP_V3_2_RBT_ARB_IN_R
          	               	2         	160B1     	OCP_V3_2_RBT_ARB_IN 

R3210     	Q_RES_0402LF   	          	          	                    
          	               	1         	160B2     	NCSI_BMC_CRS_DV_R1  
          	               	2         	160B2     	RMII_OCP_BMC_CRSDV  

R3211     	Q_RES_0402LF   	          	          	                    
          	               	1         	160B2     	NCSI_BMC_RXD0_R1    
          	               	2         	160B2     	RMII_OCP_BMC_RXD_0  

R3212     	Q_RES_0402LF   	          	          	                    
          	               	1         	160B2     	NCSI_BMC_RXD1_R1    
          	               	2         	160B2     	RMII_OCP_BMC_RXD_1  

R3213     	Q_RES_0402LF   	          	          	                    
          	               	1         	160B2     	NCSI_BMC_TX_EN_R1   
          	               	2         	160B2     	RMII_BMC_OCP_TX_EN  

R3214     	Q_RES_0402LF   	          	          	                    
          	               	1         	160B2     	NCSI_BMC_TXD0_R1    
          	               	2         	160B2     	RMII_BMC_OCP_TXD_0  

R3215     	Q_RES_0402LF   	          	          	                    
          	               	1         	160B2     	NCSI_BMC_TXD1_R1    
          	               	2         	160B2     	RMII_BMC_OCP_TXD_1  

R3216     	Q_RES_0402LF   	          	          	                    
          	               	1         	160A2     	OCP_V3_2_ISO_BIF1_EN
          	               	2         	160A2     	GND                 

R3217     	Q_RES_0402LF   	          	          	                    
          	               	1         	160A2     	OCP_V3_2_ISO_BIF2_EN
          	               	2         	160A2     	GND                 

R3222     	Q_RES_0402LF   	          	          	                    
          	               	1         	236B1     	SMB_S3M_CPU0_PIROM_3V3AUX_SCL
          	               	2         	236B1     	P3V3_AUX            

R3223     	Q_RES_0402LF   	          	          	                    
          	               	1         	236B1     	SMB_S3M_CPU0_PIROM_3V3AUX_SDA
          	               	2         	236B1     	P3V3_AUX            

R3224     	Q_RES_0402LF   	          	          	                    
          	               	1         	236B1     	SMB_S3M_CPU1_PIROM_3V3AUX_SCL
          	               	2         	236B1     	P3V3_AUX            

R3225     	Q_RES_0402LF   	          	          	                    
          	               	1         	236B1     	SMB_S3M_CPU1_PIROM_3V3AUX_SDA
          	               	2         	236B1     	P3V3_AUX            

R3226     	Q_RES_0402LF   	          	          	                    
          	               	1         	241B1     	SMB_1_BMC_GPU_SCL   
          	               	2         	241B1     	P3V3_AUX            

R3227     	Q_RES_0402LF   	          	          	                    
          	               	1         	241B1     	SMB_1_BMC_GPU_SDA   
          	               	2         	241B1     	P3V3_AUX            

R3228     	Q_RES_0402LF   	          	          	                    
          	               	1         	159B2     	SMB_OCP_V3_2_3V3AUX_BUF_R_SCL
          	               	2         	159B2     	SMB_OCP_V3_2_3V3AUX_BUF_SCL

R3229     	Q_RES_0402LF   	          	          	                    
          	               	1         	159B2     	SMB_OCP_V3_2_3V3AUX_BUF_R_SDA
          	               	2         	159B2     	SMB_OCP_V3_2_3V3AUX_BUF_SDA

R3230     	Q_RES_0402LF   	          	          	                    
          	               	1         	213A2     	FM_OCP_V3_2_PWR_GOOD
          	               	2         	213A2     	FM_OCP_V3_2_PWR_GOOD_R

R3231     	Q_RES_0402LF   	          	          	                    
          	               	1         	154A4     	OCP_SFF_AUX_PWR_EN  
          	               	2         	154A4     	OCP_SFF_AUX_PWR_EN_R4

R3232     	Q_RES_0402LF   	          	          	                    
          	               	1         	154A3     	RST_HP_OCP_SFF_R_N  
          	               	2         	154A3     	GND                 

R3233     	Q_RES_0402LF   	          	          	                    
          	               	1         	154A3     	RST_HP_OCP_SFF_R_N  
          	               	2         	154A3     	RST_SMB_OCP_SFF_N   

R3234     	Q_RES_0402LF   	          	          	                    
          	               	1         	161A4     	OCP_V3_2_AUX_PWR_EN 
          	               	2         	161A4     	OCP_V3_2_AUX_PWR_EN_R3

R3235     	Q_RES_0402LF   	          	          	                    
          	               	1         	161A3     	RST_HP_OCP_V3_2_R_N 
          	               	2         	161A3     	GND                 

R3236     	Q_RES_0402LF   	          	          	                    
          	               	1         	161A3     	RST_HP_OCP_V3_2_R_N 
          	               	2         	161A3     	RST_SMB_OCP_V3_2_N  

R3237     	Q_RES_0402LF   	          	          	                    
          	               	1         	154B1     	OCP_SFF_RBT_ARB_OUT 
          	               	2         	154B1     	OCP_SFF_RBT_ARB_IN_R

R3238     	Q_RES_0402LF   	          	          	                    
          	               	1         	240B4     	SMB_OCP_SFF_3V3AUX_SCL
          	               	2         	240B4     	SMB_OCP_SFF_3V3AUX_SCL_R0

R3239     	Q_RES_0402LF   	          	          	                    
          	               	1         	240B4     	SMB_OCP_SFF_3V3AUX_SDA
          	               	2         	240B4     	SMB_OCP_SFF_3V3AUX_SDA_R0

R3240     	Q_RES_0402LF   	          	          	                    
          	               	1         	241B1     	SMB_OCP_SFF_3V3AUX_SCL
          	               	2         	241B1     	P3V3_AUX            

R3241     	Q_RES_0402LF   	          	          	                    
          	               	1         	241B1     	SMB_OCP_SFF_3V3AUX_SDA
          	               	2         	241B1     	P3V3_AUX            

R3242     	Q_RES_0402LF   	          	          	                    
          	               	1         	241A1     	SMB_OCP_V3_2_3V3AUX_SCL
          	               	2         	241A1     	P3V3_AUX            

R3243     	Q_RES_0402LF   	          	          	                    
          	               	1         	241A1     	SMB_OCP_V3_2_3V3AUX_SDA
          	               	2         	241A1     	P3V3_AUX            

R3244     	Q_RES_0402LF   	          	          	                    
          	               	1         	160B1     	OCP_V3_2_RBT_ARB_OUT
          	               	2         	160B1     	OCP_V3_2_RBT_ARB_IN_R

R3249     	Q_RES_0402LF   	          	          	                    
          	               	1         	216B2     	P3V3_AUX            
          	               	2         	216A2     	PU_FPGA_D12_PROGRAMN

R3254     	Q_RES_0402LF   	          	          	                    
          	               	1         	240A1     	TP_PCIE_HPM_TXP<3>  
          	               	2         	240A1     	LED_HDD_ACTIVITY_B_N

R3263     	Q_RES_0402LF   	          	          	                    
          	               	1         	238B2     	HP_LVC3_OCP_V3_1_R_EN
          	               	2         	238B2     	HP_LVC3_OCP_V3_1_EN 

R3264     	Q_RES_0402LF   	          	          	                    
          	               	1         	238B2     	HP_LVC3_OCP_V3_2_R_EN
          	               	2         	238B2     	HP_LVC3_OCP_V3_2_EN 

R3265     	Q_RES_0402LF   	          	          	                    
          	               	1         	166B1     	CLK_GEN2_GPU_FPGA_OE_OR_N
          	               	2         	166B1     	GND                 

R3266     	Q_RES_0402LF   	          	          	                    
          	               	1         	166B1     	P3V3_AUX            
          	               	2         	166B1     	FM_P2E_MODE         

R3267     	Q_RES_0402LF   	          	          	                    
          	               	1         	166B4     	FM_P2E_FGB          
          	               	2         	166A4     	GND                 

R3268     	Q_RES_0402LF   	          	          	                    
          	               	1         	166A4     	FM_P2E_EQA1         
          	               	2         	166A4     	GND                 

R3269     	Q_RES_0402LF   	          	          	                    
          	               	1         	166B4     	P3V3_AUX            
          	               	2         	166B4     	FM_P2E_FGB          

R3270     	Q_RES_0402LF   	          	          	                    
          	               	1         	166B4     	FM_P2E_FGB          
          	               	2         	166A4     	GND                 

R3271     	Q_RES_0402LF   	          	          	                    
          	               	1         	166A4     	P3V3_AUX            
          	               	2         	166A4     	FM_P2E_EQA1         

R3272     	Q_RES_0402LF   	          	          	                    
          	               	1         	166A4     	FM_P2E_EQA1         
          	               	2         	166A4     	GND                 

R3273     	Q_RES_0402LF   	          	          	                    
          	               	1         	166B4     	FM_P2E_FGA          
          	               	2         	166A4     	GND                 

R3274     	Q_RES_0402LF   	          	          	                    
          	               	1         	166A4     	FM_P2E_EQA0         
          	               	2         	166A4     	GND                 

R3275     	Q_RES_0402LF   	          	          	                    
          	               	1         	166B4     	P3V3_AUX            
          	               	2         	166B4     	FM_P2E_FGA          

R3276     	Q_RES_0402LF   	          	          	                    
          	               	1         	166B4     	FM_P2E_FGA          
          	               	2         	166A4     	GND                 

R3277     	Q_RES_0402LF   	          	          	                    
          	               	1         	166A4     	P3V3_AUX            
          	               	2         	166A4     	FM_P2E_EQA0         

R3278     	Q_RES_0402LF   	          	          	                    
          	               	1         	166A4     	FM_P2E_EQA0         
          	               	2         	166A4     	GND                 

R3279     	Q_RES_0402LF   	          	          	                    
          	               	1         	166A4     	FM_P2E_EQB1         
          	               	2         	166A4     	GND                 

R3280     	Q_RES_0402LF   	          	          	                    
          	               	1         	166A4     	P3V3_AUX            
          	               	2         	166A4     	FM_P2E_EQB1         

R3281     	Q_RES_0402LF   	          	          	                    
          	               	1         	166A4     	FM_P2E_EQB1         
          	               	2         	166A4     	GND                 

R3282     	Q_RES_0402LF   	          	          	                    
          	               	1         	166A3     	FM_P2E_EQB0         
          	               	2         	166A3     	GND                 

R3283     	Q_RES_0402LF   	          	          	                    
          	               	1         	166A3     	P3V3_AUX            
          	               	2         	166A3     	FM_P2E_EQB0         

R3284     	Q_RES_0402LF   	          	          	                    
          	               	1         	166A3     	FM_P2E_EQB0         
          	               	2         	166A3     	GND                 

R3285     	Q_RES_0402LF   	          	          	                    
          	               	1         	166B3     	FM_P2E_SWB          
          	               	2         	166A3     	GND                 

R3286     	Q_RES_0402LF   	          	          	                    
          	               	1         	166B3     	P3V3_AUX            
          	               	2         	166B3     	FM_P2E_SWB          

R3287     	Q_RES_0402LF   	          	          	                    
          	               	1         	166B3     	FM_P2E_SWB          
          	               	2         	166A3     	GND                 

R3288     	Q_RES_0402LF   	          	          	                    
          	               	1         	166B2     	FM_P2E_SWA          
          	               	2         	166A2     	GND                 

R3289     	Q_RES_0402LF   	          	          	                    
          	               	1         	166B2     	P3V3_AUX            
          	               	2         	166B2     	FM_P2E_SWA          

R3290     	Q_RES_0402LF   	          	          	                    
          	               	1         	166B2     	FM_P2E_SWA          
          	               	2         	166A2     	GND                 

R3291     	Q_RES_0402LF   	          	          	                    
          	               	1         	166B2     	PU_TEST             
          	               	2         	166B2     	GND                 

R3292     	Q_RES_0402LF   	          	          	                    
          	               	1         	166B1     	P3V3_AUX            
          	               	2         	166B1     	CLK_GEN2_GPU_FPGA_OE_OR_N

R3293     	Q_RES_0402LF   	          	          	                    
          	               	1         	166B1     	FM_P2E_MODE         
          	               	2         	166B1     	GND                 

R3294     	Q_RES_0402LF   	          	          	                    
          	               	1         	190B4     	LED_M2_SSD_0_ACT_N  
          	               	2         	190B4     	LED_HDD_ACTIVITY_N  

R3295     	Q_RES_0402LF   	          	          	                    
          	               	1         	190B4     	P3V3_M2_0           
          	               	2         	190B4     	LED_HDD_ACTIVITY_N  

R3296     	Q_RES_0402LF   	          	          	                    
          	               	1         	190A3     	P3V3_AUX            
          	               	2         	190A3     	HDD_ACTIVITY_BUF    

R3297     	Q_RES_0402LF   	          	          	                    
          	               	1         	190A2     	LED_HDD_ACTIVITY_B_N
          	               	2         	190A2     	GND                 

R3298     	Q_RES_0402LF   	          	          	                    
          	               	1         	190A2     	P3V3_AUX            
          	               	2         	190A2     	HDD_ACTIVITY_BUF_N  

R3301     	Q_RES_0402LF   	          	          	                    
          	               	1         	190B4     	IRQ_LVC3_WAKE_N     
          	               	2         	190B4     	M2_0_PEWAKE_N       

R3302     	Q_RES_0402LF   	          	          	                    
          	               	1         	240A1     	TP_PCIE_HPM_TXN<3>  
          	               	2         	240A1     	FM_PCH_SPKR         

R3303     	Q_RES_0402LF   	          	          	                    
          	               	1         	165B3     	OCP_SFF_PRSNT_ALL_R_N
          	               	2         	165B3     	OCP_SFF_PRSNT_ALL_R1_N

R3304     	Q_RES_0402LF   	          	          	                    
          	               	1         	165B3     	OCP_SFF_PRSNT_ALL_R_N
          	               	2         	165B3     	OCP_SFF_PRSNT_ALL_R3_N

R3305     	Q_RES_0402LF   	          	          	                    
          	               	1         	165B3     	OCP_SFF_RBT_ARB_IN_MUX1
          	               	2         	165B3     	OCP_SFF_RBT_ARB_IN_MUX1_R

R3306     	Q_RES_0402LF   	          	          	                    
          	               	1         	165A3     	OCP_V3_2_PRSNT_ALL_R_N
          	               	2         	165A3     	OCP_V3_2_PRSNT_ALL_R3_N

R3307     	Q_RES_0402LF   	          	          	                    
          	               	1         	165A3     	OCP_SFF_RBT_ARB_IN_MUX2
          	               	2         	165A3     	OCP_SFF_RBT_ARB_IN_MUX2_R

R3308     	Q_RES_0402LF   	          	          	                    
          	               	1         	165B3     	OCP_V3_2_PRSNT_ALL_R_N
          	               	2         	165B3     	OCP_V3_2_PRSNT_ALL_R1_N

R3315     	Q_RES_0402LF   	          	          	                    
          	               	1         	151A2     	GPU_FPGA_RST_R1_BUF_N
          	               	2         	151A2     	GPU_FPGA_RST_R_BUF_N

R3317     	Q_RES_0402LF   	          	          	                    
          	               	1         	151A2     	P3V3_AUX            
          	               	2         	151A2     	GPU_FPGA_RST_R1_BUF_N

R3318     	Q_RES_0402LF   	          	          	                    
          	               	1         	148A2     	P3V3_AUX            
          	               	2         	148A2     	GPU_FPGA_READY      

R3320     	Q_RES_0402LF   	          	          	                    
          	               	1         	148A2     	P3V3_AUX            
          	               	2         	148A2     	GPU_FPGA_READY_N    

R3321     	Q_RES_0402LF   	          	          	                    
          	               	1         	148A1     	P3V3_AUX            
          	               	2         	148A1     	GPU_FPGA_READY_ISO  

R3322     	Q_RES_0402LF   	          	          	                    
          	               	1         	212A4     	P3V3_AUX            
          	               	2         	212A4     	CLK_GEN2_GPU_FPGA_OE_R2_N

R3324     	Q_RES_0402LF   	          	          	                    
          	               	1         	213A2     	GPU_FPGA_READY_ISO  
          	               	2         	213A2     	GPU_FPGA_READY_ISO_R

R3325     	Q_RES_0402LF   	          	          	                    
          	               	1         	198B4     	FM_PCH_SPKR         
          	               	2         	198B4     	GND                 

R3326     	Q_RES_0402LF   	          	          	                    
          	               	1         	212A4     	GPU_FPGA_READY_N    
          	               	2         	212A4     	GPU_FPGA_READY_R_N  

R3327     	Q_RES_0402LF   	          	          	                    
          	               	1         	212A4     	CLK_GEN2_GPU_FPGA_OE_N
          	               	2         	212A4     	CLK_GEN2_GPU_FPGA_OE_R2_N

R3335     	Q_RES_0402LF   	          	          	                    
          	               	1         	212B2     	CLK_100M_BMC_RC_DP_R
          	               	2         	212B2     	CLK_100M_BMC_RC_DP  

R3336     	Q_RES_0402LF   	          	          	                    
          	               	1         	212B2     	CLK_100M_BMC_RC_DN_R
          	               	2         	212B2     	CLK_100M_BMC_RC_DN  

R3337     	Q_RES_0402LF   	          	          	                    
          	               	1         	212B2     	CLK_100M_GPU_FPGA_DP_R
          	               	2         	212B2     	CLK_100M_GPU_FPGA_DP

R3338     	Q_RES_0402LF   	          	          	                    
          	               	1         	212B2     	CLK_100M_GPU_FPGA_DN_R
          	               	2         	212B2     	CLK_100M_GPU_FPGA_DN

R3340     	Q_RES_0402LF   	          	          	                    
          	               	1         	241B4     	SMB_HOST_CLK_3V3AUX_SCL
          	               	2         	241B4     	SMB_HOST_CLK_GEN2_3V3AUX_SCL

R3341     	Q_RES_0402LF   	          	          	                    
          	               	1         	241B4     	SMB_HOST_CLK_3V3AUX_SDA
          	               	2         	241B4     	SMB_HOST_CLK_GEN2_3V3AUX_SDA

R3344     	Q_RES_0603LF   	          	          	                    
          	               	1         	217A4     	P3V3_AUX            
          	               	2         	217A4     	P3V3_AUX_FPGA_VCCIO3

R3345     	Q_RES_0603LF   	          	          	                    
          	               	1         	217A3     	P3V3_AUX            
          	               	2         	217A3     	P3V3_AUX_FPGA_VCCIO4

R3346     	Q_RES_0603LF   	          	          	                    
          	               	1         	217B3     	P3V3_AUX            
          	               	2         	217B3     	P3V3_AUX_FPGA_VCCIO0

R3347     	Q_RES_0603LF   	          	          	                    
          	               	1         	217A3     	P3V3_AUX            
          	               	2         	217A3     	P3V3_AUX_FPGA_VCCIO2

R3348     	Q_RES_0603LF   	          	          	                    
          	               	1         	217B3     	P3V3_AUX            
          	               	2         	217B3     	P3V3_AUX_FPGA_VCCIO1

R3349     	Q_RES_0603LF   	          	          	                    
          	               	1         	217A2     	P3V3_AUX            
          	               	2         	217A2     	P3V3_AUX_FPGA_VCCIO5

R3352     	Q_RES_0402LF   	          	          	                    
          	               	1         	207B4     	CLK_100M_GPU_1_R_DP 
          	               	2         	207B4     	CLK_100M_GPU_1_DP   

R3353     	Q_RES_0402LF   	          	          	                    
          	               	1         	207B4     	CLK_100M_GPU_1_R_DN 
          	               	2         	207B4     	CLK_100M_GPU_1_DN   

R3354     	Q_RES_0402LF   	          	          	                    
          	               	1         	207B4     	CLK_100M_GPU_2_R_DP 
          	               	2         	207B4     	CLK_100M_GPU_2_DP   

R3355     	Q_RES_0402LF   	          	          	                    
          	               	1         	207B4     	CLK_100M_GPU_2_R_DN 
          	               	2         	207B4     	CLK_100M_GPU_2_DN   

R3362     	Q_RES_0402LF   	          	          	                    
          	               	1         	167B3     	PD_P2E_BUF2_ENSMB   
          	               	2         	167B3     	GND                 

R3381     	Q_RES_0402LF   	          	          	                    
          	               	1         	167A3     	FM_P2E_BUF2_RXDET   
          	               	2         	167A3     	GND                 

R3386     	Q_RES_0402LF   	          	          	                    
          	               	1         	167A1     	P3V3_AUX            
          	               	2         	167A1     	FM_P2E_BUF2_VOD_SEL 

R3390     	Q_RES_0402LF   	          	          	                    
          	               	1         	149B2     	GPU_FPGA_BOOT_EN_BUF_R
          	               	2         	149B2     	GPU_FPGA_BOOT_EN_BUF

R3391     	Q_RES_0402LF   	          	          	                    
          	               	1         	149B2     	RST_PERST_1_SWB_BUF_R_N
          	               	2         	149B2     	RST_PERST_1_SWB_BUF_N

R3392     	Q_RES_0402LF   	          	          	                    
          	               	1         	149B2     	GPU_BASE_STBY_EN_BUF_R
          	               	2         	149B2     	GPU_BASE_STBY_EN_BUF

R3393     	Q_RES_0402LF   	          	          	                    
          	               	1         	231B3     	SMB_IOEXP_3V3AUX_SCL_R
          	               	2         	231B3     	SMB_IOEXP_3V3AUX_SCL

R3394     	Q_RES_0402LF   	          	          	                    
          	               	1         	231B3     	SMB_IOEXP_3V3AUX_SDA_R
          	               	2         	231B3     	SMB_IOEXP_3V3AUX_SDA

R3395     	Q_RES_0402LF   	          	          	                    
          	               	1         	231B2     	P3V3_AUX            
          	               	2         	231B2     	SMB_INA230_3V3AUX_SCL

R3396     	Q_RES_0402LF   	          	          	                    
          	               	1         	231B2     	P3V3_AUX            
          	               	2         	231B2     	SMB_INA230_3V3AUX_SDA

R3397     	Q_RES_0402LF   	          	          	                    
          	               	1         	150B2     	GPU_NVS_PWR_BRAKE_N_R
          	               	2         	150B2     	GPU_NVS_PWR_BRAKE_N_BUF

R3428     	Q_RES_0402LF   	          	          	                    
          	               	1         	147B4     	GPU_FPGA_THERM_OVERT_N
          	               	2         	147B4     	GND                 

R3429     	Q_RES_0402LF   	          	          	                    
          	               	1         	147B4     	P3V3_AUX            
          	               	2         	147B4     	GPU_BASE_HMC_READY  

R3430     	Q_RES_0402LF   	          	          	                    
          	               	1         	147A4     	GPU_FPGA_OVERT_N    
          	               	2         	147A4     	GND                 

R3431     	Q_RES_0402LF   	          	          	                    
          	               	1         	147A4     	GPU_HMC_PRSNT_N     
          	               	2         	147A4     	GND                 

R3432     	Q_RES_0402LF   	          	          	                    
          	               	1         	147B4     	P3V3_AUX            
          	               	2         	147B4     	GPU_FPGA_THERM_OVERT

R3433     	Q_RES_0402LF   	          	          	                    
          	               	1         	147B4     	P3V3_AUX            
          	               	2         	147B4     	GPU_BASE_HMC_READY_N

R3434     	Q_RES_0402LF   	          	          	                    
          	               	1         	147B4     	P3V3_AUX            
          	               	2         	147B4     	GPU_HMC_PRSNT       

R3435     	Q_RES_0402LF   	          	          	                    
          	               	1         	147A4     	P3V3_AUX            
          	               	2         	147A4     	GPU_FPGA_OVERT      

R3436     	Q_RES_0402LF   	          	          	                    
          	               	1         	147B4     	P3V3_AUX            
          	               	2         	147B4     	GPU_HMC_PRSNT_ISO_N 

R3437     	Q_RES_0402LF   	          	          	                    
          	               	1         	147A4     	P3V3_AUX            
          	               	2         	147A4     	GPU_FPGA_OVERT_ISO_N

R3438     	Q_RES_0402LF   	          	          	                    
          	               	1         	147B4     	P3V3_AUX            
          	               	2         	147B4     	GPU_BASE_HMC_READY_ISO

R3439     	Q_RES_0402LF   	          	          	                    
          	               	1         	147B4     	P3V3_AUX            
          	               	2         	147B4     	GPU_FPGA_THERM_OVERT_ISO_N

R3440     	Q_RES_0402LF   	          	          	                    
          	               	1         	144A1     	GPU_BASE_ID0        
          	               	2         	144A1     	GND                 

R3441     	Q_RES_0402LF   	          	          	                    
          	               	1         	144A1     	GPU_BASE_ID1        
          	               	2         	144A1     	GND                 

R3442     	Q_RES_0402LF   	          	          	                    
          	               	1         	144A1     	GPU_PEX_STRAP0      
          	               	2         	144A1     	GND                 

R3443     	Q_RES_0402LF   	          	          	                    
          	               	1         	144A1     	GPU_PEX_STRAP1      
          	               	2         	144A1     	GND                 

R3448     	Q_RES_0402LF   	          	          	                    
          	               	1         	149B4     	P3V3_AUX            
          	               	2         	149B4     	GPU_FPGA_BOOT_EN    

R3449     	Q_RES_0402LF   	          	          	                    
          	               	1         	149B4     	GPU_FPGA_BOOT_EN    
          	               	2         	149B4     	GND                 

R3451     	Q_RES_0402LF   	          	          	                    
          	               	1         	149B4     	P3V3_AUX            
          	               	2         	149B4     	GPU_BASE_STBY_EN    

R3452     	Q_RES_0402LF   	          	          	                    
          	               	1         	149B4     	GPU_BASE_STBY_EN    
          	               	2         	149B4     	GND                 

R3453     	Q_RES_0402LF   	          	          	                    
          	               	1         	149B2     	P3V3_AUX            
          	               	2         	149B2     	GPU_FPGA_BOOT_EN_BUF_R

R3454     	Q_RES_0402LF   	          	          	                    
          	               	1         	149B2     	GPU_FPGA_BOOT_EN_BUF_R
          	               	2         	149B2     	GND                 

R3455     	Q_RES_0402LF   	          	          	                    
          	               	1         	149B2     	RST_PERST_1_SWB_BUF_R_N
          	               	2         	149A2     	GND                 

R3456     	Q_RES_0402LF   	          	          	                    
          	               	1         	149B2     	P3V3_AUX            
          	               	2         	149B2     	GPU_BASE_STBY_EN_BUF_R

R3457     	Q_RES_0402LF   	          	          	                    
          	               	1         	149B2     	GPU_BASE_STBY_EN_BUF_R
          	               	2         	149B2     	GND                 

R3458     	Q_RES_0603LF   	          	          	                    
          	               	1         	217B3     	P3V3_AUX            
          	               	2         	217B3     	VCC_PLD_CORE        

R3459     	Q_RES_0402LF   	          	          	                    
          	               	1         	150B4     	P3V3_AUX            
          	               	2         	150B4     	GPU_NVS_PWR_BRAKE_N 

R3460     	Q_RES_0402LF   	          	          	                    
          	               	1         	150B4     	GPU_NVS_PWR_BRAKE_N 
          	               	2         	150B4     	GND                 

R3461     	Q_RES_0402LF   	          	          	                    
          	               	1         	150B2     	P3V3_AUX            
          	               	2         	150B2     	GPU_NVS_PWR_BRAKE_N_R

R3462     	Q_RES_0402LF   	          	          	                    
          	               	1         	150B2     	GPU_NVS_PWR_BRAKE_N_R
          	               	2         	150B2     	GND                 

R3463     	Q_RES_0402LF   	          	          	                    
          	               	1         	147B4     	GPU_BASE_HMC_READY  
          	               	2         	147B4     	GND                 

R3464     	Q_RES_0402LF   	          	          	                    
          	               	1         	147A4     	P3V3_AUX            
          	               	2         	147A4     	GPU_FPGA_OVERT_N    

R3465     	Q_RES_0402LF   	          	          	                    
          	               	1         	147B4     	P3V3_AUX            
          	               	2         	147B4     	GPU_HMC_PRSNT_N     

R3466     	Q_RES_0402LF   	          	          	                    
          	               	1         	149A2     	RST_PERST_2_SWB_BUF_R_N
          	               	2         	149A2     	GND                 

R3467     	Q_RES_0402LF   	          	          	                    
          	               	1         	149B2     	RST_PERST_0_SWB_BUF_R_N
          	               	2         	149B2     	GND                 

R3468     	Q_RES_0402LF   	          	          	                    
          	               	1         	149A2     	RST_PERST_2_SWB_BUF_R_N
          	               	2         	149A2     	RST_PERST_2_SWB_BUF_N

R3469     	Q_RES_0402LF   	          	          	                    
          	               	1         	149B2     	RST_PERST_0_SWB_BUF_R_N
          	               	2         	149B2     	RST_PERST_0_SWB_BUF_N

R3470     	Q_RES_0402LF   	          	          	                    
          	               	1         	147B2     	P3V3_AUX            
          	               	2         	147B2     	GPU_WP_HW_CTRL_N    

R3471     	Q_RES_0402LF   	          	          	                    
          	               	1         	147B2     	GPU_WP_HW_CTRL_N    
          	               	2         	147B2     	GND                 

R3472     	Q_RES_0402LF   	          	          	                    
          	               	1         	147B1     	GND                 
          	               	2         	147B1     	GPU_WP_HW_CTRL_ISO  

R3473     	Q_RES_0402LF   	          	          	                    
          	               	1         	147B2     	GPU_PRSNT_N         
          	               	2         	147B2     	GND                 

R3474     	Q_RES_0402LF   	          	          	                    
          	               	1         	147B2     	P3V3_AUX            
          	               	2         	147B2     	GPU_PRSNT           

R3475     	Q_RES_0402LF   	          	          	                    
          	               	1         	147B1     	P3V3_AUX            
          	               	2         	147B1     	GPU_PRSNT_N_ISO     

R3476     	Q_RES_0402LF   	          	          	                    
          	               	1         	213A4     	GPU_FPGA_THERM_OVERT_ISO_N
          	               	2         	213A4     	GPU_FPGA_THERM_OVERT_ISO_R_N

R3477     	Q_RES_0402LF   	          	          	                    
          	               	1         	213A4     	GPU_NVS_PWR_BRAKE_N 
          	               	2         	213A4     	GPU_NVS_PWR_BRAKE_R_N

R3478     	Q_RES_0402LF   	          	          	                    
          	               	1         	213A4     	GPU_FPGA_EROT_RST_N 
          	               	2         	213A4     	GPU_FPGA_EROT_RST_R_N

R3479     	Q_RES_0402LF   	          	          	                    
          	               	1         	213A4     	GPU_BASE_STBY_EN    
          	               	2         	213A4     	GPU_BASE_STBY_EN_R  

R3480     	Q_RES_0402LF   	          	          	                    
          	               	1         	213A4     	GPU_BASE_HMC_READY_ISO
          	               	2         	213A4     	GPU_BASE_HMC_READY_ISO_R

R3481     	Q_RES_0402LF   	          	          	                    
          	               	1         	213A4     	GPU_HMC_PRSNT_ISO_N 
          	               	2         	213A4     	GPU_HMC_PRSNT_ISO_R_N

R3482     	Q_RES_0402LF   	          	          	                    
          	               	1         	213A4     	GPU_FPGA_BOOT_EN    
          	               	2         	213A4     	GPU_FPGA_BOOT_EN_R  

R3483     	Q_RES_0402LF   	          	          	                    
          	               	1         	213A4     	GPU_FPGA_EROT_RECOV_N
          	               	2         	213A4     	GPU_FPGA_EROT_RECOV_R_N

R3484     	Q_RES_0402LF   	          	          	                    
          	               	1         	213A4     	GPU_FPGA_OVERT_ISO_N
          	               	2         	213A4     	GPU_FPGA_OVERT_ISO_R_N

R3485     	Q_RES_0402LF   	          	          	                    
          	               	1         	213A4     	GPU_WP_HW_CTRL_N    
          	               	2         	213A4     	GPU_WP_HW_CTRL_R_N  

R3486     	Q_RES_0402LF   	          	          	                    
          	               	1         	213A4     	GPU_PRSNT_N_ISO     
          	               	2         	213A4     	GPU_PRSNT_N_ISO_R   

R3487     	Q_RES_0402LF   	          	          	                    
          	               	1         	147B2     	P3V3_AUX            
          	               	2         	147B2     	GPU_PRSNT_N         

R3488     	Q_RES_0402LF   	          	          	                    
          	               	1         	150B4     	P3V3_AUX            
          	               	2         	150B4     	GPU_FPGA_EROT_RST_N 

R3489     	Q_RES_0402LF   	          	          	                    
          	               	1         	150B4     	GPU_FPGA_EROT_RST_N 
          	               	2         	150B4     	GND                 

R3490     	Q_RES_0402LF   	          	          	                    
          	               	1         	150B4     	P3V3_AUX            
          	               	2         	150B4     	GPU_FPGA_EROT_RECOV_N

R3491     	Q_RES_0402LF   	          	          	                    
          	               	1         	150B4     	GPU_FPGA_EROT_RECOV_N
          	               	2         	150B4     	GND                 

R3492     	Q_RES_0402LF   	          	          	                    
          	               	1         	150B2     	P3V3_AUX            
          	               	2         	150B2     	GPU_FPGA_EROT_RST_BUF_R_N

R3493     	Q_RES_0402LF   	          	          	                    
          	               	1         	150B2     	GPU_FPGA_EROT_RST_BUF_R_N
          	               	2         	150B2     	GND                 

R3494     	Q_RES_0402LF   	          	          	                    
          	               	1         	150B2     	P3V3_AUX            
          	               	2         	150B2     	GPU_FPGA_EROT_RECOV_BUF_R_N

R3495     	Q_RES_0402LF   	          	          	                    
          	               	1         	150B2     	GPU_FPGA_EROT_RECOV_BUF_R_N
          	               	2         	150B2     	GND                 

R3496     	Q_RES_0402LF   	          	          	                    
          	               	1         	150B2     	GPU_FPGA_EROT_RST_BUF_R_N
          	               	2         	150B2     	GPU_FPGA_EROT_RST_BUF_N

R3497     	Q_RES_0402LF   	          	          	                    
          	               	1         	150B2     	GPU_FPGA_EROT_RECOV_BUF_R_N
          	               	2         	150B2     	GPU_FPGA_EROT_RECOV_BUF_N

R3498     	Q_RES_0402LF   	          	          	                    
          	               	1         	147B4     	P3V3_AUX            
          	               	2         	147B4     	GPU_FPGA_THERM_OVERT_N

R3499     	Q_RES_0402LF   	          	          	                    
          	               	1         	227B3     	GPU_BASE_ID1        
          	               	2         	227B3     	GPU_BASE_ID1_R      

R3500     	Q_RES_0402LF   	          	          	                    
          	               	1         	238B2     	P3V3_OCP_SFF        
          	               	2         	238B2     	SMB_OCP_SFF_3V3AUX_BUF_SCL

R3501     	Q_RES_0402LF   	          	          	                    
          	               	1         	238B2     	P3V3_OCP_SFF        
          	               	2         	238B2     	SMB_OCP_SFF_3V3AUX_BUF_SDA

R3502     	Q_RES_0402LF   	          	          	                    
          	               	1         	147A2     	GPU_FPGA_EROT_FATALERR_N
          	               	2         	147A2     	GND                 

R3503     	Q_RES_0402LF   	          	          	                    
          	               	1         	147B2     	P3V3_AUX            
          	               	2         	147B2     	GPU_FPGA_EROT_FATALERR

R3504     	Q_RES_0402LF   	          	          	                    
          	               	1         	147B1     	P3V3_AUX            
          	               	2         	147B1     	GPU_FPGA_EROT_FATALERR_ISO_N

R3505     	Q_RES_0402LF   	          	          	                    
          	               	1         	213A4     	GPU_FPGA_EROT_FATALERR_ISO_N
          	               	2         	213A4     	GPU_FPGA_EROT_FATALERR_ISO_R_N

R3506     	Q_RES_0402LF   	          	          	                    
          	               	1         	151A4     	P3V3_AUX            
          	               	2         	151A4     	GPU_FPGA_RST_R_N    

R3507     	Q_RES_0402LF   	          	          	                    
          	               	1         	151A4     	GPU_FPGA_RST_R_N    
          	               	2         	151A4     	GND                 

R3508     	Q_RES_0402LF   	          	          	                    
          	               	1         	151B2     	FM_GPU_PWR_EN_R1    
          	               	2         	151B2     	GND                 

R3509     	Q_RES_0402LF   	          	          	                    
          	               	1         	151A2     	GPU_FPGA_RST_R1_BUF_N
          	               	2         	151A2     	GND                 

R3510     	Q_RES_0402LF   	          	          	                    
          	               	1         	148A4     	P3V3_AUX            
          	               	2         	148A4     	FM_SMB_1_ALERT_GPU_N

R3511     	Q_RES_0402LF   	          	          	                    
          	               	1         	148A2     	GPU_FPGA_READY      
          	               	2         	148A2     	GND                 

R3512     	Q_RES_0402LF   	          	          	                    
          	               	1         	148B2     	P3V3_AUX            
          	               	2         	148B2     	FM_GPU_PWRGD        

R3513     	Q_RES_0402LF   	          	          	                    
          	               	1         	148B2     	FM_GPU_PWRGD        
          	               	2         	148B2     	GND                 

R3514     	Q_RES_0402LF   	          	          	                    
          	               	1         	148B2     	P3V3_AUX            
          	               	2         	148B2     	FM_SMB_2_ALERT_GPU_N

R3515     	Q_RES_0402LF   	          	          	                    
          	               	1         	149A2     	FM_SWB_PWR_EN_R1_BUF
          	               	2         	149A2     	FM_SWB_PWR_EN_R_BUF 

R3516     	Q_RES_0402LF   	          	          	                    
          	               	1         	227A3     	GPU_BASE_ID0        
          	               	2         	227A3     	GPU_BASE_ID0_R      

R3517     	Q_RES_0402LF   	          	          	                    
          	               	1         	227A3     	GPU_PEX_STRAP1      
          	               	2         	227A3     	GPU_PEX_STRAP1_R    

R3518     	Q_RES_0402LF   	          	          	                    
          	               	1         	227A3     	GPU_PEX_STRAP0      
          	               	2         	227A3     	GPU_PEX_STRAP0_R    

R3519     	Q_RES_0402LF   	          	          	                    
          	               	1         	238B2     	P3V3_OCP_V3_2       
          	               	2         	238B2     	SMB_OCP_V3_2_3V3AUX_BUF_SCL

R3520     	Q_RES_0402LF   	          	          	                    
          	               	1         	238B2     	P3V3_OCP_V3_2       
          	               	2         	238B2     	SMB_OCP_V3_2_3V3AUX_BUF_SDA

R3521     	Q_RES_0402LF   	          	          	                    
          	               	1         	234B3     	P3V3_AUX            
          	               	2         	234B3     	SMB_2_BMC_GPU_BUF_R_SCL

R3522     	Q_RES_0402LF   	          	          	                    
          	               	1         	234B3     	P3V3_AUX            
          	               	2         	234B3     	SMB_2_BMC_GPU_BUF_R_SDA

R3523     	Q_RES_0402LF   	          	          	                    
          	               	1         	234B2     	P3V3_AUX            
          	               	2         	234B2     	SMB_1_BMC_GPU_BUF_R_SCL

R3524     	Q_RES_0402LF   	          	          	                    
          	               	1         	234B2     	P3V3_AUX            
          	               	2         	234B2     	SMB_1_BMC_GPU_BUF_R_SDA

R3525     	Q_RES_0402LF   	          	          	                    
          	               	1         	147B2     	P3V3_AUX            
          	               	2         	147A2     	GPU_FPGA_EROT_FATALERR_N

R3526     	Q_RES_0402LF   	          	          	                    
          	               	1         	231B3     	SMB_PCIE0_3V3AUX_SCL_R5
          	               	2         	231B3     	SMB_SENSOR_E1S_3V3AUX_SCL

R3527     	Q_RES_0402LF   	          	          	                    
          	               	1         	231B3     	SMB_PCIE0_3V3AUX_SDA_R5
          	               	2         	231B3     	SMB_SENSOR_E1S_3V3AUX_SDA

R3529     	Q_RES_0402LF   	          	          	                    
          	               	1         	194B3     	P3V3_AUX            
          	               	2         	194B3     	SMB_PCIE_E1S_ISO_EN_R

R3530     	Q_RES_0402LF   	          	          	                    
          	               	1         	194B2     	P3V3_E1S_0          
          	               	2         	194B2     	SMB_E1S_3V3AUX_ISO_SCL_R

R3531     	Q_RES_0402LF   	          	          	                    
          	               	1         	194B4     	SMB_PCIE_E1S_ISO_EN 
          	               	2         	194B4     	SMB_PCIE_E1S_ISO_EN_R

R3532     	Q_RES_0402LF   	          	          	                    
          	               	1         	194B2     	P3V3_E1S_0          
          	               	2         	194B2     	SMB_E1S_3V3AUX_ISO_SDA_R

R3533     	Q_RES_0402LF   	          	          	                    
          	               	1         	194B2     	SMB_E1S_3V3AUX_ISO_SCL_R
          	               	2         	194B2     	SMB_E1S_3V3AUX_ISO_SCL

R3534     	Q_RES_0402LF   	          	          	                    
          	               	1         	194B2     	SMB_E1S_3V3AUX_ISO_SDA_R
          	               	2         	194B2     	SMB_E1S_3V3AUX_ISO_SDA

R3535     	Q_RES_0402LF   	          	          	                    
          	               	1         	231A2     	P3V3_AUX            
          	               	2         	231A2     	SMB_SENSOR_E1S_3V3AUX_SCL

R3536     	Q_RES_0402LF   	          	          	                    
          	               	1         	231A2     	P3V3_AUX            
          	               	2         	231A2     	SMB_SENSOR_E1S_3V3AUX_SDA

R3553     	Q_RES_0402LF   	          	          	                    
          	               	1         	170A4     	SMB_LM75_3_3V3AUX_SCL
          	               	2         	170A4     	SMB_LM75_3_3V3AUX_SCL_R1

R3554     	Q_RES_0402LF   	          	          	                    
          	               	1         	170A4     	SMB_LM75_3_3V3AUX_SDA
          	               	2         	170A4     	SMB_LM75_3_3V3AUX_SDA_R1

R3559     	Q_RES_0402LF   	          	          	                    
          	               	1         	172B2     	OCP_V3_2_P3V3_ADC_ALERT_R
          	               	2         	172B2     	OCP_V3_2_P3V3_ADC_ALERT

R3560     	Q_RES_0402LF   	          	          	                    
          	               	1         	172B2     	M2_0_P3V3_ADC_ALERT_R
          	               	2         	172B2     	M2_0_P3V3_ADC_ALERT 

R3561     	Q_RES_0402LF   	          	          	                    
          	               	1         	172A2     	P12V_SCM_ADC_ALERT_R
          	               	2         	172A2     	P12V_SCM_ADC_ALERT  

R3563     	Q_RES_0402LF   	          	          	                    
          	               	1         	171B2     	OCP_SFF_P3V3_ADC_ALERT_R
          	               	2         	171B2     	OCP_SFF_P3V3_ADC_ALERT

R3568     	Q_RES_0402LF   	          	          	                    
          	               	1         	172B3     	SMB_INA230_3_3V3AUX_SCL_R
          	               	2         	172B3     	SMB_INA230_3_3V3AUX_SCL_R1

R3569     	Q_RES_0402LF   	          	          	                    
          	               	1         	172B3     	SMB_INA230_3_3V3AUX_SDA_R
          	               	2         	172B3     	SMB_INA230_3_3V3AUX_SDA_R1

R3570     	Q_RES_0402LF   	          	          	                    
          	               	1         	172B3     	P3V3_OCP_V3_2_R     
          	               	2         	172B3     	VSENSE_P12V_INA230_3_INP

R3571     	Q_RES_0402LF   	          	          	                    
          	               	1         	172B3     	P3V3_OCP_V3_2       
          	               	2         	172B3     	VSENSE_P12V_INA230_3_INN

R3572     	Q_RES_0402LF   	          	          	                    
          	               	1         	172B3     	SMB_INA230_4_3V3AUX_SCL_R
          	               	2         	172B3     	SMB_INA230_4_3V3AUX_SCL_R1

R3573     	Q_RES_0402LF   	          	          	                    
          	               	1         	172B3     	SMB_INA230_4_3V3AUX_SDA_R
          	               	2         	172B3     	SMB_INA230_4_3V3AUX_SDA_R1

R3574     	Q_RES_0402LF   	          	          	                    
          	               	1         	172B3     	P3V3                
          	               	2         	172B3     	VSENSE_P12V_INA230_4_INP

R3575     	Q_RES_0402LF   	          	          	                    
          	               	1         	172B3     	P3V3_M2_0           
          	               	2         	172B3     	VSENSE_P12V_INA230_4_INN

R3576     	Q_RES_0402LF   	          	          	                    
          	               	1         	172A3     	SMB_INA230_5_3V3AUX_SCL_R
          	               	2         	172A3     	SMB_INA230_5_3V3AUX_SCL_R1

R3577     	Q_RES_0402LF   	          	          	                    
          	               	1         	172A3     	SMB_INA230_5_3V3AUX_SDA_R
          	               	2         	172A3     	SMB_INA230_5_3V3AUX_SDA_R1

R3578     	Q_RES_0402LF   	          	          	                    
          	               	1         	172A3     	P12V_SCM_R          
          	               	2         	172A3     	VSENSE_P12V_INA230_5_INP

R3579     	Q_RES_0402LF   	          	          	                    
          	               	1         	172A3     	P12V_SCM            
          	               	2         	172A3     	VSENSE_P12V_INA230_5_INN

R3580     	Q_RES_0402LF   	          	          	                    
          	               	1         	231B2     	SMB_INA230_3V3AUX_SCL_R
          	               	2         	231B2     	SMB_INA230_3V3AUX_SCL

R3581     	Q_RES_0402LF   	          	          	                    
          	               	1         	231B2     	SMB_INA230_3V3AUX_SDA_R
          	               	2         	231B2     	SMB_INA230_3V3AUX_SDA

R3582     	Q_RES_0402LF   	          	          	                    
          	               	1         	231A2     	P3V3_AUX            
          	               	2         	231A2     	SMB_IOEXP_3V3AUX_SCL

R3583     	Q_RES_0402LF   	          	          	                    
          	               	1         	231A2     	P3V3_AUX            
          	               	2         	231A2     	SMB_IOEXP_3V3AUX_SDA

R3586     	Q_RES_0402LF   	          	          	                    
          	               	1         	232B3     	SMB_INA230_3V3AUX_SCL
          	               	2         	232B3     	SMB_INA230_1_3V3AUX_SCL_R

R3587     	Q_RES_0402LF   	          	          	                    
          	               	1         	232B3     	SMB_INA230_3V3AUX_SDA
          	               	2         	232B3     	SMB_INA230_1_3V3AUX_SDA_R

R3588     	Q_RES_0402LF   	          	          	                    
          	               	1         	232B3     	SMB_INA230_3V3AUX_SCL
          	               	2         	232B3     	SMB_INA230_2_3V3AUX_SCL_R

R3589     	Q_RES_0402LF   	          	          	                    
          	               	1         	232B3     	SMB_INA230_3V3AUX_SDA
          	               	2         	232B3     	SMB_INA230_2_3V3AUX_SDA_R

R3590     	Q_RES_0402LF   	          	          	                    
          	               	1         	232B3     	SMB_INA230_3V3AUX_SCL
          	               	2         	232B3     	SMB_INA230_3_3V3AUX_SCL_R

R3591     	Q_RES_0402LF   	          	          	                    
          	               	1         	232B3     	SMB_INA230_3V3AUX_SDA
          	               	2         	232B3     	SMB_INA230_3_3V3AUX_SDA_R

R3592     	Q_RES_0402LF   	          	          	                    
          	               	1         	232B3     	SMB_INA230_3V3AUX_SCL
          	               	2         	232B3     	SMB_INA230_5_3V3AUX_SCL_R

R3593     	Q_RES_0402LF   	          	          	                    
          	               	1         	232B3     	SMB_INA230_3V3AUX_SDA
          	               	2         	232B3     	SMB_INA230_5_3V3AUX_SDA_R

R3594     	Q_RES_0402LF   	          	          	                    
          	               	1         	232B3     	SMB_INA230_3V3AUX_SCL
          	               	2         	232B3     	SMB_INA230_4_3V3AUX_SCL_R

R3595     	Q_RES_0402LF   	          	          	                    
          	               	1         	232B3     	SMB_INA230_3V3AUX_SDA
          	               	2         	232B3     	SMB_INA230_4_3V3AUX_SDA_R

R3600     	Q_RES_0402LF   	          	          	                    
          	               	1         	171B3     	SMB_INA230_1_3V3AUX_SCL_R
          	               	2         	171B3     	SMB_INA230_1_3V3AUX_SCL_R1

R3601     	Q_RES_0402LF   	          	          	                    
          	               	1         	171B3     	SMB_INA230_1_3V3AUX_SDA_R
          	               	2         	171B3     	SMB_INA230_1_3V3AUX_SDA_R1

R3602     	Q_RES_0402LF   	          	          	                    
          	               	1         	171B3     	P3V3_OCP_SFF_R      
          	               	2         	171B3     	VSENSE_P3V3_INA230_1_INP

R3603     	Q_RES_0402LF   	          	          	                    
          	               	1         	171B3     	P3V3_OCP_SFF        
          	               	2         	171B3     	VSENSE_P3V3_INA230_1_INN

R3608     	Q_RES_0402LF   	          	          	                    
          	               	1         	172B3     	GND                 
          	               	2         	172B3     	INA230_3_A1         

R3609     	Q_RES_0402LF   	          	          	                    
          	               	1         	172B3     	GND                 
          	               	2         	172B3     	INA230_3_A0         

R3610     	Q_RES_0402LF   	          	          	                    
          	               	1         	172B4     	GND                 
          	               	2         	172B4     	INA230_4_A1         

R3611     	Q_RES_0402LF   	          	          	                    
          	               	1         	172B4     	GND                 
          	               	2         	172B4     	INA230_4_A0         

R3612     	Q_RES_0402LF   	          	          	                    
          	               	1         	172A4     	GND                 
          	               	2         	172A4     	INA230_5_A1         

R3613     	Q_RES_0402LF   	          	          	                    
          	               	1         	172A4     	GND                 
          	               	2         	172A4     	INA230_5_A0         

R3616     	Q_RES_0402LF   	          	          	                    
          	               	1         	171B4     	GND                 
          	               	2         	171B4     	INA230_1_A1         

R3617     	Q_RES_0402LF   	          	          	                    
          	               	1         	171B4     	GND                 
          	               	2         	171B4     	INA230_1_A0         

R3620     	Q_RES_0402LF   	          	          	                    
          	               	1         	172B3     	INA230_3_A0         
          	               	2         	172B3     	SMB_INA230_3_3V3AUX_SCL_R1

R3621     	Q_RES_0402LF   	          	          	                    
          	               	1         	172B3     	P3V3_AUX            
          	               	2         	172B3     	INA230_4_A0         

R3622     	Q_RES_0402LF   	          	          	                    
          	               	1         	172A3     	P3V3_AUX            
          	               	2         	172A3     	INA230_5_A0         

R3623     	Q_RES_0402LF   	          	          	                    
          	               	1         	172B3     	P3V3_AUX            
          	               	2         	172B3     	INA230_4_A1         

R3624     	Q_RES_0402LF   	          	          	                    
          	               	1         	172A3     	P3V3_AUX            
          	               	2         	172A3     	INA230_5_A1         

R3627     	Q_RES_0402LF   	          	          	                    
          	               	1         	171B3     	P3V3_AUX            
          	               	2         	171B3     	INA230_1_A0         

R3628     	Q_RES_0402LF   	          	          	                    
          	               	1         	171B3     	P3V3_AUX            
          	               	2         	171B3     	INA230_1_A1         

R3630     	Q_RES_0402LF   	          	          	                    
          	               	1         	163A4     	HP_LVC3_OCP_V3_2_EN 
          	               	2         	163A4     	P12V_OCP_V3_2_EN_2_R3

R3631     	Q_RES_0402LF   	          	          	                    
          	               	1         	163B2     	HP_LVC3_OCP_V3_2_EN 
          	               	2         	163B2     	P3V3_OCP_EN_2       

R3633     	Q_RES_2512LF   	          	          	                    
          	               	1         	172B4     	P3V3_OCP_V3_2       
          	               	2         	172B4     	P3V3_OCP_V3_2_R     

R3634     	Q_RES_2512LF   	          	          	                    
          	               	1         	172B4     	P3V3_M2_0           
          	               	2         	172B4     	P3V3                

R3635     	Q_RES_2512LF   	          	          	                    
          	               	1         	172A4     	P12V_SCM            
          	               	2         	172A4     	P12V_SCM_R          

R3636     	Q_RES_0402LF   	          	          	                    
          	               	1         	206B3     	OCP_SFF_CLK_OE_N    
          	               	2         	206B3     	FM_DB2000_11_OE_N   

R3637     	Q_RES_0402LF   	          	          	                    
          	               	1         	206B3     	OCP_SFF_CLK_OE_N    
          	               	2         	206B3     	FM_DB2000_12_OE_N   

R3638     	Q_RES_0402LF   	          	          	                    
          	               	1         	208A4     	P3V3_AUX            
          	               	2         	208A3     	CK440Q_OE_1         

R3639     	Q_RES_0402LF   	          	          	                    
          	               	1         	208A4     	P3V3_AUX            
          	               	2         	208A3     	CK440Q_OE_2         

R3640     	Q_RES_0402LF   	          	          	                    
          	               	1         	208A4     	P3V3_AUX            
          	               	2         	208A3     	CK440Q_OE_3         

R3641     	Q_RES_0402LF   	          	          	                    
          	               	1         	208A4     	P3V3_AUX            
          	               	2         	208A3     	CK440Q_OE_4         

R3642     	Q_RES_0402LF   	          	          	                    
          	               	1         	208A4     	P3V3_AUX            
          	               	2         	208A3     	CK440Q_OE_5         

R3643     	Q_RES_0402LF   	          	          	                    
          	               	1         	208A4     	P3V3_AUX            
          	               	2         	208A3     	CK440Q_OE_6         

R3645     	Q_RES_2512LF   	          	          	                    
          	               	1         	171B4     	P3V3_OCP_SFF        
          	               	2         	171B4     	P3V3_OCP_SFF_R      

R3651     	Q_RES_0402LF   	          	          	                    
          	               	1         	152B2     	USB2_P0_R_DP        
          	               	2         	152B2     	USB2_HOST_BMC_B_DP  

R3652     	Q_RES_0402LF   	          	          	                    
          	               	1         	152B2     	USB2_P0_R_DN        
          	               	2         	152B2     	USB2_HOST_BMC_B_DN  

R3653     	Q_RES_0402LF   	          	          	                    
          	               	1         	152B3     	USB_HUB_RREF        
          	               	2         	152B3     	GND                 

R3654     	Q_RES_0402LF   	          	          	                    
          	               	1         	152B4     	RST_USB_HUB_N       
          	               	2         	152B4     	RST_USB_HUB_R_N     

R3655     	Q_RES_0402LF   	          	          	                    
          	               	1         	152B4     	P3V3_AUX            
          	               	2         	152B4     	P3V3_AUX_USB_HUB    

R3656     	Q_RES_0402LF   	          	          	                    
          	               	1         	152B4     	P3V3_AUX            
          	               	2         	152B4     	USB_HUB_OVCUR1      

R3657     	Q_RES_0402LF   	          	          	                    
          	               	1         	152B4     	P3V3_AUX            
          	               	2         	152B4     	USB_HUB_OVCUR2      

R3658     	Q_RES_0402LF   	          	          	                    
          	               	1         	152B4     	P3V3_AUX            
          	               	2         	152B4     	USB_HUB_OVCUR3      

R3659     	Q_RES_0402LF   	          	          	                    
          	               	1         	152B4     	P3V3_AUX            
          	               	2         	152B4     	USB_HUB_OVCUR4      

R3660     	Q_RES_0402LF   	          	          	                    
          	               	1         	152B4     	P3V3_AUX            
          	               	2         	152B4     	RST_USB_HUB_R_N     

R3661     	Q_RES_0402LF   	          	          	                    
          	               	1         	152B4     	GND                 
          	               	2         	152B4     	RST_USB_HUB_R_N     

R3662     	Q_RES_0402LF   	          	          	                    
          	               	1         	152B3     	P3V3_AUX_USB_HUB    
          	               	2         	152B3     	USB_HUB_DVDD        

R3663     	Q_RES_0402LF   	          	          	                    
          	               	1         	152B4     	P3V3_AUX            
          	               	2         	152B4     	USB_HUB_PSELF       

R3664     	Q_RES_0402LF   	          	          	                    
          	               	1         	152B4     	USB_HUB_PSELF       
          	               	2         	152B4     	GND                 

R3665     	Q_RES_0402LF   	          	          	                    
          	               	1         	152B3     	USB_HUB_PGANG       
          	               	2         	152B3     	GND                 

R3666     	Q_RES_0402LF   	          	          	                    
          	               	1         	152B2     	USB_HUB_TEST        
          	               	2         	152B2     	GND                 

R3667     	Q_RES_0402LF   	          	          	                    
          	               	1         	250A3     	P3V3_AUX            
          	               	2         	250A3     	ADC128_A1           

R3668     	Q_RES_0402LF   	          	          	                    
          	               	1         	250A3     	ADC128_A1           
          	               	2         	250A3     	GND                 

R3669     	Q_RES_0402LF   	          	          	                    
          	               	1         	250A3     	P3V3_AUX            
          	               	2         	250A3     	ADC128_A0           

R3670     	Q_RES_0402LF   	          	          	                    
          	               	1         	250A3     	ADC128_A0           
          	               	2         	250A3     	GND                 

R3671     	Q_RES_0402LF   	          	          	                    
          	               	1         	250A1     	SMB_VR_3V3AUX_SDA_R1
          	               	2         	250A1     	SMB_SEN_TIC_3V3AUX_SDA

R3672     	Q_RES_0402LF   	          	          	                    
          	               	1         	250A1     	SMB_VR_3V3AUX_SCL_R1
          	               	2         	250A1     	SMB_SEN_TIC_3V3AUX_SCL

R3679     	Q_RES_0402LF   	          	          	                    
          	               	1         	250A4     	P12V_AUX_ADC        
          	               	2         	250A4     	P12V_AUX_ADC_MAM    

R3680     	Q_RES_0402LF   	          	          	                    
          	               	1         	250A4     	P12V_AUX_ADC        
          	               	2         	250A4     	P12V_AUX_ADC_TIC    

R3681     	Q_RES_0402LF   	          	          	                    
          	               	1         	250B4     	P3V3_AUX_ADC        
          	               	2         	250B4     	P3V3_AUX_ADC_MAM    

R3682     	Q_RES_0402LF   	          	          	                    
          	               	1         	250B4     	P3V3_AUX_ADC        
          	               	2         	250B4     	P3V3_AUX_ADC_TIC    

R3683     	Q_RES_0402LF   	          	          	                    
          	               	1         	250B4     	P3V3_ADC            
          	               	2         	250B4     	P3V3_ADC_MAM        

R3684     	Q_RES_0402LF   	          	          	                    
          	               	1         	250B4     	P3V3_ADC            
          	               	2         	250B4     	P3V3_ADC_TIC        

R3685     	Q_RES_0402LF   	          	          	                    
          	               	1         	250B4     	P5V_ADC             
          	               	2         	250B4     	P5V_ADC_MAM         

R3686     	Q_RES_0402LF   	          	          	                    
          	               	1         	250B4     	P5V_ADC             
          	               	2         	250B4     	P5V_ADC_TIC         

R3687     	Q_RES_0402LF   	          	          	                    
          	               	1         	250A4     	P1V581_PDB_ADC      
          	               	2         	250A4     	P3V3_PDB_AUX_ADC_MAM

R3688     	Q_RES_0402LF   	          	          	                    
          	               	1         	250A4     	P1V581_PDB_ADC      
          	               	2         	250A4     	P3V3_PDB_AUX_ADC_TIC

R3689     	Q_RES_0402LF   	          	          	                    
          	               	1         	250B2     	P3V3_ADC128_VCC     
          	               	2         	250A2     	ADC128_VREF         

R3690     	Q_RES_0402LF   	          	          	                    
          	               	1         	250A2     	ADC128_VREF         
          	               	2         	250A2     	GND                 

R3703     	Q_RES_0402LF   	          	          	                    
          	               	1         	233B4     	P3V3_AUX            
          	               	2         	233B4     	PCA9548_PCIE0_ADDR2 

R3704     	Q_RES_0402LF   	          	          	                    
          	               	1         	233A4     	PCA9548_PCIE0_ADDR2 
          	               	2         	233A4     	GND                 

R3705     	Q_RES_0402LF   	          	          	                    
          	               	1         	233B4     	P3V3_AUX            
          	               	2         	233B4     	RST_SMB_SWITCH_N    

R3706     	Q_RES_0402LF   	          	          	                    
          	               	1         	233B4     	P3V3_AUX            
          	               	2         	233B4     	PCA9548_PCIE0_ADDR1 

R3707     	Q_RES_0402LF   	          	          	                    
          	               	1         	233A4     	PCA9548_PCIE0_ADDR1 
          	               	2         	233A4     	GND                 

R3708     	Q_RES_0402LF   	          	          	                    
          	               	1         	233B4     	P3V3_AUX            
          	               	2         	233B4     	PCA9548_PCIE0_ADDR0 

R3709     	Q_RES_0402LF   	          	          	                    
          	               	1         	233A4     	PCA9548_PCIE0_ADDR0 
          	               	2         	233A4     	GND                 

R3710     	Q_RES_0402LF   	          	          	                    
          	               	1         	233B3     	RST_SMB_SWITCH_N    
          	               	2         	233B3     	PU_RST_SMB_PCIE2_N  

R3711     	Q_RES_0402LF   	          	          	                    
          	               	1         	233B2     	SMB_VR_SENSOR_3V3AUX_SCL
          	               	2         	233B2     	SMB_VR_SENSOR_3V3AUX_SCL_R

R3712     	Q_RES_0402LF   	          	          	                    
          	               	1         	233B2     	SMB_VR_SENSOR_3V3AUX_SDA
          	               	2         	233B2     	SMB_VR_SENSOR_3V3AUX_SDA_R

R3713     	Q_RES_0402LF   	          	          	                    
          	               	1         	233B3     	SMB_VR_3V3AUX_SCL_R6
          	               	2         	233B3     	SMB_VR_3V3AUX_SCL   

R3714     	Q_RES_0402LF   	          	          	                    
          	               	1         	233B3     	SMB_VR_3V3AUX_SDA_R6
          	               	2         	233B3     	SMB_VR_3V3AUX_SDA   

R3715     	Q_RES_0402LF   	          	          	                    
          	               	1         	233B3     	SMB_LM75_0_3V3AUX_SCL_R
          	               	2         	233B3     	SMB_LM75_0_3V3AUX_SCL

R3716     	Q_RES_0402LF   	          	          	                    
          	               	1         	233B3     	SMB_LM75_0_3V3AUX_SDA_R
          	               	2         	233B3     	SMB_LM75_0_3V3AUX_SDA

R3717     	Q_RES_0402LF   	          	          	                    
          	               	1         	233B3     	SMB_LM75_1_3V3AUX_SCL_R
          	               	2         	233B3     	SMB_LM75_1_3V3AUX_SCL

R3718     	Q_RES_0402LF   	          	          	                    
          	               	1         	233B3     	SMB_LM75_1_3V3AUX_SDA_R
          	               	2         	233B3     	SMB_LM75_1_3V3AUX_SDA

R3719     	Q_RES_0402LF   	          	          	                    
          	               	1         	233B3     	SMB_LM75_2_3V3AUX_SCL_R
          	               	2         	233B3     	SMB_LM75_2_3V3AUX_SCL

R3720     	Q_RES_0402LF   	          	          	                    
          	               	1         	233B3     	SMB_LM75_2_3V3AUX_SDA_R
          	               	2         	233B3     	SMB_LM75_2_3V3AUX_SDA

R3721     	Q_RES_0402LF   	          	          	                    
          	               	1         	233B2     	SMB_LM75_3_3V3AUX_SCL_R
          	               	2         	233B2     	SMB_LM75_3_3V3AUX_SCL

R3722     	Q_RES_0402LF   	          	          	                    
          	               	1         	233B2     	SMB_LM75_3_3V3AUX_SDA_R
          	               	2         	233B2     	SMB_LM75_3_3V3AUX_SDA

R3723     	Q_RES_0402LF   	          	          	                    
          	               	1         	233B2     	P3V3_AUX            
          	               	2         	233B2     	SMB_VR_3V3AUX_SCL   

R3724     	Q_RES_0402LF   	          	          	                    
          	               	1         	233B2     	P3V3_AUX            
          	               	2         	233B2     	SMB_VR_3V3AUX_SDA   

R3725     	Q_RES_0402LF   	          	          	                    
          	               	1         	233B2     	P3V3_AUX            
          	               	2         	233B2     	SMB_LM75_0_3V3AUX_SCL

R3726     	Q_RES_0402LF   	          	          	                    
          	               	1         	233B2     	P3V3_AUX            
          	               	2         	233B2     	SMB_LM75_0_3V3AUX_SDA

R3727     	Q_RES_0402LF   	          	          	                    
          	               	1         	233B2     	P3V3_AUX            
          	               	2         	233B2     	SMB_LM75_1_3V3AUX_SCL

R3728     	Q_RES_0402LF   	          	          	                    
          	               	1         	233A2     	P3V3_AUX            
          	               	2         	233A2     	SMB_LM75_1_3V3AUX_SDA

R3729     	Q_RES_0402LF   	          	          	                    
          	               	1         	233A2     	P3V3_AUX            
          	               	2         	233A2     	SMB_LM75_2_3V3AUX_SCL

R3730     	Q_RES_0402LF   	          	          	                    
          	               	1         	233A2     	P3V3_AUX            
          	               	2         	233A2     	SMB_LM75_2_3V3AUX_SDA

R3731     	Q_RES_0402LF   	          	          	                    
          	               	1         	233A2     	P3V3_AUX            
          	               	2         	233A2     	SMB_LM75_3_3V3AUX_SCL

R3732     	Q_RES_0402LF   	          	          	                    
          	               	1         	233A2     	P3V3_AUX            
          	               	2         	233A2     	SMB_LM75_3_3V3AUX_SDA

R3751     	Q_RES_0402LF   	          	          	                    
          	               	1         	171B3     	INA230_2_A0         
          	               	2         	171A3     	SMB_INA230_2_3V3AUX_SDA_R1

R3752     	Q_RES_0402LF   	          	          	                    
          	               	1         	171A2     	E1S_0_P3V3_ADC_ALERT_R
          	               	2         	171A2     	E1S_0_P3V3_ADC_ALERT

R3754     	Q_RES_0402LF   	          	          	                    
          	               	1         	171A3     	SMB_INA230_2_3V3AUX_SCL_R
          	               	2         	171A3     	SMB_INA230_2_3V3AUX_SCL_R1

R3756     	Q_RES_0402LF   	          	          	                    
          	               	1         	171A3     	SMB_INA230_2_3V3AUX_SDA_R
          	               	2         	171A3     	SMB_INA230_2_3V3AUX_SDA_R1

R3758     	Q_RES_0402LF   	          	          	                    
          	               	1         	171A3     	P3V3_E1S_0_R        
          	               	2         	171A3     	VSENSE_P3V3_INA230_2_INP

R3760     	Q_RES_0402LF   	          	          	                    
          	               	1         	171A3     	P3V3_E1S_0          
          	               	2         	171A3     	VSENSE_P3V3_INA230_2_INN

R3763     	Q_RES_0402LF   	          	          	                    
          	               	1         	171B4     	GND                 
          	               	2         	171B4     	INA230_2_A1         

R3764     	Q_RES_0402LF   	          	          	                    
          	               	1         	171B4     	GND                 
          	               	2         	171B4     	INA230_2_A0         

R3767     	Q_RES_2512LF   	          	          	                    
          	               	1         	171A4     	P3V3_E1S_0          
          	               	2         	171A4     	P3V3_E1S_0_R        

R3770     	Q_RES_0402LF   	          	          	                    
          	               	1         	246B4     	GPU_PRSNT           
          	               	2         	246B4     	GPU_PRSNT_R         

R3771     	Q_RES_0402LF   	          	          	                    
          	               	1         	191B4     	P3V3_AUX            
          	               	2         	191B4     	E1S_0_PWRDIS        

R3772     	Q_RES_0402LF   	          	          	                    
          	               	1         	191A2     	RST_SMB_BUF_E1S_0_N 
          	               	2         	191A2     	RST_SMB_E1S_0_N     

R3773     	Q_RES_0402LF   	          	          	                    
          	               	1         	191A2     	P3V3_AUX            
          	               	2         	191A2     	RST_SMB_E1S_0_N     

R3775     	Q_RES_0402LF   	          	          	                    
          	               	1         	191A4     	RST_SMB_SWITCH_N    
          	               	2         	191A3     	RST_SMB_E1S_N       

R3776     	Q_RES_0402LF   	          	          	                    
          	               	1         	240A4     	FM_UARTSW_MSB_N     
          	               	2         	240A4     	FM_UARTSW_MSB_R     

R3777     	Q_RES_0402LF   	          	          	                    
          	               	1         	240A4     	FM_UARTSW_LSB_N     
          	               	2         	240A4     	FM_UARTSW_LSB_R     

R3778     	Q_RES_0402LF   	          	          	                    
          	               	1         	240B1     	FM_SOL_UART_CH_SEL_R
          	               	2         	240B1     	FM_SOL_UART_CH_SEL  

R3779     	Q_RES_0402LF   	          	          	                    
          	               	1         	191B4     	RST_PCIE_PCH_DEV_PERST_E1S_R_N
          	               	2         	191B4     	RST_PCIE_PCH_E1S_PERST_N

R3783     	Q_RES_0402LF   	          	          	                    
          	               	1         	156B1     	P3V3_AUX            
          	               	2         	156B1     	OCP_V3_1_P3V3_PWRGD 

R3784     	Q_RES_0402LF   	          	          	                    
          	               	1         	156B3     	P12V_OCP_UV_1_R     
          	               	2         	156B3     	P12V_OCP_UV_1       

R3785     	Q_RES_0402LF   	          	          	                    
          	               	1         	156B3     	P3V3_OCP_UV_1_R1    
          	               	2         	156B3     	P3V3_OCP_UV_1       

R3794     	Q_RES_0402LF   	          	          	                    
          	               	1         	156B1     	P3V3_OCP_PWRGD_1    
          	               	2         	156B1     	OCP_V3_1_P3V3_PWRGD 

R3796     	Q_RES_0402LF   	          	          	                    
          	               	1         	156B1     	P3V3_AUX            
          	               	2         	156B1     	P3V3_OCP_FAULT_1    

R3797     	Q_RES_0402LF   	          	          	                    
          	               	1         	156B1     	P3V3_AUX            
          	               	2         	156B1     	HP_LVC3_OCP_V3_1_P12V_PWRGD

R3799     	Q_RES_0402LF   	          	          	                    
          	               	1         	156B1     	P3V3_AUX            
          	               	2         	156B1     	P12V_OCP_FAULT_1    

R3807     	Q_RES_0402LF   	          	          	                    
          	               	1         	162B3     	P3V3_OCP_UV_2_R1    
          	               	2         	162B3     	P3V3_OCP_UV_2       

R3816     	Q_RES_0402LF   	          	          	                    
          	               	1         	162B1     	P3V3_AUX            
          	               	2         	162B1     	P12V_OCP_FAULT_2    

R3825     	Q_RES_0402LF   	          	          	                    
          	               	1         	162B1     	P3V3_AUX            
          	               	2         	162B1     	HP_LVC3_OCP_V3_2_P12V_PWRGD

R3826     	Q_RES_0402LF   	          	          	                    
          	               	1         	162B1     	P3V3_AUX            
          	               	2         	162B1     	OCP_V3_2_P3V3_PWRGD 

R3827     	Q_RES_0402LF   	          	          	                    
          	               	1         	162B3     	P12V_OCP_UV_2_R     
          	               	2         	162B3     	P12V_OCP_UV_2       

R3831     	Q_RES_0402LF   	          	          	                    
          	               	1         	162B1     	P12V_OCP_PWRGD_2    
          	               	2         	162B1     	HP_LVC3_OCP_V3_2_P12V_PWRGD

R3832     	Q_RES_0402LF   	          	          	                    
          	               	1         	162B1     	P3V3_OCP_PWRGD_2    
          	               	2         	162B1     	OCP_V3_2_P3V3_PWRGD 

R3833     	Q_RES_0402LF   	          	          	                    
          	               	1         	162B1     	P3V3_AUX            
          	               	2         	162B1     	P3V3_OCP_FAULT_2    

R3834     	Q_RES_0402LF   	          	          	                    
          	               	1         	157A4     	HP_LVC3_OCP_V3_1_EN 
          	               	2         	157A4     	P12V_OCP_EN_1_R2    

R3836     	Q_RES_0402LF   	          	          	                    
          	               	1         	242B2     	P3V3_AUX            
          	               	2         	242B2     	HP_LVC3_SCM_HSC_PWRGD_R

R3845     	Q_RES_0402LF   	          	          	                    
          	               	1         	157B2     	HP_LVC3_OCP_V3_1_EN 
          	               	2         	157B2     	P3V3_OCP_EN_1_R2    

R3848     	Q_RES_0402LF   	          	          	                    
          	               	1         	163A3     	P3V3_AUX            
          	               	2         	163A3     	HP_LVC3_OCP_V3_2_P12V_PWRGD

R3858     	Q_RES_0402LF   	          	          	                    
          	               	1         	240B4     	SMB_OCP_V3_2_3V3AUX_SDA
          	               	2         	240B4     	SMB_OCP_V3_2_3V3AUX_SDA_R0

R3859     	Q_RES_0402LF   	          	          	                    
          	               	1         	250B3     	P12V_OCP_V3_2_ISENSE_MAM_MAM
          	               	2         	250B3     	P12V_OCP_V3_2_ISENSE_MAM

R3860     	Q_RES_0402LF   	          	          	                    
          	               	1         	250B3     	P12V_OCP_V3_2_ISENSE_MPS_MAM
          	               	2         	250B3     	P12V_OCP_V3_2_ISENSE_MAM

R3861     	Q_RES_0402LF   	          	          	                    
          	               	1         	250B3     	P12V_OCP_V3_2_ISENSE_MAM_TIC
          	               	2         	250B3     	P12V_OCP_V3_2_ISENSE_TIC

R3862     	Q_RES_0402LF   	          	          	                    
          	               	1         	250B3     	P12V_OCP_V3_2_ISENSE_MPS_TIC
          	               	2         	250B3     	P12V_OCP_V3_2_ISENSE_TIC

R3863     	Q_RES_0402LF   	          	          	                    
          	               	1         	250B3     	P12V_OCP_SFF_ISENSE_MAM_MAM
          	               	2         	250B3     	P12V_OCP_SFF_ISENSE_MAM

R3864     	Q_RES_0402LF   	          	          	                    
          	               	1         	250B3     	P12V_OCP_SFF_ISENSE_MPS_MAM
          	               	2         	250B3     	P12V_OCP_SFF_ISENSE_MAM

R3865     	Q_RES_0402LF   	          	          	                    
          	               	1         	250B3     	P12V_OCP_SFF_ISENSE_MAM_TIC
          	               	2         	250B3     	P12V_OCP_SFF_ISENSE_TIC

R3866     	Q_RES_0402LF   	          	          	                    
          	               	1         	250B3     	P12V_OCP_SFF_ISENSE_MPS_TIC
          	               	2         	250B3     	P12V_OCP_SFF_ISENSE_TIC

R3867     	Q_RES_0402LF   	          	          	                    
          	               	1         	162B1     	P12V_OCP_SENSE_2    
          	               	2         	162B1     	P12V_OCP_V3_2_ISENSE_MAM_MAM

R3868     	Q_RES_0402LF   	          	          	                    
          	               	1         	162B1     	P12V_OCP_SENSE_2    
          	               	2         	162B1     	P12V_OCP_V3_2_ISENSE_MAM_TIC

R3869     	Q_RES_0402LF   	          	          	                    
          	               	1         	156B1     	P12V_OCP_SENSE_1    
          	               	2         	156B1     	P12V_OCP_SFF_ISENSE_MAM_MAM

R3870     	Q_RES_0402LF   	          	          	                    
          	               	1         	156B1     	P12V_OCP_SENSE_1    
          	               	2         	156B1     	P12V_OCP_SFF_ISENSE_MAM_TIC

R3871     	Q_RES_0402LF   	          	          	                    
          	               	1         	157A2     	P12V_OCP_IMON_1     
          	               	2         	157A2     	P12V_OCP_SFF_ISENSE_MPS_MAM

R3872     	Q_RES_0402LF   	          	          	                    
          	               	1         	157A2     	P12V_OCP_IMON_1     
          	               	2         	157A2     	P12V_OCP_SFF_ISENSE_MPS_TIC

R3873     	Q_RES_0402LF   	          	          	                    
          	               	1         	163A2     	P12V_OCP_IMON_2     
          	               	2         	163A2     	P12V_OCP_V3_2_ISENSE_MPS_MAM

R3874     	Q_RES_0402LF   	          	          	                    
          	               	1         	163A2     	P12V_OCP_IMON_2     
          	               	2         	163A2     	P12V_OCP_V3_2_ISENSE_MPS_TIC

R3875     	Q_RES_0402LF   	          	          	                    
          	               	1         	82B4      	I3C_SPD_DDRABCD_CPU0_LVC1_SCL_R
          	               	2         	82B4      	I3C_SPD_DDRABCD_CPU0_LVC1_SCL

R3876     	Q_RES_0402LF   	          	          	                    
          	               	1         	83B4      	I3C_SPD_DDRABCD_CPU0_LVC1_SCL_1
          	               	2         	83B4      	I3C_SPD_DDRABCD_CPU0_LVC1_SCL

R3877     	Q_RES_0402LF   	          	          	                    
          	               	1         	84B4      	I3C_SPD_DDRABCD_CPU0_LVC1_SCL_2
          	               	2         	84B4      	I3C_SPD_DDRABCD_CPU0_LVC1_SCL

R3878     	Q_RES_0402LF   	          	          	                    
          	               	1         	85B4      	I3C_SPD_DDRABCD_CPU0_LVC1_SCL_3
          	               	2         	85B4      	I3C_SPD_DDRABCD_CPU0_LVC1_SCL

R3879     	Q_RES_0402LF   	          	          	                    
          	               	1         	86B4      	I3C_SPD_DDRABCD_CPU0_LVC1_SCL_4
          	               	2         	86B4      	I3C_SPD_DDRABCD_CPU0_LVC1_SCL

R3880     	Q_RES_0402LF   	          	          	                    
          	               	1         	87B4      	I3C_SPD_DDRABCD_CPU0_LVC1_SCL_5
          	               	2         	87B4      	I3C_SPD_DDRABCD_CPU0_LVC1_SCL

R3881     	Q_RES_0402LF   	          	          	                    
          	               	1         	88B4      	I3C_SPD_DDRABCD_CPU0_LVC1_SCL_6
          	               	2         	88B4      	I3C_SPD_DDRABCD_CPU0_LVC1_SCL

R3882     	Q_RES_0402LF   	          	          	                    
          	               	1         	89B4      	I3C_SPD_DDRABCD_CPU0_LVC1_SCL_7
          	               	2         	89B4      	I3C_SPD_DDRABCD_CPU0_LVC1_SCL

R3883     	Q_RES_0402LF   	          	          	                    
          	               	1         	90B4      	I3C_SPD_DDREFGH_CPU0_LVC1_SCL_R
          	               	2         	90B4      	I3C_SPD_DDREFGH_CPU0_LVC1_SCL

R3884     	Q_RES_0402LF   	          	          	                    
          	               	1         	91B4      	I3C_SPD_DDREFGH_CPU0_LVC1_SCL_1
          	               	2         	91B4      	I3C_SPD_DDREFGH_CPU0_LVC1_SCL

R3885     	Q_RES_0402LF   	          	          	                    
          	               	1         	92B4      	I3C_SPD_DDREFGH_CPU0_LVC1_SCL_2
          	               	2         	92B4      	I3C_SPD_DDREFGH_CPU0_LVC1_SCL

R3886     	Q_RES_0402LF   	          	          	                    
          	               	1         	93B4      	I3C_SPD_DDREFGH_CPU0_LVC1_SCL_3
          	               	2         	93B4      	I3C_SPD_DDREFGH_CPU0_LVC1_SCL

R3887     	Q_RES_0402LF   	          	          	                    
          	               	1         	94B4      	I3C_SPD_DDREFGH_CPU0_LVC1_SCL_4
          	               	2         	94B4      	I3C_SPD_DDREFGH_CPU0_LVC1_SCL

R3888     	Q_RES_0402LF   	          	          	                    
          	               	1         	95B4      	I3C_SPD_DDREFGH_CPU0_LVC1_SCL_5
          	               	2         	95B4      	I3C_SPD_DDREFGH_CPU0_LVC1_SCL

R3889     	Q_RES_0402LF   	          	          	                    
          	               	1         	96B4      	I3C_SPD_DDREFGH_CPU0_LVC1_SCL_6
          	               	2         	96B4      	I3C_SPD_DDREFGH_CPU0_LVC1_SCL

R3890     	Q_RES_0402LF   	          	          	                    
          	               	1         	97B4      	I3C_SPD_DDREFGH_CPU0_LVC1_SCL_7
          	               	2         	97B4      	I3C_SPD_DDREFGH_CPU0_LVC1_SCL

R3891     	Q_RES_0402LF   	          	          	                    
          	               	1         	98B4      	I3C_SPD_DDRABCD_CPU1_LVC1_SCL_R
          	               	2         	98B4      	I3C_SPD_DDRABCD_CPU1_LVC1_SCL

R3892     	Q_RES_0402LF   	          	          	                    
          	               	1         	99B4      	I3C_SPD_DDRABCD_CPU1_LVC1_SCL_1
          	               	2         	99B4      	I3C_SPD_DDRABCD_CPU1_LVC1_SCL

R3893     	Q_RES_0402LF   	          	          	                    
          	               	1         	100B4     	I3C_SPD_DDRABCD_CPU1_LVC1_SCL_2
          	               	2         	100B4     	I3C_SPD_DDRABCD_CPU1_LVC1_SCL

R3894     	Q_RES_0402LF   	          	          	                    
          	               	1         	101B4     	I3C_SPD_DDRABCD_CPU1_LVC1_SCL_3
          	               	2         	101B4     	I3C_SPD_DDRABCD_CPU1_LVC1_SCL

R3895     	Q_RES_0402LF   	          	          	                    
          	               	1         	102B4     	I3C_SPD_DDRABCD_CPU1_LVC1_SCL_4
          	               	2         	102B4     	I3C_SPD_DDRABCD_CPU1_LVC1_SCL

R3896     	Q_RES_0402LF   	          	          	                    
          	               	1         	103B4     	I3C_SPD_DDRABCD_CPU1_LVC1_SCL_5
          	               	2         	103B4     	I3C_SPD_DDRABCD_CPU1_LVC1_SCL

R3897     	Q_RES_0402LF   	          	          	                    
          	               	1         	104B4     	I3C_SPD_DDRABCD_CPU1_LVC1_SCL_6
          	               	2         	104B4     	I3C_SPD_DDRABCD_CPU1_LVC1_SCL

R3898     	Q_RES_0402LF   	          	          	                    
          	               	1         	105B4     	I3C_SPD_DDRABCD_CPU1_LVC1_SCL_7
          	               	2         	105B4     	I3C_SPD_DDRABCD_CPU1_LVC1_SCL

R3899     	Q_RES_0402LF   	          	          	                    
          	               	1         	106B4     	I3C_SPD_DDREFGH_CPU1_LVC1_SCL_R
          	               	2         	106B4     	I3C_SPD_DDREFGH_CPU1_LVC1_SCL

R3900     	Q_RES_0402LF   	          	          	                    
          	               	1         	107B4     	I3C_SPD_DDREFGH_CPU1_LVC1_SCL_1
          	               	2         	107B4     	I3C_SPD_DDREFGH_CPU1_LVC1_SCL

R3901     	Q_RES_0402LF   	          	          	                    
          	               	1         	108B4     	I3C_SPD_DDREFGH_CPU1_LVC1_SCL_2
          	               	2         	108B4     	I3C_SPD_DDREFGH_CPU1_LVC1_SCL

R3902     	Q_RES_0402LF   	          	          	                    
          	               	1         	109B4     	I3C_SPD_DDREFGH_CPU1_LVC1_SCL_3
          	               	2         	109B4     	I3C_SPD_DDREFGH_CPU1_LVC1_SCL

R3903     	Q_RES_0402LF   	          	          	                    
          	               	1         	110B4     	I3C_SPD_DDREFGH_CPU1_LVC1_SCL_4
          	               	2         	110B4     	I3C_SPD_DDREFGH_CPU1_LVC1_SCL

R3904     	Q_RES_0402LF   	          	          	                    
          	               	1         	111B4     	I3C_SPD_DDREFGH_CPU1_LVC1_SCL_5
          	               	2         	111B4     	I3C_SPD_DDREFGH_CPU1_LVC1_SCL

R3905     	Q_RES_0402LF   	          	          	                    
          	               	1         	112B4     	I3C_SPD_DDREFGH_CPU1_LVC1_SCL_6
          	               	2         	112B4     	I3C_SPD_DDREFGH_CPU1_LVC1_SCL

R3906     	Q_RES_0402LF   	          	          	                    
          	               	1         	113B4     	I3C_SPD_DDREFGH_CPU1_LVC1_SCL_7
          	               	2         	113B4     	I3C_SPD_DDREFGH_CPU1_LVC1_SCL

R3907     	Q_RES_0402LF   	          	          	                    
          	               	1         	301A4     	PDB_PRSNT_N         
          	               	2         	301A4     	GND                 

R3909     	Q_RES_0402LF   	          	          	                    
          	               	1         	301B4     	SMB_SML1_PMBUS_HSC_SCL
          	               	2         	301B4     	SMB_SML1_PMBUS_HSC_L_SCL

R3923     	Q_RES_0402LF   	          	          	                    
          	               	1         	301A4     	P12V_PSU_FUSE       
          	               	2         	301A4     	PDB_PRSNT_N         

R3924     	Q_RES_0402LF   	          	          	                    
          	               	1         	301B4     	IRQ_SML1_PMBUS_ALERT_N
          	               	2         	301B4     	IRQ_SML1_PMBUS_ALERT

R3925     	Q_RES_0402LF   	          	          	                    
          	               	1         	301B4     	IRQ_SML1_PMBUS_ALERT
          	               	2         	301B4     	P3V3_AUX            

R3933     	Q_RES_0402LF   	          	          	                    
          	               	1         	301B2     	P12V_AUX            
          	               	2         	301B2     	MB0_P12V_STBY_PWRGD 

R3934     	Q_RES_0402LF   	          	          	                    
          	               	1         	301B2     	HSC_D_OC_R          
          	               	2         	301B1     	HSC_D_OC            

R3936     	Q_RES_0402LF   	          	          	                    
          	               	1         	301B1     	HSC_VDD             
          	               	2         	301B1     	HSC_D_OC            

R3938     	Q_RES_0402LF   	          	          	                    
          	               	1         	183A2     	PU_OC2_USB_N        
          	               	2         	183A1     	P3V3_AUX            

R3939     	Q_RES_0402LF   	          	          	                    
          	               	1         	250B3     	P12V_E1S_0_ISENSE_MAM_MAM
          	               	2         	250B3     	P12V_E1S_0_ISENSE_MAM

R3940     	Q_RES_0402LF   	          	          	                    
          	               	1         	250B3     	P12V_E1S_0_ISENSE_MPS_MAM
          	               	2         	250B3     	P12V_E1S_0_ISENSE_MAM

R3941     	Q_RES_0402LF   	          	          	                    
          	               	1         	250B3     	P12V_E1S_0_ISENSE_MAM_TIC
          	               	2         	250B3     	P12V_E1S_0_ISENSE_TIC

R3942     	Q_RES_0402LF   	          	          	                    
          	               	1         	250B3     	P12V_E1S_0_ISENSE_MPS_TIC
          	               	2         	250B3     	P12V_E1S_0_ISENSE_TIC

R3943     	Q_RES_0402LF   	          	          	                    
          	               	1         	193B4     	E1S_0_EN            
          	               	2         	193B3     	P12V_E1S_EN_0_R2    

R3946     	Q_RES_0402LF   	          	          	                    
          	               	1         	193A3     	E1S_0_EN            
          	               	2         	193A3     	P3V3_E1S_EN_0_R2    

R3948     	Q_RES_0402LF   	          	          	                    
          	               	1         	193B3     	P3V3_AUX            
          	               	2         	193B3     	HP_LVC3_E1S_0_HSC_PWRGD

R3955     	Q_RES_0402LF   	          	          	                    
          	               	1         	193B2     	P12V_E1S_IMON_0     
          	               	2         	193B2     	P12V_E1S_0_ISENSE_MPS_MAM

R3956     	Q_RES_0402LF   	          	          	                    
          	               	1         	193B2     	P12V_E1S_IMON_0     
          	               	2         	193B2     	P12V_E1S_0_ISENSE_MPS_TIC

R3958     	Q_RES_0402LF   	          	          	                    
          	               	1         	192B3     	P12V_E1S_UV_0_R     
          	               	2         	192B3     	P12V_E1S_UV_0       

R3959     	Q_RES_0402LF   	          	          	                    
          	               	1         	192A3     	P3V3_E1S_UV_0_R     
          	               	2         	192A3     	P3V3_E1S_UV_0       

R3972     	Q_RES_0402LF   	          	          	                    
          	               	1         	192B1     	P12V_E1S_PWRGD_0    
          	               	2         	192B1     	HP_LVC3_E1S_0_HSC_PWRGD

R3973     	Q_RES_0402LF   	          	          	                    
          	               	1         	192A1     	P3V3_E1S_PWRGD_0    
          	               	2         	192A1     	TP_P3V3_E1S_PWRGD_0 

R3974     	Q_RES_0402LF   	          	          	                    
          	               	1         	192B1     	P12V_E1S_SENSE_0    
          	               	2         	192B1     	P12V_E1S_0_ISENSE_MAM_MAM

R3975     	Q_RES_0402LF   	          	          	                    
          	               	1         	192B1     	P12V_E1S_SENSE_0    
          	               	2         	192B1     	P12V_E1S_0_ISENSE_MAM_TIC

R3976     	Q_RES_0402LF   	          	          	                    
          	               	1         	192B1     	P3V3_AUX            
          	               	2         	192B1     	P12V_E1S_FAULT_0    

R3977     	Q_RES_0402LF   	          	          	                    
          	               	1         	192A1     	P3V3_AUX            
          	               	2         	192A1     	P3V3_E1S_FAULT_0    

R3978     	Q_RES_0402LF   	          	          	                    
          	               	1         	192B1     	P3V3_AUX            
          	               	2         	192B1     	HP_LVC3_E1S_0_HSC_PWRGD

R3979     	Q_RES_0402LF   	          	          	                    
          	               	1         	192A1     	P3V3_AUX            
          	               	2         	192A1     	TP_P3V3_E1S_PWRGD_0 

R3996     	Q_RES_0402LF   	          	          	                    
          	               	1         	242B4     	VIRTUAL_RESEAT_FPGA_N
          	               	2         	242B4     	P12V_SCM_EN         

R3997     	Q_RES_0402LF   	          	          	                    
          	               	1         	242B3     	P12V_SCM_UV_R       
          	               	2         	242B3     	P12V_SCM_UV         

R3998     	Q_RES_0402LF   	          	          	                    
          	               	1         	242A3     	P12V_SCM_EN         
          	               	2         	242A3     	P12V_SCM_EN_R2      

R4013     	Q_RES_0402LF   	          	          	                    
          	               	1         	242B1     	P3V3_AUX            
          	               	2         	242B1     	P12V_SCM_FAULT_R_N  

R4015     	Q_RES_0402LF   	          	          	                    
          	               	1         	242B1     	P3V3_AUX            
          	               	2         	242B1     	HP_LVC3_SCM_HSC_PWRGD

R4016     	Q_RES_0402LF   	          	          	                    
          	               	1         	226B2     	P3V3                
          	               	2         	226B2     	P0V62_CPU0_ERRS_VREF

R4019     	Q_RES_0402LF   	          	          	                    
          	               	1         	226B2     	P0V62_CPU0_ERRS_VREF
          	               	2         	226B2     	GND                 

R4021     	Q_RES_0402LF   	          	          	                    
          	               	1         	226B2     	PWRGD_CPUPWRGD_LVC2_R
          	               	2         	226B2     	PWRGD_CPUPWRGD_LVC2_R1

R4022     	Q_RES_0402LF   	          	          	                    
          	               	1         	226B2     	H_CPU_RMCA_LVC2_R1_N
          	               	2         	226B2     	H_CPU_RMCA_LVC2_R2_N

R4023     	Q_RES_0402LF   	          	          	                    
          	               	1         	226B2     	H_CPU_CATERR_LVC2_R1_N
          	               	2         	226B2     	H_CPU_CATERR_LVC2_R2_N

R4029     	Q_RES_0402LF   	          	          	                    
          	               	1         	226B2     	PD_CPU0_ERRS_DIR    
          	               	2         	226B2     	GND                 

R4036     	Q_RES_0402LF   	          	          	                    
          	               	1         	225B2     	P3V3_AUX            
          	               	2         	225B2     	P0V62_CPU0_RST_DDR_VREF

R4037     	Q_RES_0402LF   	          	          	                    
          	               	1         	225B2     	P3V3_AUX            
          	               	2         	225B2     	P0V62_CPU1_RST_DDR_VREF

R4038     	Q_RES_0402LF   	          	          	                    
          	               	1         	225A2     	P3V3                
          	               	2         	225A2     	P0V62_CPU0_ERRS_U306_VREF

R4039     	Q_RES_0402LF   	          	          	                    
          	               	1         	225B2     	P0V62_CPU0_RST_DDR_VREF
          	               	2         	225B2     	GND                 

R4040     	Q_RES_0402LF   	          	          	                    
          	               	1         	225B2     	P0V62_CPU1_RST_DDR_VREF
          	               	2         	225B2     	GND                 

R4041     	Q_RES_0402LF   	          	          	                    
          	               	1         	225A2     	P0V62_CPU0_ERRS_U306_VREF
          	               	2         	225A2     	GND                 

R4042     	Q_RES_0402LF   	          	          	                    
          	               	1         	225B2     	RST_CPU0_DRAM_AB_PLD_LVT3_R_N
          	               	2         	225B2     	RST_CPU0_DRAM_AB_PLD_LVT3_N

R4043     	Q_RES_0402LF   	          	          	                    
          	               	1         	225B2     	RST_CPU0_DRAM_CD_PLD_LVT3_R_N
          	               	2         	225B2     	RST_CPU0_DRAM_CD_PLD_LVT3_N

R4044     	Q_RES_0402LF   	          	          	                    
          	               	1         	225B2     	RST_CPU0_DRAM_EF_PLD_LVT3_R_N
          	               	2         	225B2     	RST_CPU0_DRAM_EF_PLD_LVT3_N

R4045     	Q_RES_0402LF   	          	          	                    
          	               	1         	225B2     	RST_CPU0_DRAM_GH_PLD_LVT3_R_N
          	               	2         	225B2     	RST_CPU0_DRAM_GH_PLD_LVT3_N

R4046     	Q_RES_0402LF   	          	          	                    
          	               	1         	225B2     	RST_CPU1_DRAM_AB_PLD_LVT3_R_N
          	               	2         	225B2     	RST_CPU1_DRAM_AB_PLD_LVT3_N

R4047     	Q_RES_0402LF   	          	          	                    
          	               	1         	225B2     	RST_CPU1_DRAM_CD_PLD_LVT3_R_N
          	               	2         	225B2     	RST_CPU1_DRAM_CD_PLD_LVT3_N

R4048     	Q_RES_0402LF   	          	          	                    
          	               	1         	225B2     	RST_CPU1_DRAM_EF_PLD_LVT3_R_N
          	               	2         	225B2     	RST_CPU1_DRAM_EF_PLD_LVT3_N

R4049     	Q_RES_0402LF   	          	          	                    
          	               	1         	225B2     	RST_CPU1_DRAM_GH_PLD_LVT3_R_N
          	               	2         	225B2     	RST_CPU1_DRAM_GH_PLD_LVT3_N

R4050     	Q_RES_0402LF   	          	          	                    
          	               	1         	225A1     	H_CPU_ERR0_LVC2_R_N 
          	               	2         	225A1     	H_CPU_ERR0_LVC2_N   

R4051     	Q_RES_0402LF   	          	          	                    
          	               	1         	225A1     	H_CPU_ERR1_LVC2_R_N 
          	               	2         	225A1     	H_CPU_ERR1_LVC2_N   

R4052     	Q_RES_0402LF   	          	          	                    
          	               	1         	225A1     	H_CPU_ERR2_LVC2_R_N 
          	               	2         	225A1     	H_CPU_ERR2_LVC2_N   

R4053     	Q_RES_0402LF   	          	          	                    
          	               	1         	225B2     	PD_GTL2014_BMC_JTAG_DIR_0
          	               	2         	225B2     	GND                 

R4054     	Q_RES_0402LF   	          	          	                    
          	               	1         	225B2     	PD_GTL2014_BMC_JTAG_DIR_1
          	               	2         	225B2     	GND                 

R4055     	Q_RES_0402LF   	          	          	                    
          	               	1         	225A2     	PD_CPU1_ERRS_U306_DIR
          	               	2         	225A2     	GND                 

R4056     	Q_RES_0402LF   	          	          	                    
          	               	1         	215B4     	HSC_D_OC            
          	               	2         	215B4     	HSC_D_OC_R1         

R4057     	Q_RES_0402LF   	          	          	                    
          	               	1         	215B4     	PRSNT_SWB_ISO_N     
          	               	2         	215B4     	PRSNT_SWB_ISO_R_N   

R4059     	Q_RES_0402LF   	          	          	                    
          	               	1         	162A4     	HP_LVC3_OCP_V3_2_EN 
          	               	2         	162A4     	P12V_OCP_EN_2_R     

R4060     	Q_RES_0402LF   	          	          	                    
          	               	1         	162B4     	HP_LVC3_OCP_V3_2_EN 
          	               	2         	162B4     	P3V3_OCP_EN_2_R     

R4061     	Q_RES_0402LF   	          	          	                    
          	               	1         	156A4     	HP_LVC3_OCP_V3_1_EN 
          	               	2         	156A4     	P12V_OCP_EN_1_R     

R4062     	Q_RES_0402LF   	          	          	                    
          	               	1         	242B4     	P12V_SCM_EN         
          	               	2         	242B4     	P12V_SCM_EN_R       

R4063     	Q_RES_0402LF   	          	          	                    
          	               	1         	192A4     	E1S_0_EN            
          	               	2         	192A4     	P3V3_E1S_EN_1_R     

R4064     	Q_RES_0402LF   	          	          	                    
          	               	1         	192B4     	E1S_0_EN            
          	               	2         	192B4     	P12V_E1S_EN_0_R     

R4065     	Q_RES_0402LF   	          	          	                    
          	               	1         	162B4     	P12V_AUX            
          	               	2         	162B4     	P12V_OCP_2_EN_G     

R4066     	Q_RES_0402LF   	          	          	                    
          	               	1         	162B4     	P3V3_OCP_EN_2_R     
          	               	2         	162B4     	GND                 

R4067     	Q_RES_0402LF   	          	          	                    
          	               	1         	162B4     	P12V_AUX            
          	               	2         	162B4     	P3V3_OCP_2_EN_G     

R4068     	Q_RES_0402LF   	          	          	                    
          	               	1         	156B4     	P12V_AUX            
          	               	2         	156B4     	P12V_OCP_1_EN_G     

R4069     	Q_RES_0402LF   	          	          	                    
          	               	1         	156B4     	P3V3_OCP_EN_1_R     
          	               	2         	156B4     	GND                 

R4070     	Q_RES_0402LF   	          	          	                    
          	               	1         	156B4     	P12V_AUX            
          	               	2         	156B4     	P3V3_OCP_1_EN_G     

R4071     	Q_RES_0402LF   	          	          	                    
          	               	1         	242B4     	P12V_AUX            
          	               	2         	242B4     	P12V_SCM_EN_G       

R4072     	Q_RES_0402LF   	          	          	                    
          	               	1         	192A4     	P12V_AUX            
          	               	2         	192A4     	P3V3_E1S_0_EN_G     

R4073     	Q_RES_0402LF   	          	          	                    
          	               	1         	192B4     	P12V_E1S_EN_0_R     
          	               	2         	192B4     	GND                 

R4074     	Q_RES_0402LF   	          	          	                    
          	               	1         	192B4     	P12V_AUX            
          	               	2         	192B4     	P12V_E1S_0_EN_G     

R4075     	Q_RES_0402LF   	          	          	                    
          	               	1         	212B4     	CLK_GEN2_BMC_RC_OE_N
          	               	2         	212B4     	CLK_GEN2_BMC_RC_OE_R3_N

R4076     	Q_RES_0402LF   	          	          	                    
          	               	1         	212B4     	CLK_GEN2_GPU_FPGA_OE_OR_N
          	               	2         	212B4     	CLK_GEN2_GPU_OE_N   

R4077     	Q_RES_0402LF   	          	          	                    
          	               	1         	212B3     	VFG3P3_CLK_GEN      
          	               	2         	212B3     	VFG_3P3A_CLK_GEN    

R4078     	Q_RES_0402LF   	          	          	                    
          	               	1         	212A2     	P3V3_AUX            
          	               	2         	212A2     	FG_SS_EN            

R4079     	Q_RES_0402LF   	          	          	                    
          	               	1         	212A2     	FG_SS_EN            
          	               	2         	212A2     	GND                 

R4080     	Q_RES_0402LF   	          	          	                    
          	               	1         	212B1     	P3V3_AUX            
          	               	2         	212B1     	P3V3_PWRGD_CLKGEN   

R4081     	Q_RES_0402LF   	          	          	                    
          	               	1         	212A1     	P3V3_AUX            
          	               	2         	212A1     	CLK_GEN2_SMB_SADR   

R4082     	Q_RES_0402LF   	          	          	                    
          	               	1         	212A1     	CLK_GEN2_SMB_SADR   
          	               	2         	212A1     	GND                 

R4083     	Q_RES_0402LF   	          	          	                    
          	               	1         	183B4     	E1S_0_PERST1_CLKREQ_N
          	               	2         	183B4     	E1S_0_CLKREQ_N      

R4084     	Q_RES_0402LF   	          	          	                    
          	               	1         	183B4     	E1S_0_PRSNT_N       
          	               	2         	183B4     	E1S_0_CLKREQ_N      

R4086     	Q_RES_0402LF   	          	          	                    
          	               	1         	215B1     	P3V3_AUX_FPGA_VCCIO2
          	               	2         	215B1     	PULL_FPGA_PB46A     

R4087     	Q_RES_0402LF   	          	          	                    
          	               	1         	240B4     	FM_JTAG_BMC_MUX_SEL_FROM_BMC_R
          	               	2         	240B4     	FM_JTAG_BMC_MUX_SEL_FROM_BMC_R2

R4088     	Q_RES_0402LF   	          	          	                    
          	               	1         	214A2     	FM_JTAG_BMC_MUX_SEL_FROM_BMC_R
          	               	2         	214A2     	FM_JTAG_BMC_MUX_SEL 

R4089     	Q_RES_0402LF   	          	          	                    
          	               	1         	14A4      	H_CPU0_PMSYNC_CPU1_R1
          	               	2         	14A3      	H_CPU0_PMSYNC_CPU1  

R4090     	Q_RES_0402LF   	          	          	                    
          	               	1         	172B2     	P3V3_AUX            
          	               	2         	172B2     	M2_0_P3V3_ADC_ALERT_R

R4091     	Q_RES_0402LF   	          	          	                    
          	               	1         	172A2     	P3V3_AUX            
          	               	2         	172A2     	P12V_SCM_ADC_ALERT_R

R4092     	Q_RES_0402LF   	          	          	                    
          	               	1         	172B2     	P3V3_AUX            
          	               	2         	172B2     	OCP_V3_2_P3V3_ADC_ALERT_R

R4093     	Q_RES_0402LF   	          	          	                    
          	               	1         	171B2     	P3V3_AUX            
          	               	2         	171B2     	E1S_0_P3V3_ADC_ALERT_R

R4094     	Q_RES_0402LF   	          	          	                    
          	               	1         	171B2     	P3V3_AUX            
          	               	2         	171B2     	OCP_SFF_P3V3_ADC_ALERT_R

R4095     	Q_RES_0402LF   	          	          	                    
          	               	1         	183A4     	PD_PCH_GPPC_A_19    
          	               	2         	183A4     	GND                 

R4096     	Q_RES_0402LF   	          	          	                    
          	               	1         	183A4     	PD_PCH_GPPC_A_18    
          	               	2         	183A4     	GND                 

R4097     	Q_RES_0402LF   	          	          	                    
          	               	1         	183A4     	PD_PCH_GPPC_A_15    
          	               	2         	183A4     	GND                 

R4098     	Q_RES_0402LF   	          	          	                    
          	               	1         	183A4     	PD_PCH_GPPC_A_14    
          	               	2         	183A4     	GND                 

R4099     	Q_RES_0402LF   	          	          	                    
          	               	1         	183A4     	PD_PCH_GPPC_A_10    
          	               	2         	183A4     	GND                 

R4100     	Q_RES_0402LF   	          	          	                    
          	               	1         	183A4     	PD_PCH_GPPC_C10     
          	               	2         	183A4     	GND                 

R4101     	Q_RES_0402LF   	          	          	                    
          	               	1         	183A4     	PD_PCH_GPPC_C9      
          	               	2         	183A4     	GND                 

R4102     	Q_RES_0402LF   	          	          	                    
          	               	1         	183A4     	PD_PCH_GPPC_C5      
          	               	2         	183A4     	GND                 

R4103     	Q_RES_0402LF   	          	          	                    
          	               	1         	184B3     	PD_GPP_M_17         
          	               	2         	184B2     	GND                 

R4104     	Q_RES_0402LF   	          	          	                    
          	               	1         	184B3     	PD_GPP_M_16         
          	               	2         	184B2     	GND                 

R4105     	Q_RES_0402LF   	          	          	                    
          	               	1         	184B3     	PD_GPP_M_15         
          	               	2         	184B2     	GND                 

R4106     	Q_RES_0402LF   	          	          	                    
          	               	1         	184B3     	PD_GPP_M_8          
          	               	2         	184B2     	GND                 

R4107     	Q_RES_0402LF   	          	          	                    
          	               	1         	184B3     	PD_GPP_I_17         
          	               	2         	184B2     	GND                 

R4108     	Q_RES_0402LF   	          	          	                    
          	               	1         	184A3     	PD_GPP_I_16         
          	               	2         	184A2     	GND                 

R4109     	Q_RES_0402LF   	          	          	                    
          	               	1         	184A3     	PD_GPP_I_15         
          	               	2         	184A2     	GND                 

R4110     	Q_RES_0402LF   	          	          	                    
          	               	1         	184A3     	PD_PCH_GPP_E_14     
          	               	2         	184A2     	GND                 

R4111     	Q_RES_0402LF   	          	          	                    
          	               	1         	184A3     	PD_PCH_GPP_E_13     
          	               	2         	184A2     	GND                 

R4112     	Q_RES_0402LF   	          	          	                    
          	               	1         	184A3     	PD_PCH_GPP_E_12     
          	               	2         	184A2     	GND                 

R4113     	Q_RES_0402LF   	          	          	                    
          	               	1         	184A3     	PD_PCH_GPP_E_11     
          	               	2         	184A2     	GND                 

R4114     	Q_RES_0402LF   	          	          	                    
          	               	1         	184A3     	PD_PCH_GPP_E_10     
          	               	2         	184A2     	GND                 

R4115     	Q_RES_0402LF   	          	          	                    
          	               	1         	184A3     	PD_PCH_GPP_E_9      
          	               	2         	184A2     	GND                 

R4116     	Q_RES_0402LF   	          	          	                    
          	               	1         	184A3     	PD_PCH_GPP_E_8      
          	               	2         	184A2     	GND                 

R4117     	Q_RES_0402LF   	          	          	                    
          	               	1         	184A3     	PD_PCH_GPP_E_3      
          	               	2         	184A2     	GND                 

R4118     	Q_RES_0402LF   	          	          	                    
          	               	1         	202B4     	IRQ_LPC_SERIRQ_ESPI_CS1_N
          	               	2         	202B4     	IRQ_LPC_SERIRQ_ESPI_CS1_R_N

R4119     	Q_RES_0402LF   	          	          	                    
          	               	1         	146B4     	P3V3_AUX            
          	               	2         	146B4     	GPU_3V3IO_RSVD0_FFU 

R4120     	Q_RES_0402LF   	          	          	                    
          	               	1         	146B4     	GPU_3V3IO_RSVD0_FFU 
          	               	2         	146B4     	GND                 

R4121     	Q_RES_0402LF   	          	          	                    
          	               	1         	146B4     	P3V3_AUX            
          	               	2         	146B4     	PRSNT_CABLE_GPU_B3_N

R4122     	Q_RES_0402LF   	          	          	                    
          	               	1         	146A4     	PRSNT_CABLE_GPU_B3_N
          	               	2         	146A4     	GND                 

R4123     	Q_RES_0402LF   	          	          	                    
          	               	1         	146B4     	P3V3_AUX            
          	               	2         	146B4     	GPU_3V3IO_RSVD1_FFU 

R4124     	Q_RES_0402LF   	          	          	                    
          	               	1         	146B4     	GPU_3V3IO_RSVD1_FFU 
          	               	2         	146B4     	GND                 

R4125     	Q_RES_0402LF   	          	          	                    
          	               	1         	146B4     	P3V3_AUX            
          	               	2         	146B4     	GPU_3V3IO_RSVD0_FFU_N

R4126     	Q_RES_0402LF   	          	          	                    
          	               	1         	146B4     	P3V3_AUX            
          	               	2         	146B4     	PRSNT_CABLE_GPU_B3  

R4127     	Q_RES_0402LF   	          	          	                    
          	               	1         	146B4     	P3V3_AUX            
          	               	2         	146B4     	GPU_3V3IO_RSVD1_FFU_N

R4128     	Q_RES_0402LF   	          	          	                    
          	               	1         	146B4     	P3V3_AUX            
          	               	2         	146B4     	GPU_3V3IO_RSVD0_FFU_ISO

R4129     	Q_RES_0402LF   	          	          	                    
          	               	1         	146B4     	P3V3_AUX            
          	               	2         	146B4     	PRSNT_CABLE_GPU_B3_ISO_N

R4130     	Q_RES_0402LF   	          	          	                    
          	               	1         	146B4     	P3V3_AUX            
          	               	2         	146B4     	GPU_3V3IO_RSVD1_FFU_ISO

R4131     	Q_RES_0402LF   	          	          	                    
          	               	1         	146B3     	P3V3_AUX            
          	               	2         	146B3     	GPU_3V3IO_RSVD3_FFU 

R4132     	Q_RES_0402LF   	          	          	                    
          	               	1         	146B3     	GPU_3V3IO_RSVD3_FFU 
          	               	2         	146B3     	GND                 

R4133     	Q_RES_0402LF   	          	          	                    
          	               	1         	146B3     	P3V3_AUX            
          	               	2         	146B3     	GPU_3V3IO_RSVD5_FFU 

R4134     	Q_RES_0402LF   	          	          	                    
          	               	1         	146A3     	GPU_3V3IO_RSVD5_FFU 
          	               	2         	146A3     	GND                 

R4135     	Q_RES_0402LF   	          	          	                    
          	               	1         	146B3     	P3V3_AUX            
          	               	2         	146B3     	PRSNT_CABLE_GPU_A2_N

R4136     	Q_RES_0402LF   	          	          	                    
          	               	1         	146B3     	PRSNT_CABLE_GPU_A2_N
          	               	2         	146B3     	GND                 

R4137     	Q_RES_0402LF   	          	          	                    
          	               	1         	146B2     	P3V3_AUX            
          	               	2         	146B2     	GPU_3V3IO_RSVD3_FFU_N

R4138     	Q_RES_0402LF   	          	          	                    
          	               	1         	146B2     	P3V3_AUX            
          	               	2         	146B2     	GPU_3V3IO_RSVD5_FFU_N

R4139     	Q_RES_0402LF   	          	          	                    
          	               	1         	146B2     	P3V3_AUX            
          	               	2         	146B2     	PRSNT_CABLE_GPU_A2  

R4140     	Q_RES_0402LF   	          	          	                    
          	               	1         	146B1     	P3V3_AUX            
          	               	2         	146B1     	GPU_3V3IO_RSVD3_FFU_ISO

R4141     	Q_RES_0402LF   	          	          	                    
          	               	1         	146B1     	P3V3_AUX            
          	               	2         	146B1     	GPU_3V3IO_RSVD5_FFU_ISO

R4142     	Q_RES_0402LF   	          	          	                    
          	               	1         	146B1     	P3V3_AUX            
          	               	2         	146B1     	PRSNT_CABLE_GPU_A2_ISO_N

R4143     	Q_RES_0402LF   	          	          	                    
          	               	1         	215B4     	GPU_3V3IO_RSVD0_FFU_ISO
          	               	2         	215B4     	GPU_3V3IO_RSVD0_FFU_ISO_R

R4144     	Q_RES_0402LF   	          	          	                    
          	               	1         	215A4     	GPU_3V3IO_RSVD1_FFU_ISO
          	               	2         	215A4     	GPU_3V3IO_RSVD1_FFU_ISO_R

R4145     	Q_RES_0402LF   	          	          	                    
          	               	1         	215A4     	PRSNT_CABLE_GPU_B3_ISO_N
          	               	2         	215A4     	PRSNT_CABLE_GPU_B3_ISO_R_N

R4146     	Q_RES_0402LF   	          	          	                    
          	               	1         	215A4     	GPU_3V3IO_RSVD3_FFU_ISO
          	               	2         	215A4     	GPU_3V3IO_RSVD3_FFU_ISO_R

R4147     	Q_RES_0402LF   	          	          	                    
          	               	1         	215A4     	PRSNT_CABLE_GPU_A2_ISO_N
          	               	2         	215A4     	PRSNT_CABLE_GPU_A2_ISO_R_N

R4148     	Q_RES_0402LF   	          	          	                    
          	               	1         	215A4     	GPU_3V3IO_RSVD5_FFU_ISO
          	               	2         	215A4     	GPU_3V3IO_RSVD5_FFU_ISO_R

R4149     	Q_RES_0402LF   	          	          	                    
          	               	1         	241A4     	SMB_1_PLD_3V3AUX_SCL
          	               	2         	241A4     	SMB_1_PLD_3V3AUX_SCL_R1

R4150     	Q_RES_0402LF   	          	          	                    
          	               	1         	241A4     	SMB_1_PLD_3V3AUX_SDA
          	               	2         	241A4     	SMB_1_PLD_3V3AUX_SDA_R1

R4151     	Q_RES_0402LF   	          	          	                    
          	               	1         	241A4     	SMB_1_PLD_3V3AUX_SCL
          	               	2         	241A4     	SMB_2_PLD_3V3AUX_SCL_R1

R4152     	Q_RES_0402LF   	          	          	                    
          	               	1         	241A4     	SMB_1_PLD_3V3AUX_SDA
          	               	2         	241A4     	SMB_2_PLD_3V3AUX_SDA_R1

R4153     	Q_RES_0402LF   	          	          	                    
          	               	1         	146A4     	P3V3_AUX            
          	               	2         	146A4     	PRSNT_CABLE_GPU_A1_N

R4154     	Q_RES_0402LF   	          	          	                    
          	               	1         	146A4     	PRSNT_CABLE_GPU_A1_N
          	               	2         	146A4     	GND                 

R4155     	Q_RES_0402LF   	          	          	                    
          	               	1         	146A4     	P3V3_AUX            
          	               	2         	146A4     	PRSNT_CABLE_GPU_A1  

R4156     	Q_RES_0402LF   	          	          	                    
          	               	1         	146A4     	P3V3_AUX            
          	               	2         	146A4     	PRSNT_CABLE_GPU_A1_ISO_N

R4157     	Q_RES_0402LF   	          	          	                    
          	               	1         	215A4     	PRSNT_CABLE_GPU_A1_ISO_N
          	               	2         	215A4     	PRSNT_CABLE_GPU_A1_ISO_R_N

R4158     	Q_RES_0402LF   	          	          	                    
          	               	1         	145B4     	P3V3_AUX            
          	               	2         	145B4     	GPU_3V3IO_RSVD1     

R4159     	Q_RES_0402LF   	          	          	                    
          	               	1         	145B4     	GPU_3V3IO_RSVD1     
          	               	2         	145B4     	GND                 

R4160     	Q_RES_0402LF   	          	          	                    
          	               	1         	145B4     	P3V3_AUX            
          	               	2         	145B4     	GPU_3V3IO_RSVD4     

R4161     	Q_RES_0402LF   	          	          	                    
          	               	1         	145A4     	GPU_3V3IO_RSVD4     
          	               	2         	145A4     	GND                 

R4162     	Q_RES_0402LF   	          	          	                    
          	               	1         	145B4     	P3V3_AUX            
          	               	2         	145B4     	GPU_3V3IO_RSVD3     

R4163     	Q_RES_0402LF   	          	          	                    
          	               	1         	145B4     	GPU_3V3IO_RSVD3     
          	               	2         	145B4     	GND                 

R4164     	Q_RES_0402LF   	          	          	                    
          	               	1         	145B4     	P3V3_AUX            
          	               	2         	145B4     	GPU_3V3IO_RSVD1_N   

R4165     	Q_RES_0402LF   	          	          	                    
          	               	1         	145B4     	P3V3_AUX            
          	               	2         	145B4     	GPU_3V3IO_RSVD4_N   

R4166     	Q_RES_0402LF   	          	          	                    
          	               	1         	145B4     	P3V3_AUX            
          	               	2         	145B4     	GPU_3V3IO_RSVD3_N   

R4167     	Q_RES_0402LF   	          	          	                    
          	               	1         	145B4     	P3V3_AUX            
          	               	2         	145B4     	GPU_3V3IO_RSVD1_ISO 

R4168     	Q_RES_0402LF   	          	          	                    
          	               	1         	145B4     	P3V3_AUX            
          	               	2         	145B4     	GPU_3V3IO_RSVD4_ISO 

R4169     	Q_RES_0402LF   	          	          	                    
          	               	1         	145B4     	P3V3_AUX            
          	               	2         	145B4     	GPU_3V3IO_RSVD3_ISO 

R4170     	Q_RES_0402LF   	          	          	                    
          	               	1         	215A4     	GPU_3V3IO_RSVD1_ISO 
          	               	2         	215A4     	GPU_3V3IO_RSVD1_ISO_R

R4171     	Q_RES_0402LF   	          	          	                    
          	               	1         	215A4     	GPU_3V3IO_RSVD3_ISO 
          	               	2         	215A4     	GPU_3V3IO_RSVD3_ISO_R

R4172     	Q_RES_0402LF   	          	          	                    
          	               	1         	215A4     	GPU_3V3IO_RSVD4_ISO 
          	               	2         	215A4     	GPU_3V3IO_RSVD4_ISO_R

R4173     	Q_RES_0402LF   	          	          	                    
          	               	1         	151A3     	P3V3_AUX            
          	               	2         	151A3     	UART_BMC_BIC_R_BUF_RX

R4174     	Q_RES_0402LF   	          	          	                    
          	               	1         	215B2     	RST_PCIE_PCH_DEV_PERST_N
          	               	2         	215B2     	RST_PCIE_PCH_DEV_PERST_E1S_R_N

R4175     	Q_RES_0402LF   	          	          	                    
          	               	1         	215B2     	RST_PCIE_PCH_DEV_PERST_N
          	               	2         	215B2     	RST_PCIE_PCH_DEV_PERST_M2_R_N

R4176     	Q_RES_0402LF   	          	          	                    
          	               	1         	257B4     	P3V3_AUX            
          	               	2         	257B4     	FM_LPC_ESPI_SEL     

R4177     	Q_RES_0402LF   	          	          	                    
          	               	1         	257B3     	FM_ESPI_PLD_R_EN_BUF_R
          	               	2         	257B3     	FM_ESPI_PLD_R_EN_BUF

R4178     	Q_RES_0402LF   	          	          	                    
          	               	1         	170B4     	SMB_LM75_2_3V3AUX_SCL
          	               	2         	170B4     	SMB_LM75_2_3V3AUX_SCL_R1

R4179     	Q_RES_0402LF   	          	          	                    
          	               	1         	170B4     	SMB_LM75_1_3V3AUX_SCL
          	               	2         	170B4     	SMB_LM75_1_3V3AUX_SCL_R1

R4180     	Q_RES_0402LF   	          	          	                    
          	               	1         	170B4     	SMB_LM75_0_3V3AUX_SCL
          	               	2         	170B4     	SMB_LM75_0_3V3AUX_SCL_R1

R4181     	Q_RES_0402LF   	          	          	                    
          	               	1         	170B4     	SMB_LM75_2_3V3AUX_SDA
          	               	2         	170B4     	SMB_LM75_2_3V3AUX_SDA_R1

R4182     	Q_RES_0402LF   	          	          	                    
          	               	1         	170B4     	SMB_LM75_1_3V3AUX_SDA
          	               	2         	170B4     	SMB_LM75_1_3V3AUX_SDA_R1

R4183     	Q_RES_0402LF   	          	          	                    
          	               	1         	170B4     	SMB_LM75_0_3V3AUX_SDA
          	               	2         	170B4     	SMB_LM75_0_3V3AUX_SDA_R1

R4184     	Q_RES_0402LF   	          	          	                    
          	               	1         	170A2     	P3V3_AUX            
          	               	2         	170A2     	U273_3_ADD2         

R4185     	Q_RES_0402LF   	          	          	                    
          	               	1         	170A2     	U273_3_ADD2         
          	               	2         	170A2     	GND                 

R4186     	Q_RES_0402LF   	          	          	                    
          	               	1         	170B2     	P3V3_AUX            
          	               	2         	170B2     	U272_2_ADD2         

R4187     	Q_RES_0402LF   	          	          	                    
          	               	1         	170A2     	U272_2_ADD2         
          	               	2         	170A2     	GND                 

R4188     	Q_RES_0402LF   	          	          	                    
          	               	1         	170B2     	P3V3_AUX            
          	               	2         	170B2     	U271_1_ADD2         

R4189     	Q_RES_0402LF   	          	          	                    
          	               	1         	170B2     	U271_1_ADD2         
          	               	2         	170B2     	GND                 

R4190     	Q_RES_0402LF   	          	          	                    
          	               	1         	170B2     	P3V3_AUX            
          	               	2         	170B2     	U270_0_ADD2         

R4191     	Q_RES_0402LF   	          	          	                    
          	               	1         	170B2     	U270_0_ADD2         
          	               	2         	170B2     	GND                 

R4192     	Q_RES_0402LF   	          	          	                    
          	               	1         	170A2     	P3V3_AUX            
          	               	2         	170A2     	U273_3_ADD1         

R4193     	Q_RES_0402LF   	          	          	                    
          	               	1         	170A2     	U273_3_ADD1         
          	               	2         	170A2     	GND                 

R4194     	Q_RES_0402LF   	          	          	                    
          	               	1         	170B2     	P3V3_AUX            
          	               	2         	170B2     	U272_2_ADD1         

R4195     	Q_RES_0402LF   	          	          	                    
          	               	1         	170A2     	U272_2_ADD1         
          	               	2         	170A2     	GND                 

R4196     	Q_RES_0402LF   	          	          	                    
          	               	1         	170B2     	P3V3_AUX            
          	               	2         	170B2     	U271_1_ADD1         

R4197     	Q_RES_0402LF   	          	          	                    
          	               	1         	170B2     	U271_1_ADD1         
          	               	2         	170B2     	GND                 

R4198     	Q_RES_0402LF   	          	          	                    
          	               	1         	170B2     	P3V3_AUX            
          	               	2         	170B2     	U270_0_ADD1         

R4199     	Q_RES_0402LF   	          	          	                    
          	               	1         	170B2     	U270_0_ADD1         
          	               	2         	170B2     	GND                 

R4200     	Q_RES_0402LF   	          	          	                    
          	               	1         	170A2     	P3V3_AUX            
          	               	2         	170A2     	U273_3_ADD0         

R4201     	Q_RES_0402LF   	          	          	                    
          	               	1         	170A2     	U273_3_ADD0         
          	               	2         	170A2     	GND                 

R4202     	Q_RES_0402LF   	          	          	                    
          	               	1         	170B2     	P3V3_AUX            
          	               	2         	170B2     	U272_2_ADD0         

R4203     	Q_RES_0402LF   	          	          	                    
          	               	1         	170A2     	U272_2_ADD0         
          	               	2         	170A2     	GND                 

R4204     	Q_RES_0402LF   	          	          	                    
          	               	1         	170B2     	P3V3_AUX            
          	               	2         	170B2     	U271_1_ADD0         

R4205     	Q_RES_0402LF   	          	          	                    
          	               	1         	170B2     	U271_1_ADD0         
          	               	2         	170B2     	GND                 

R4206     	Q_RES_0402LF   	          	          	                    
          	               	1         	170B2     	P3V3_AUX            
          	               	2         	170B2     	U270_0_ADD0         

R4207     	Q_RES_0402LF   	          	          	                    
          	               	1         	170B2     	U270_0_ADD0         
          	               	2         	170B2     	GND                 

R4208     	Q_RES_0402LF   	          	          	                    
          	               	1         	170A4     	P3V3_AUX            
          	               	2         	170A4     	FM_THERMAL_ALERT_N  

R4209     	Q_RES_0402LF   	          	          	                    
          	               	1         	170B4     	P3V3_AUX            
          	               	2         	170B4     	FM_THERMAL_ALERT_N  

R4210     	Q_RES_0402LF   	          	          	                    
          	               	1         	170B4     	P3V3_AUX            
          	               	2         	170B4     	FM_THERMAL_ALERT_N  

R4211     	Q_RES_0402LF   	          	          	                    
          	               	1         	170B4     	P3V3_AUX            
          	               	2         	170B4     	FM_THERMAL_ALERT_N  

R4212     	Q_RES_0402LF   	          	          	                    
          	               	1         	170A4     	FM_THERMAL_ALERT_N  
          	               	2         	170A4     	FM_LM75_3_ALERT_N   

R4213     	Q_RES_0402LF   	          	          	                    
          	               	1         	170A4     	FM_THERMAL_ALERT_N  
          	               	2         	170A4     	FM_LM75_2_ALERT_N   

R4214     	Q_RES_0402LF   	          	          	                    
          	               	1         	170B4     	FM_THERMAL_ALERT_N  
          	               	2         	170B4     	FM_G751_1_ALERT_N   

R4215     	Q_RES_0402LF   	          	          	                    
          	               	1         	170B4     	FM_THERMAL_ALERT_N  
          	               	2         	170B4     	FM_G751_0_ALERT_N   

R4216     	Q_RES_0402LF   	          	          	                    
          	               	1         	266A4     	FM_PVCCFA_EHV_FIVRA_CPU0_EN
          	               	2         	266A4     	PVCCFA_EHV_FIVRA_CPU0_EN_R

R4259     	Q_RES_0402LF   	          	          	                    
          	               	1         	214A2     	FM_THERMAL_ALERT_N  
          	               	2         	214A2     	FM_THERMAL_ALERT_R_N

R4260     	Q_RES_0402LF   	          	          	                    
          	               	1         	119A1     	PVNN_TERM_CPU0      
          	               	2         	119A1     	PD_CPU1_BIST_ENABLE 

R4261     	Q_RES_0402LF   	          	          	                    
          	               	1         	119A1     	PD_CPU1_BIST_ENABLE 
          	               	2         	119A1     	GND                 

R4262     	Q_RES_0402LF   	          	          	                    
          	               	1         	119B1     	PVNN_TERM_CPU0      
          	               	2         	119B1     	PD_CPU0_BIST_ENABLE 

R4263     	Q_RES_0402LF   	          	          	                    
          	               	1         	119B1     	PD_CPU0_BIST_ENABLE 
          	               	2         	119B1     	GND                 

R4264     	Q_RES_0402LF   	          	          	                    
          	               	1         	246B2     	P3V3_AUX            
          	               	2         	246B2     	PWRGD_P3V3_AUX_PDB_BUF_R

R4265     	Q_RES_0402LF   	          	          	                    
          	               	1         	246B2     	PWRGD_P3V3_AUX_PDB_BUF_R
          	               	2         	246B2     	GND                 

R4266     	Q_RES_0402LF   	          	          	                    
          	               	1         	246B2     	PWRGD_P3V3_AUX_PDB_BUF_R
          	               	2         	246B2     	PWRGD_P3V3_AUX_PDB_BUF

R4267     	Q_RES_0402LF   	          	          	                    
          	               	1         	222A4     	PWRGD_P3V3_AUX      
          	               	2         	222A4     	PWRGD_P3V3_AUX_PDB  

R4268     	Q_RES_0402LF   	          	          	                    
          	               	1         	246B4     	PWRGD_P3V3_AUX_PDB  
          	               	2         	246B4     	PWRGD_P3V3_AUX_PDB_R

R4269     	Q_RES_0402LF   	          	          	                    
          	               	1         	233A2     	P3V3_AUX            
          	               	2         	233A2     	SMB_VR_SENSOR_3V3AUX_SCL

R4270     	Q_RES_0402LF   	          	          	                    
          	               	1         	233A2     	P3V3_AUX            
          	               	2         	233A2     	SMB_VR_SENSOR_3V3AUX_SDA

R4273     	Q_RES_0402LF   	          	          	                    
          	               	1         	169B4     	P3V3_AUX            
          	               	2         	169B4     	FM_USB3_1_FGB       

R4274     	Q_RES_0402LF   	          	          	                    
          	               	1         	169B4     	FM_USB3_1_FGB       
          	               	2         	169A4     	GND                 

R4275     	Q_RES_0402LF   	          	          	                    
          	               	1         	169A4     	P3V3_AUX            
          	               	2         	169A4     	FM_USB3_1_EQA       

R4276     	Q_RES_0402LF   	          	          	                    
          	               	1         	169A4     	FM_USB3_1_EQA       
          	               	2         	169A4     	GND                 

R4279     	Q_RES_0402LF   	          	          	                    
          	               	1         	169B4     	P3V3_AUX            
          	               	2         	169B4     	FM_USB3_1_FGA       

R4280     	Q_RES_0402LF   	          	          	                    
          	               	1         	169B4     	FM_USB3_1_FGA       
          	               	2         	169A4     	GND                 

R4281     	Q_RES_0402LF   	          	          	                    
          	               	1         	169A4     	P3V3_AUX            
          	               	2         	169A4     	FM_USB3_1_EQB       

R4282     	Q_RES_0402LF   	          	          	                    
          	               	1         	169A4     	FM_USB3_1_EQB       
          	               	2         	169A4     	GND                 

R4284     	Q_RES_0402LF   	          	          	                    
          	               	1         	169B3     	P3V3_AUX            
          	               	2         	169B3     	FM_USB3_1_SWB       

R4285     	Q_RES_0402LF   	          	          	                    
          	               	1         	169B3     	FM_USB3_1_SWB       
          	               	2         	169A3     	GND                 

R4287     	Q_RES_0402LF   	          	          	                    
          	               	1         	169B2     	P3V3_AUX            
          	               	2         	169B2     	FM_USB3_1_SWA       

R4288     	Q_RES_0402LF   	          	          	                    
          	               	1         	169B2     	FM_USB3_1_SWA       
          	               	2         	169A2     	GND                 

R4289     	Q_RES_0402LF   	          	          	                    
          	               	1         	169B1     	P3V3_AUX            
          	               	2         	169B1     	FM_USB3_1_RXDET_EN  

R4290     	Q_RES_0402LF   	          	          	                    
          	               	1         	169B1     	FM_USB3_1_RXDET_EN  
          	               	2         	169B1     	GND                 

R4291     	Q_RES_0402LF   	          	          	                    
          	               	1         	169B1     	P3V3_AUX            
          	               	2         	169B1     	FM_USB3_1_EN_N      

R4292     	Q_RES_0402LF   	          	          	                    
          	               	1         	169B1     	FM_USB3_1_EN_N      
          	               	2         	169B1     	GND                 

R4293     	Q_RES_0402LF   	          	          	                    
          	               	1         	122B2     	H_CPU0_MEMHOT_IN_LVC1_R1_N
          	               	2         	122B2     	H_CPU0_MEMHOT_IN_LVC1_N

R4294     	Q_RES_0402LF   	          	          	                    
          	               	1         	122B2     	H_CPU1_MEMHOT_IN_LVC1_R1_N
          	               	2         	122B2     	H_CPU1_MEMHOT_IN_LVC1_N

R4295     	Q_RES_0402LF   	          	          	                    
          	               	1         	124B2     	PWRGD_DRAMPWRGD_CPU0_AB_LVC1_R2
          	               	2         	124B2     	PWRGD_DRAMPWRGD_CPU0_AB_LVC1_R

R4296     	Q_RES_0402LF   	          	          	                    
          	               	1         	124B2     	PWRGD_DRAMPWRGD_CPU0_CD_LVC1_R2
          	               	2         	124B2     	PWRGD_DRAMPWRGD_CPU0_CD_LVC1_R

R4297     	Q_RES_0402LF   	          	          	                    
          	               	1         	124B2     	PWRGD_DRAMPWRGD_CPU0_EF_LVC1_R2
          	               	2         	124B2     	PWRGD_DRAMPWRGD_CPU0_EF_LVC1_R

R4298     	Q_RES_0402LF   	          	          	                    
          	               	1         	124B2     	PWRGD_DRAMPWRGD_CPU0_GH_LVC1_R2
          	               	2         	124B2     	PWRGD_DRAMPWRGD_CPU0_GH_LVC1_R

R4299     	Q_RES_0402LF   	          	          	                    
          	               	1         	125B2     	PWRGD_DRAMPWRGD_CPU1_AB_LVC1_R2
          	               	2         	125B2     	PWRGD_DRAMPWRGD_CPU1_AB_LVC1_R

R4300     	Q_RES_0402LF   	          	          	                    
          	               	1         	125B2     	PWRGD_DRAMPWRGD_CPU1_CD_LVC1_R2
          	               	2         	125B2     	PWRGD_DRAMPWRGD_CPU1_CD_LVC1_R

R4301     	Q_RES_0402LF   	          	          	                    
          	               	1         	125B2     	PWRGD_DRAMPWRGD_CPU1_EF_LVC1_R2
          	               	2         	125B2     	PWRGD_DRAMPWRGD_CPU1_EF_LVC1_R

R4302     	Q_RES_0402LF   	          	          	                    
          	               	1         	125B2     	PWRGD_DRAMPWRGD_CPU1_GH_LVC1_R2
          	               	2         	125B2     	PWRGD_DRAMPWRGD_CPU1_GH_LVC1_R

R4303     	Q_RES_0402LF   	          	          	                    
          	               	1         	179B3     	CLK_100M_E1S_0_R_DP 
          	               	2         	179B3     	CLK_100M_E1S_0_DP   

R4304     	Q_RES_0402LF   	          	          	                    
          	               	1         	179B3     	CLK_100M_E1S_0_R_DN 
          	               	2         	179B3     	CLK_100M_E1S_0_DN   

R4305     	Q_RES_0402LF   	          	          	                    
          	               	1         	179B3     	CLK_100M_PE_M2_0_R_DP
          	               	2         	179B3     	CLK_100M_PE_M2_0_DP 

R4306     	Q_RES_0402LF   	          	          	                    
          	               	1         	179B3     	CLK_100M_PE_M2_0_R_DN
          	               	2         	179B3     	CLK_100M_PE_M2_0_DN 

R4388     	Q_RES_0402LF   	          	          	                    
          	               	1         	225A4     	PVNN_TERM_CPU0      
          	               	2         	225A4     	H_CPU_ERR1_LVC1_R_N 

R4389     	Q_RES_0402LF   	          	          	                    
          	               	1         	225A4     	PVNN_TERM_CPU0      
          	               	2         	225A4     	H_CPU_ERR2_LVC1_R_N 

R4390     	Q_RES_0402LF   	          	          	                    
          	               	1         	225B4     	PVNN_TERM_CPU0      
          	               	2         	225A4     	H_CPU_ERR0_LVC1_R_N 

R4391     	Q_RES_0402LF   	          	          	                    
          	               	1         	225A4     	PD_GTL2014_ERROR_B0 
          	               	2         	225A4     	GND                 

R4392     	Q_RES_0402LF   	          	          	                    
          	               	1         	225A1     	H_CPU_ERR0_LVC2_R_N 
          	               	2         	225A1     	H_CPU_ERR0_PCH_R_N  

R4393     	Q_RES_0402LF   	          	          	                    
          	               	1         	225A1     	H_CPU_ERR1_LVC2_R_N 
          	               	2         	225A1     	H_CPU_ERR1_PCH_R_N  

R4394     	Q_RES_0402LF   	          	          	                    
          	               	1         	225A1     	H_CPU_ERR2_LVC2_R_N 
          	               	2         	225A1     	H_CPU_ERR2_PCH_R_N  

R4395     	Q_RES_0402LF   	          	          	                    
          	               	1         	121B4     	PVNN_TERM_CPU0      
          	               	2         	121B4     	H_CPU0_THERMTRIP_LVC1_R_N

R4396     	Q_RES_0402LF   	          	          	                    
          	               	1         	121B4     	PVNN_TERM_CPU1      
          	               	2         	121B4     	H_CPU1_THERMTRIP_LVC1_R_N

R4397     	Q_RES_0402LF   	          	          	                    
          	               	1         	121B3     	H_CPU0_THERMTRIP_N  
          	               	2         	121B3     	H_CPU0_THERMTRIP_R_N

R4398     	Q_RES_0402LF   	          	          	                    
          	               	1         	121B3     	H_CPU1_THERMTRIP_N  
          	               	2         	121B3     	H_CPU1_THERMTRIP_R_N

R4399     	Q_RES_0402LF   	          	          	                    
          	               	1         	121B2     	H_CPU0_THERMTRIP_VT_N
          	               	2         	121B2     	H_CPU0_THERMTRIP_LVC1_N

R4400     	Q_RES_0402LF   	          	          	                    
          	               	1         	121B2     	H_CPU1_THERMTRIP_VT_N
          	               	2         	121B2     	H_CPU1_THERMTRIP_LVC1_N

R4401     	Q_RES_0402LF   	          	          	                    
          	               	1         	122B4     	PVNN_TERM_CPU0      
          	               	2         	122B4     	H_CPU0_MEMHOT_OUT_LVC1_R_N

R4402     	Q_RES_0402LF   	          	          	                    
          	               	1         	122B4     	PVNN_TERM_CPU1      
          	               	2         	122A4     	H_CPU1_MEMHOT_OUT_LVC1_R_N

R4403     	Q_RES_0402LF   	          	          	                    
          	               	1         	122B3     	H_CPU0_MEMHOT_OUT   
          	               	2         	122B3     	H_CPU0_MEMHOT_OUT_R 

R4404     	Q_RES_0402LF   	          	          	                    
          	               	1         	122A3     	H_CPU1_MEMHOT_OUT   
          	               	2         	122A3     	H_CPU1_MEMHOT_OUT_R 

R4405     	Q_RES_0402LF   	          	          	                    
          	               	1         	122B2     	P3V3                
          	               	2         	122B2     	H_CPU0_MEMHOT_OUT_VT_N

R4406     	Q_RES_0402LF   	          	          	                    
          	               	1         	122A2     	P3V3                
          	               	2         	122A2     	H_CPU1_MEMHOT_OUT_VT_N

R4407     	Q_RES_0402LF   	          	          	                    
          	               	1         	122B2     	H_CPU0_MEMHOT_OUT_VT_N
          	               	2         	122B2     	H_CPU0_MEMHOT_OUT_LVC1_N

R4408     	Q_RES_0402LF   	          	          	                    
          	               	1         	122A2     	H_CPU1_MEMHOT_OUT_VT_N
          	               	2         	122A2     	H_CPU1_MEMHOT_OUT_LVC1_N

R4409     	Q_RES_0402LF   	          	          	                    
          	               	1         	123B3     	H_CPU0_MEMTRIP      
          	               	2         	123B3     	H_CPU0_MEMTRIP_R    

R4410     	Q_RES_0402LF   	          	          	                    
          	               	1         	123B3     	H_CPU1_MEMTRIP      
          	               	2         	123B3     	H_CPU1_MEMTRIP_R    

R4411     	Q_RES_0402LF   	          	          	                    
          	               	1         	123B2     	P3V3                
          	               	2         	123B2     	H_CPU0_MEMTRIP_VT_N 

R4412     	Q_RES_0402LF   	          	          	                    
          	               	1         	123B2     	P3V3                
          	               	2         	123B2     	H_CPU1_MEMTRIP_VT_N 

R4413     	Q_RES_0402LF   	          	          	                    
          	               	1         	123B2     	H_CPU0_MEMTRIP_VT_N 
          	               	2         	123B2     	H_CPU0_MEMTRIP_LVC1_N

R4414     	Q_RES_0402LF   	          	          	                    
          	               	1         	123B2     	H_CPU1_MEMTRIP_VT_N 
          	               	2         	123B2     	H_CPU1_MEMTRIP_LVC1_N

R4419     	Q_RES_0402LF   	          	          	                    
          	               	1         	152B1     	USB2_HOST_BMC_B_DP  
          	               	2         	152B1     	GND                 

R4420     	Q_RES_0402LF   	          	          	                    
          	               	1         	152B1     	USB2_HOST_BMC_B_DN  
          	               	2         	152B1     	GND                 

R4448     	Q_RES_0402LF   	          	          	                    
          	               	1         	196B4     	P3V3_AUX            
          	               	2         	196B4     	USB_HUB_2_PSELF     

R4449     	Q_RES_0402LF   	          	          	                    
          	               	1         	196B4     	USB_HUB_2_PSELF     
          	               	2         	196B4     	GND                 

R4450     	Q_RES_0402LF   	          	          	                    
          	               	1         	196B4     	P3V3_AUX            
          	               	2         	196B4     	P3V3_AUX_USB_HUB_2  

R4451     	Q_RES_0402LF   	          	          	                    
          	               	1         	196B4     	RST_USB_HUB_N       
          	               	2         	196B4     	RST_USB_HUB_2_R_N   

R4452     	Q_RES_0402LF   	          	          	                    
          	               	1         	196B4     	P3V3_AUX            
          	               	2         	196B4     	RST_USB_HUB_2_R_N   

R4453     	Q_RES_0402LF   	          	          	                    
          	               	1         	196B4     	GND                 
          	               	2         	196B4     	RST_USB_HUB_2_R_N   

R4454     	Q_RES_0402LF   	          	          	                    
          	               	1         	196A4     	USB2_HUB_2_EXT_DP   
          	               	2         	196A4     	USB2_HUB_2_BUF_EXT_R_DP

R4455     	Q_RES_0402LF   	          	          	                    
          	               	1         	196A4     	USB2_HUB_2_EXT_DN   
          	               	2         	196A4     	USB2_HUB_2_BUF_EXT_R_DN

R4456     	Q_RES_0402LF   	          	          	                    
          	               	1         	196B4     	P3V3_AUX            
          	               	2         	196B4     	USB_HUB_2_OVCUR1    

R4457     	Q_RES_0402LF   	          	          	                    
          	               	1         	196B4     	P3V3_AUX            
          	               	2         	196B4     	USB_HUB_2_OVCUR2    

R4458     	Q_RES_0402LF   	          	          	                    
          	               	1         	196B4     	P3V3_AUX            
          	               	2         	196B4     	USB_HUB_2_OVCUR3    

R4459     	Q_RES_0402LF   	          	          	                    
          	               	1         	196B4     	P3V3_AUX            
          	               	2         	196B4     	USB_HUB_2_OVCUR4    

R4460     	Q_RES_0402LF   	          	          	                    
          	               	1         	196A4     	USB2_HOST_PCH_0_DP  
          	               	2         	196A4     	USB2_HUB_2_BUF_EXT_R_DP

R4461     	Q_RES_0402LF   	          	          	                    
          	               	1         	196A4     	USB2_HOST_PCH_0_DN  
          	               	2         	196A4     	USB2_HUB_2_BUF_EXT_R_DN

R4462     	Q_RES_0402LF   	          	          	                    
          	               	1         	196B4     	P3V3_AUX_USB_HUB_2  
          	               	2         	196B3     	USB_HUB_2_DVDD      

R4463     	Q_RES_0402LF   	          	          	                    
          	               	1         	196B3     	USB_HUB_2_RREF      
          	               	2         	196B3     	GND                 

R4464     	Q_RES_0402LF   	          	          	                    
          	               	1         	196B3     	USB_HUB_2_PGANG     
          	               	2         	196B3     	GND                 

R4465     	Q_RES_0402LF   	          	          	                    
          	               	1         	196A3     	PD_USB_HUB_2_EQ     
          	               	2         	196A3     	GND                 

R4466     	Q_RES_0402LF   	          	          	                    
          	               	1         	196B2     	USB_HUB_2_TEST      
          	               	2         	196B2     	GND                 

R4467     	Q_RES_0402LF   	          	          	                    
          	               	1         	196A2     	USB2_HUB_2_BUF_EXT_R_DP
          	               	2         	196A2     	USB2_HUB_2_BUF_EXT_DP

R4468     	Q_RES_0402LF   	          	          	                    
          	               	1         	196A2     	USB2_HUB_2_BUF_EXT_R_DN
          	               	2         	196A2     	USB2_HUB_2_BUF_EXT_DN

R4471     	Q_RES_0402LF   	          	          	                    
          	               	1         	196B2     	USB2_PCH_0_R_DP     
          	               	2         	196B2     	USB2_0_DP           

R4472     	Q_RES_0402LF   	          	          	                    
          	               	1         	196B2     	USB2_PCH_0_R_DN     
          	               	2         	196B2     	USB2_0_DN           

R4473     	Q_RES_0402LF   	          	          	                    
          	               	1         	196B2     	USB2_0_DP           
          	               	2         	196B2     	USB2_HOST_PCH_0_DP  

R4474     	Q_RES_0402LF   	          	          	                    
          	               	1         	196B2     	USB2_0_DN           
          	               	2         	196B2     	USB2_HOST_PCH_0_DN  

R4475     	Q_RES_0603LF   	          	          	                    
          	               	1         	211B4     	P3V3_9ZXL045        
          	               	2         	211B4     	P3V3_9ZXL045_VDDR   

R4476     	Q_RES_0402LF   	          	          	                    
          	               	1         	211B4     	FM_PLD_CLKS_DEV_EN  
          	               	2         	211B4     	FM_9ZXL045_DEV_EN   

R4477     	Q_RES_0402LF   	          	          	                    
          	               	1         	211B2     	FM_9ZXL045_0_OE_N   
          	               	2         	211B2     	CLK_SWB_BUF2_OE_N   

R4478     	Q_RES_0402LF   	          	          	                    
          	               	1         	211B2     	FM_9ZXL045_1_OE_N   
          	               	2         	211B2     	CLK_GPU_1_OE_N      

R4479     	Q_RES_0402LF   	          	          	                    
          	               	1         	211B2     	FM_9ZXL045_2_OE_N   
          	               	2         	211B2     	CLK_GPU_2_OE_N      

R4480     	Q_RES_0402LF   	          	          	                    
          	               	1         	237B3     	SMB_HOST_CLK_BUF_ISO_3V3AUX_SCL
          	               	2         	237B2     	SMB_HOST_9ZXL045_3V3AUX_SCL

R4481     	Q_RES_0402LF   	          	          	                    
          	               	1         	237B3     	SMB_HOST_CLK_BUF_ISO_3V3AUX_SDA
          	               	2         	237B2     	SMB_HOST_9ZXL045_3V3AUX_SDA

R4482     	Q_RES_0402LF   	          	          	                    
          	               	1         	152A4     	USB2_HOST_BMC_B_BUF_DP
          	               	2         	152A4     	GND                 

R4483     	Q_RES_0402LF   	          	          	                    
          	               	1         	152A4     	USB2_HOST_BMC_B_BUF_DN
          	               	2         	152A4     	GND                 

R4486     	Q_RES_0402LF   	          	          	                    
          	               	1         	196A4     	USB2_HOST_PCH_0_DP  
          	               	2         	196A4     	GND                 

R4487     	Q_RES_0402LF   	          	          	                    
          	               	1         	196A4     	USB2_HOST_PCH_0_DN  
          	               	2         	196A4     	GND                 

R4489     	Q_RES_0402LF   	          	          	                    
          	               	1         	211A3     	P3V3                
          	               	2         	211A3     	CLK_9ZXL045_SADR0   

R4490     	Q_RES_0402LF   	          	          	                    
          	               	1         	211A3     	CLK_9ZXL045_SADR0   
          	               	2         	211A3     	GND                 

R4491     	Q_RES_0402LF   	          	          	                    
          	               	1         	211A2     	P3V3                
          	               	2         	211A2     	CLK_9ZXL045_HIBW    

R4492     	Q_RES_0402LF   	          	          	                    
          	               	1         	211A2     	CLK_9ZXL045_HIBW    
          	               	2         	211A2     	GND                 

R4493     	Q_RES_0603LF   	          	          	                    
          	               	1         	211B4     	P3V3_9ZXL045        
          	               	2         	211B4     	P3V3_9ZXL045_VDDA   

R4494     	Q_RES_0402LF   	          	          	                    
          	               	1         	211B2     	FM_9ZXL045_3_OE_N   
          	               	2         	211B2     	P3V3                

R4495     	Q_RES_0402LF   	          	          	                    
          	               	1         	213B2     	OCP_SFF_CLK_OE_R_N  
          	               	2         	213B2     	OCP_SFF_CLK_OE_N    

R4496     	Q_RES_0402LF   	          	          	                    
          	               	1         	237B3     	SMB_HOST_CLK_BUF_ISO_3V3AUX_SCL
          	               	2         	237B2     	SMB_HOST_DB2000_3V3AUX_SCL

R4497     	Q_RES_0402LF   	          	          	                    
          	               	1         	237B3     	SMB_HOST_CLK_BUF_ISO_3V3AUX_SDA
          	               	2         	237B2     	SMB_HOST_DB2000_3V3AUX_SDA

R4498     	Q_RES_0402LF   	          	          	                    
          	               	1         	237B2     	P3V3                
          	               	2         	237B2     	SMB_HOST_CLK_BUF_ISO_3V3AUX_S_1

R4499     	Q_RES_0402LF   	          	          	                    
          	               	1         	237B2     	P3V3                
          	               	2         	237B2     	SMB_HOST_CLK_BUF_ISO_3V3AUX_S_2

R4500     	Q_RES_0402LF   	          	          	                    
          	               	1         	237B3     	P3V3                
          	               	2         	237B3     	PU_CLK_BUF_ISO_EN   

R4501     	Q_RES_0402LF   	          	          	                    
          	               	1         	212B4     	CLK_GEN2_XTAL_IN_R  
          	               	2         	212B4     	CLK_GEN2_XTAL_IN    

R4502     	Q_RES_0402LF   	          	          	                    
          	               	1         	131B3     	SMB_HOST_3V3AUX_SCL_R4
          	               	2         	131B3     	SMB_HOST_3V3AUX_XDP_R_SCL

R4503     	Q_RES_0402LF   	          	          	                    
          	               	1         	131B3     	SMB_HOST_3V3AUX_SDA_R4
          	               	2         	131B3     	SMB_HOST_3V3AUX_XDP_R_SDA

R4504     	Q_RES_0402LF   	          	          	                    
          	               	1         	183B2     	SMB_SML1_PMBUS_3V3AUX_PCH_SDA
          	               	2         	183B2     	SMB_SML1_PMBUS_3V3AUX_PCH_SDA_1

R4505     	Q_RES_0402LF   	          	          	                    
          	               	1         	183B2     	SMB_SML1_PMBUS_3V3AUX_PCH_SCL
          	               	2         	183B2     	SMB_SML1_PMBUS_3V3AUX_PCH_SCL_1

R4506     	Q_RES_0402LF   	          	          	                    
          	               	1         	240B4     	SMB_SML0_3V3AUX_SCL 
          	               	2         	240B4     	SMB_SML0_3V3AUX_SCL_R1

R4507     	Q_RES_0402LF   	          	          	                    
          	               	1         	240B4     	SMB_SML0_3V3AUX_SDA 
          	               	2         	240B4     	SMB_SML0_3V3AUX_SDA_R1

R4508     	Q_RES_0402LF   	          	          	                    
          	               	1         	240B4     	SMB_1_PLD_3V3AUX_SCL
          	               	2         	240B4     	SMB_1_PLD_3V3AUX_SCL_R3

R4509     	Q_RES_0402LF   	          	          	                    
          	               	1         	240B4     	SMB_1_PLD_3V3AUX_SDA
          	               	2         	240B4     	SMB_1_PLD_3V3AUX_SDA_R3

R4510     	Q_RES_0402LF   	          	          	                    
          	               	1         	241B4     	SMB_HOST_3V3AUX_SCL 
          	               	2         	241B4     	SMB_HOST_3V3AUX_SCL_R4

R4511     	Q_RES_0402LF   	          	          	                    
          	               	1         	241B4     	SMB_HOST_3V3AUX_SDA 
          	               	2         	241B4     	SMB_HOST_3V3AUX_SDA_R4

R4512     	Q_RES_0402LF   	          	          	                    
          	               	1         	241B4     	SMB_HOST_3V3AUX_SCL 
          	               	2         	241B4     	SMB_HOST_3V3AUX_SCL_R5

R4513     	Q_RES_0402LF   	          	          	                    
          	               	1         	241B4     	SMB_HOST_3V3AUX_SDA 
          	               	2         	241B4     	SMB_HOST_3V3AUX_SDA_R5

R4514     	Q_RES_0402LF   	          	          	                    
          	               	1         	212A4     	CLK_GEN2_GPU_FPGA_OE_R2_N
          	               	2         	212A4     	GND                 

R4515     	Q_RES_0402LF   	          	          	                    
          	               	1         	151A4     	P3V3_AUX            
          	               	2         	151A4     	UART_BMC_BIC_RX     

R4516     	Q_RES_0402LF   	          	          	                    
          	               	1         	206B4     	P3V3                
          	               	2         	206B4     	CLK_SWB_OE_N        

R4517     	Q_RES_0402LF   	          	          	                    
          	               	1         	206B4     	P3V3                
          	               	2         	206B4     	OCP_SFF_CLK_OE_N    

R4518     	Q_RES_0402LF   	          	          	                    
          	               	1         	211B1     	P3V3                
          	               	2         	211B1     	CLK_GPU_2_OE_N      

R4519     	Q_RES_0402LF   	          	          	                    
          	               	1         	211B1     	P3V3                
          	               	2         	211B1     	CLK_GPU_1_OE_N      

R4520     	Q_RES_0402LF   	          	          	                    
          	               	1         	211B1     	P3V3                
          	               	2         	211B1     	CLK_SWB_BUF2_OE_N   

R4521     	Q_RES_0402LF   	          	          	                    
          	               	1         	212B4     	P3V3_AUX            
          	               	2         	212B4     	CLK_GEN2_BMC_RC_OE_N

R4530     	Q_RES_0402LF   	          	          	                    
          	               	1         	241B4     	SMB_SML1_PMBUS_HSC_SCL_R3
          	               	2         	241B4     	SMB_SML1_PMBUS_HSC_SCL

R4531     	Q_RES_0402LF   	          	          	                    
          	               	1         	241B4     	SMB_SML1_PMBUS_HSC_SDA_R3
          	               	2         	241B4     	SMB_SML1_PMBUS_HSC_SDA

R4532     	Q_RES_0402LF   	          	          	                    
          	               	1         	157B3     	P3V3_AUX            
          	               	2         	157A3     	HP_LVC3_OCP_V3_1_P12V_PWRGD

R4533     	Q_RES_0402LF   	          	          	                    
          	               	1         	219B4     	PWRGD_DRAMPWRGD_CPU1_GH_R_LVC1
          	               	2         	219B4     	GND                 

R4534     	Q_RES_0402LF   	          	          	                    
          	               	1         	206B3     	CLK_SWB_OE_N        
          	               	2         	206B3     	FM_DB2000_8_OE_N    

R4535     	Q_RES_0402LF   	          	          	                    
          	               	1         	240B4     	CLK_100M_BMC_P3E_DP 
          	               	2         	240B4     	CLK_100M_BMC_P3E_DP_R

R4536     	Q_RES_0402LF   	          	          	                    
          	               	1         	240B4     	CLK_100M_BMC_P3E_DN 
          	               	2         	240B4     	CLK_100M_BMC_P3E_DN_R

R4537     	Q_RES_0402LF   	          	          	                    
          	               	1         	166B3     	FM_P2E_EN_N         
          	               	2         	166B3     	CLK_GEN2_GPU_FPGA_OE_OR_N

R4540     	Q_RES_0402LF   	          	          	                    
          	               	1         	237B2     	SMB_HOST_CLK_BUF_ISO_3V3AUX_S_1
          	               	2         	237B2     	SMB_HOST_CLK_BUF_ISO_3V3AUX_SCL

R4541     	Q_RES_0402LF   	          	          	                    
          	               	1         	237B2     	SMB_HOST_CLK_BUF_ISO_3V3AUX_S_2
          	               	2         	237B2     	SMB_HOST_CLK_BUF_ISO_3V3AUX_SDA

R4543     	Q_RES_0402LF   	          	          	                    
          	               	1         	145A4     	P3V3_AUX            
          	               	2         	145A4     	HGX_DETECT_N        

R4544     	Q_RES_0402LF   	          	          	                    
          	               	1         	145A4     	HGX_DETECT_N        
          	               	2         	145A4     	GND                 

R4545     	Q_RES_0402LF   	          	          	                    
          	               	1         	145A4     	P3V3_AUX            
          	               	2         	145A4     	HGX_DETECT          

R4546     	Q_RES_0402LF   	          	          	                    
          	               	1         	145A4     	P3V3_AUX            
          	               	2         	145A4     	HGX_DETECT_N_ISO    

R4547     	Q_RES_0402LF   	          	          	                    
          	               	1         	145B3     	P3V3_AUX            
          	               	2         	145B3     	SWB_HSC_EN          

R4548     	Q_RES_0402LF   	          	          	                    
          	               	1         	145B3     	SWB_HSC_EN          
          	               	2         	145B3     	GND                 

R4549     	Q_RES_0402LF   	          	          	                    
          	               	1         	145B1     	P3V3_AUX            
          	               	2         	145B1     	SWB_HSC_EN_BUF_R    

R4550     	Q_RES_0402LF   	          	          	                    
          	               	1         	145B1     	SWB_HSC_EN_BUF_R    
          	               	2         	145B1     	SWB_HSC_EN_BUF      

R4551     	Q_RES_0402LF   	          	          	                    
          	               	1         	246A4     	P3V3_AUX            
          	               	2         	246A4     	HPDB_HSC_PWRGD      

R4552     	Q_RES_0402LF   	          	          	                    
          	               	1         	246A4     	HPDB_HSC_PWRGD      
          	               	2         	246A4     	GND                 

R4553     	Q_RES_0402LF   	          	          	                    
          	               	1         	246A3     	P3V3_AUX            
          	               	2         	246A3     	HPDB_HSC_PWRGD_N    

R4554     	Q_RES_0402LF   	          	          	                    
          	               	1         	246A2     	P3V3_AUX            
          	               	2         	246A2     	HPDB_HSC_PWRGD_ISO  

R4555     	Q_RES_0402LF   	          	          	                    
          	               	1         	145B1     	SWB_HSC_EN_BUF_R    
          	               	2         	145B1     	GND                 

R4556     	Q_RES_0402LF   	          	          	                    
          	               	1         	215B2     	HGX_DETECT_N_R      
          	               	2         	215B2     	HGX_DETECT_N        

R4557     	Q_RES_0402LF   	          	          	                    
          	               	1         	215A2     	HPDB_HSC_PWRGD_ISO  
          	               	2         	215A2     	HPDB_HSC_PWRGD_ISO_R

R4558     	Q_RES_0402LF   	          	          	                    
          	               	1         	215A2     	SWB_HSC_EN          
          	               	2         	215A2     	SWB_HSC_EN_R        

R4559     	Q_RES_0402LF   	          	          	                    
          	               	1         	146A3     	SWB_HSC_PWRGD       
          	               	2         	146A3     	GND                 

R4560     	Q_RES_0402LF   	          	          	                    
          	               	1         	146A2     	P3V3_AUX            
          	               	2         	146A2     	SWB_HSC_PWRGD_N     

R4561     	Q_RES_0402LF   	          	          	                    
          	               	1         	146A1     	P3V3_AUX            
          	               	2         	146A1     	SWB_HSC_PWRGD_ISO   

R4562     	Q_RES_0402LF   	          	          	                    
          	               	1         	146A3     	P3V3_AUX            
          	               	2         	146A3     	SWB_HSC_PWRGD       

R4563     	Q_RES_0402LF   	          	          	                    
          	               	1         	215A2     	SWB_HSC_PWRGD_ISO_R 
          	               	2         	215A2     	SWB_HSC_PWRGD_ISO   

R4564     	Q_RES_0402LF   	          	          	                    
          	               	1         	184A3     	PD_GPP_I_14         
          	               	2         	184A2     	GND                 

R4565     	Q_RES_0402LF   	          	          	                    
          	               	1         	184A3     	PD_GPP_I_13         
          	               	2         	184A2     	GND                 

R4567     	Q_RES_0402LF   	          	          	                    
          	               	1         	250A4     	P3V3_PDB_AUX_ADC    
          	               	2         	250A4     	P1V581_PDB_ADC      

R4568     	Q_RES_0402LF   	          	          	                    
          	               	1         	250A4     	P1V581_PDB_ADC      
          	               	2         	250A4     	GND                 

R4569     	Q_RES_0402LF   	          	          	                    
          	               	1         	145B4     	GPU_3V3IO_RSVD1     
          	               	2         	145B4     	GPU_3V3IO_RSVD1_ISO 

R4570     	Q_RES_0402LF   	          	          	                    
          	               	1         	145B4     	GPU_3V3IO_RSVD3     
          	               	2         	145B4     	GPU_3V3IO_RSVD3_ISO 

R4571     	Q_RES_0402LF   	          	          	                    
          	               	1         	145B4     	GPU_3V3IO_RSVD4     
          	               	2         	145B4     	GPU_3V3IO_RSVD4_ISO 

R4572     	Q_RES_0402LF   	          	          	                    
          	               	1         	146B4     	GPU_3V3IO_RSVD1_FFU 
          	               	2         	146B4     	GPU_3V3IO_RSVD1_FFU_ISO

R4573     	Q_RES_0402LF   	          	          	                    
          	               	1         	146B4     	PRSNT_CABLE_GPU_B3_N
          	               	2         	146B4     	PRSNT_CABLE_GPU_B3_ISO_N

R4574     	Q_RES_0402LF   	          	          	                    
          	               	1         	146A4     	PRSNT_CABLE_GPU_A1_N
          	               	2         	146A4     	PRSNT_CABLE_GPU_A1_ISO_N

R4575     	Q_RES_0402LF   	          	          	                    
          	               	1         	146B4     	GPU_3V3IO_RSVD0_FFU 
          	               	2         	146B4     	GPU_3V3IO_RSVD0_FFU_ISO

R4576     	Q_RES_0402LF   	          	          	                    
          	               	1         	146B2     	GPU_3V3IO_RSVD5_FFU 
          	               	2         	146B2     	GPU_3V3IO_RSVD5_FFU_ISO

R4577     	Q_RES_0402LF   	          	          	                    
          	               	1         	146B2     	GPU_3V3IO_RSVD3_FFU 
          	               	2         	146B2     	GPU_3V3IO_RSVD3_FFU_ISO

R4578     	Q_RES_0402LF   	          	          	                    
          	               	1         	146B2     	PRSNT_CABLE_GPU_A2_N
          	               	2         	146B2     	PRSNT_CABLE_GPU_A2_ISO_N

R4579     	Q_RES_0402LF   	          	          	                    
          	               	1         	195B1     	P3V3_AUX            
          	               	2         	195B1     	FAB_BMC_REV_ID0     

R4580     	Q_RES_0402LF   	          	          	                    
          	               	1         	195B3     	P3V3_AUX            
          	               	2         	195B3     	FM_BOARD_BMC_SKU_ID4

R4581     	Q_RES_0402LF   	          	          	                    
          	               	1         	195B3     	FM_BOARD_BMC_SKU_ID4
          	               	2         	195B3     	GND                 

R4582     	Q_RES_0402LF   	          	          	                    
          	               	1         	195B3     	P3V3_AUX            
          	               	2         	195B3     	FM_BOARD_BMC_SKU_ID1

R4583     	Q_RES_0402LF   	          	          	                    
          	               	1         	195B3     	FM_BOARD_BMC_SKU_ID1
          	               	2         	195B3     	GND                 

R4584     	Q_RES_0402LF   	          	          	                    
          	               	1         	195B3     	P3V3_AUX            
          	               	2         	195B3     	FM_BOARD_BMC_SKU_ID0

R4585     	Q_RES_0402LF   	          	          	                    
          	               	1         	195B3     	FM_BOARD_BMC_SKU_ID0
          	               	2         	195B3     	GND                 

R4586     	Q_RES_0402LF   	          	          	                    
          	               	1         	195B2     	P3V3_AUX            
          	               	2         	195B2     	FAB_BMC_REV_ID2     

R4588     	Q_RES_0402LF   	          	          	                    
          	               	1         	195B2     	FAB_BMC_REV_ID2     
          	               	2         	195B2     	GND                 

R4589     	Q_RES_0402LF   	          	          	                    
          	               	1         	195B2     	P3V3_AUX            
          	               	2         	195B2     	FAB_BMC_REV_ID1     

R4590     	Q_RES_0402LF   	          	          	                    
          	               	1         	195B2     	FAB_BMC_REV_ID1     
          	               	2         	195B2     	GND                 

R4591     	Q_RES_0402LF   	          	          	                    
          	               	1         	195B3     	P3V3_AUX            
          	               	2         	195B3     	FM_BOARD_BMC_SKU_ID3

R4592     	Q_RES_0402LF   	          	          	                    
          	               	1         	195B3     	FM_BOARD_BMC_SKU_ID3
          	               	2         	195B3     	GND                 

R4593     	Q_RES_0402LF   	          	          	                    
          	               	1         	266A4     	IRQ_PVCCIN_CPU0_VRHOT_R_N
          	               	2         	266A4     	IRQ_PVCCIN_CPU0_VRHOT_N

R4594     	Q_RES_0402LF   	          	          	                    
          	               	1         	292B4     	SMB_VR_3V3AUX_SCL_R 
          	               	2         	292B4     	SMB_CLK_PVCCINFAON_CPU1

R4595     	Q_RES_0402LF   	          	          	                    
          	               	1         	296B4     	SMB_VR_3V3AUX_SCL_R 
          	               	2         	296B4     	SMB_CLK_PVCCD_HV_CPU1

R4596     	Q_RES_0402LF   	          	          	                    
          	               	1         	195B1     	FAB_BMC_REV_ID0     
          	               	2         	195B1     	GND                 

R4597     	Q_RES_0402LF   	          	          	                    
          	               	1         	195B3     	P3V3_AUX            
          	               	2         	195B3     	FM_BOARD_BMC_SKU_ID2

R4598     	Q_RES_0402LF   	          	          	                    
          	               	1         	195B3     	FM_BOARD_BMC_SKU_ID2
          	               	2         	195B3     	GND                 

R4599     	Q_RES_0402LF   	          	          	                    
          	               	1         	214B2     	HP_LVC3_OCP_V3_2_P12V_PWRGD
          	               	2         	214B2     	HP_LVC3_OCP_V3_2_HSC_PWRGD_PLD_

R4600     	Q_RES_0402LF   	          	          	                    
          	               	1         	214B2     	HP_LVC3_OCP_V3_1_P12V_PWRGD
          	               	2         	214B2     	HP_LVC3_OCP_V3_1_HSC_PWRGD_PLD_

R4601     	Q_RES_0402LF   	          	          	                    
          	               	1         	155A2     	CLK_50M_NCSI_OCP_SFF_ISO
          	               	2         	155A2     	CLK_50M_NCSI_OCP_SFF_ISO_R

R4602     	Q_RES_0402LF   	          	          	                    
          	               	1         	161A2     	CLK_50M_NCSI_OCP_V3_2_ISO
          	               	2         	161A2     	CLK_50M_NCSI_OCP_V3_2_ISO_R

R4603     	Q_RES_0402LF   	          	          	                    
          	               	1         	234B4     	SMB_BMC_GPU_EN      
          	               	2         	234B4     	GND                 

R4604     	Q_RES_0402LF   	          	          	                    
          	               	1         	224B3     	P3V3_AUX            
          	               	2         	224B3     	PWRGD_PS_PWROK_PLD_N

R4605     	Q_RES_0402LF   	          	          	                    
          	               	1         	224B3     	P3V3_AUX            
          	               	2         	224B3     	PWRGD_PS_PWROK_PLD_ISO

R4606     	Q_RES_0402LF   	          	          	                    
          	               	1         	214B4     	E1S_0_LED_ACT_R_N   
          	               	2         	214B3     	E1S_0_LED_ACT_N     

R4607     	Q_RES_0402LF   	          	          	                    
          	               	1         	214A4     	LED_HDD_ACTIVITY_B_N
          	               	2         	214A3     	LED_HDD_ACTIVITY_B_PLD_N

R4608     	Q_RES_0402LF   	          	          	                    
          	               	1         	214A4     	GPU_FPGA_RST_N      
          	               	2         	214A3     	GPU_FPGA_RST_R_N    

R4609     	Q_RES_0402LF   	          	          	                    
          	               	1         	214A4     	FM_JTAG_TCK_MUX_SEL_R
          	               	2         	214A3     	FM_JTAG_TCK_MUX_SEL 

R4610     	Q_RES_0402LF   	          	          	                    
          	               	1         	214A4     	CLK_GEN2_GPU_FPGA_OE_R_N
          	               	2         	214A3     	CLK_GEN2_GPU_FPGA_OE_N

R4611     	Q_RES_0402LF   	          	          	                    
          	               	1         	214A4     	FM_BMC_CPU_FBRK_OUT_R_N
          	               	2         	214A3     	FM_BMC_CPU_FBRK_OUT_N

R4612     	Q_RES_0402LF   	          	          	                    
          	               	1         	214A4     	FM_PCH_SPKR         
          	               	2         	214A3     	FM_PCH_SPKR_R       

R4613     	Q_RES_0402LF   	          	          	                    
          	               	1         	158B3     	OCP_V3_1_P3V3_PWRGD 
          	               	2         	158B3     	HP_OCP_V3_1_RST_R   

R4614     	Q_RES_0402LF   	          	          	                    
          	               	1         	158B3     	HP_OCP_V3_1_RST     
          	               	2         	158B3     	HP_OCP_V3_1_RST_R   

R4615     	Q_RES_0402LF   	          	          	                    
          	               	1         	164B3     	OCP_V3_2_P3V3_PWRGD 
          	               	2         	164B3     	HP_OCP_V3_2_RST_R   

R4616     	Q_RES_0402LF   	          	          	                    
          	               	1         	164B3     	HP_OCP_V3_2_RST     
          	               	2         	164B3     	HP_OCP_V3_2_RST_R   

R4617     	Q_RES_0402LF   	          	          	                    
          	               	1         	164B2     	HP_LVC3_OCP_V3_2_PWRGD
          	               	2         	164B2     	HP_LVC3_OCP_V3_2_PWRGD_R

R4618     	Q_RES_0402LF   	          	          	                    
          	               	1         	158B2     	HP_LVC3_OCP_V3_1_PWRGD
          	               	2         	158B2     	HP_LVC3_OCP_V3_1_PWRGD_R

R4620     	Q_RES_0402LF   	          	          	                    
          	               	1         	306A1     	P3V3_AUX            
          	               	2         	306A1     	IRQ_UV_DETECT_N     

R4621     	Q_RES_0402LF   	          	          	                    
          	               	1         	226B2     	H_CPU_CATERR_LVC2_BMC_R_N
          	               	2         	226B2     	H_CPU_CATERR_LVC2_BMC_N

R4622     	Q_RES_0402LF   	          	          	                    
          	               	1         	219B4     	RST_PERST_SWB_N     
          	               	2         	219B4     	GND                 

R4623     	Q_RES_0402LF   	          	          	                    
          	               	1         	248B4     	P3V3_AUX            
          	               	2         	248B4     	PU_JTAG_SW_PU       

R4624     	Q_RES_0402LF   	          	          	                    
          	               	1         	248B4     	JTAG_BMC_SW_OE      
          	               	2         	248B3     	JTAG_BMC_SW_R_OE    

R4625     	Q_RES_0402LF   	          	          	                    
          	               	1         	213B2     	JTAG_BMC_SW_OE      
          	               	2         	213B2     	JTAG_BMC_SW_PLD_OE  

R4626     	Q_RES_0402LF   	          	          	                    
          	               	1         	248B3     	JTAG_BMC_TDO        
          	               	2         	248B3     	JTAG_BMC_TDO_R      

R4627     	Q_RES_0402LF   	          	          	                    
          	               	1         	248B3     	JTAG_BMC_TDI        
          	               	2         	248B3     	JTAG_BMC_TDI_R      

R4628     	Q_RES_0402LF   	          	          	                    
          	               	1         	248B3     	JTAG_BMC_TMS        
          	               	2         	248B3     	JTAG_BMC_TMS_R      

R4629     	Q_RES_0402LF   	          	          	                    
          	               	1         	248B3     	JTAG_BMC_TCK        
          	               	2         	248B3     	JTAG_BMC_TCK_R      

R4630     	Q_RES_0402LF   	          	          	                    
          	               	1         	248B2     	JTAG_BMC_SW_TDO_R   
          	               	2         	248B2     	JTAG_BMC_SW_TDO     

R4631     	Q_RES_0402LF   	          	          	                    
          	               	1         	248B2     	JTAG_BMC_SW_TDI_R   
          	               	2         	248B2     	JTAG_BMC_SW_TDI     

R4632     	Q_RES_0402LF   	          	          	                    
          	               	1         	248B2     	JTAG_BMC_SW_TMS_R   
          	               	2         	248B2     	JTAG_BMC_SW_TMS     

R4633     	Q_RES_0402LF   	          	          	                    
          	               	1         	248B2     	JTAG_BMC_SW_TCK_R   
          	               	2         	248B2     	JTAG_BMC_SW_TCK     

R4634     	Q_RES_0402LF   	          	          	                    
          	               	1         	248B4     	P3V3_AUX            
          	               	2         	248B4     	JTAG_BMC_SW_OE      

R4635     	Q_RES_0402LF   	          	          	                    
          	               	1         	248B4     	JTAG_BMC_SW_OE      
          	               	2         	248B4     	GND                 

R4636     	Q_RES_0402LF   	          	          	                    
          	               	1         	169B4     	USB3_PCH_RX_DP<4>   
          	               	2         	169B4     	GND                 

R4637     	Q_RES_0402LF   	          	          	                    
          	               	1         	169B4     	USB3_PCH_RX_DN<4>   
          	               	2         	169B4     	GND                 

R4638     	Q_RES_1206LF   	          	          	                    
          	               	1         	260B2     	P5V                 
          	               	2         	260B2     	VR_P5V_EN_D         

R4639     	Q_RES_1206LF   	          	          	                    
          	               	1         	260B2     	P5V                 
          	               	2         	260B2     	VR_P5V_EN_D         

R4640     	Q_RES_1206LF   	          	          	                    
          	               	1         	260B2     	P5V                 
          	               	2         	260B2     	VR_P5V_EN_D         

R4641     	Q_RES_1206LF   	          	          	                    
          	               	1         	260B2     	P5V                 
          	               	2         	260B2     	VR_P5V_EN_D         

R4642     	Q_RES_0402LF   	          	          	                    
          	               	1         	167A4     	P3V3_AUX            
          	               	2         	167A4     	FM_P2E_BUF2_VODB_DB 

R4643     	Q_RES_0402LF   	          	          	                    
          	               	1         	167A3     	P3V3_AUX            
          	               	2         	167A3     	FM_P2E_BUF2_VODA_DB 

R4644     	Q_RES_0402LF   	          	          	                    
          	               	1         	167B4     	P3V3_AUX            
          	               	2         	167B4     	FM_P2E_BUF2_EQB1    

R4645     	Q_RES_0402LF   	          	          	                    
          	               	1         	167B3     	P3V3_AUX            
          	               	2         	167B3     	FM_P2E_BUF2_EQB0    

R4646     	Q_RES_0402LF   	          	          	                    
          	               	1         	167A3     	FM_P2E_BUF2_EQB0    
          	               	2         	167A3     	GND                 

R4647     	Q_RES_0402LF   	          	          	                    
          	               	1         	167A3     	FM_P2E_BUF2_VODA_DB 
          	               	2         	167A3     	GND                 

R4648     	Q_RES_0402LF   	          	          	                    
          	               	1         	167B3     	P3V3_AUX            
          	               	2         	167B3     	FM_P2E_BUF2_EQA1    

R4649     	Q_RES_0402LF   	          	          	                    
          	               	1         	167B3     	P3V3_AUX            
          	               	2         	167B3     	FM_P2E_BUF2_EQA0    

R4650     	Q_RES_0402LF   	          	          	                    
          	               	1         	167A3     	FM_P2E_BUF2_EQA0    
          	               	2         	167A3     	GND                 

R4651     	Q_RES_0402LF   	          	          	                    
          	               	1         	167B1     	FM_P2E_EN2_N        
          	               	2         	167B1     	CLK_GEN2_GPU_FPGA_OE_OR_N

R4652     	Q_RES_0402LF   	          	          	                    
          	               	1         	306B2     	A_HSC_LOW_DRAIN     
          	               	2         	306B2     	HSC_D_OC            

R4653     	Q_RES_0402LF   	          	          	                    
          	               	1         	167A4     	FM_P2E_BUF2_VODB_DB 
          	               	2         	167A4     	GND                 

R4654     	Q_RES_0402LF   	          	          	                    
          	               	1         	167A3     	FM_P2E_BUF2_EQA1    
          	               	2         	167A3     	GND                 

R4655     	Q_RES_0402LF   	          	          	                    
          	               	1         	167A3     	P3V3_AUX            
          	               	2         	167A3     	FM_P2E_BUF2_RXDET   

R4656     	Q_RES_0402LF   	          	          	                    
          	               	1         	167A2     	P3V3_AUX            
          	               	2         	167A2     	FM_P2E_BUF2_SD_TH   

R4657     	Q_RES_0402LF   	          	          	                    
          	               	1         	167A2     	FM_P2E_BUF2_SD_TH   
          	               	2         	167A2     	GND                 

R4658     	Q_RES_0402LF   	          	          	                    
          	               	1         	167A1     	FM_P2E_BUF2_VOD_SEL 
          	               	2         	167A1     	GND                 

R4659     	Q_RES_0402LF   	          	          	                    
          	               	1         	167B4     	P2E_MB_BMC_TX_C_DP<0>
          	               	2         	167B4     	P2E_MB_BMC_TX_C_R1_DP<0>

R4660     	Q_RES_0402LF   	          	          	                    
          	               	1         	167B4     	P2E_MB_BMC_TX_C_DN<0>
          	               	2         	167B4     	P2E_MB_BMC_TX_C_R1_DN<0>

R4661     	Q_RES_0402LF   	          	          	                    
          	               	1         	167B4     	P2E_MB_BMC_TX_C_DP<0>
          	               	2         	167B4     	P2E_MB_BMC_TX_C_R2_DP<0>

R4662     	Q_RES_0402LF   	          	          	                    
          	               	1         	167B4     	P2E_MB_BMC_TX_C_DN<0>
          	               	2         	167B4     	P2E_MB_BMC_TX_C_R2_DN<0>

R4663     	Q_RES_0402LF   	          	          	                    
          	               	1         	167B4     	P2E_MB_BMC_RX_DP<0> 
          	               	2         	167B4     	P2E_MB_BMC_RX_R1_DP<0>

R4664     	Q_RES_0402LF   	          	          	                    
          	               	1         	167B4     	P2E_MB_BMC_RX_DN<0> 
          	               	2         	167B4     	P2E_MB_BMC_RX_R1_DN<0>

R4665     	Q_RES_0402LF   	          	          	                    
          	               	1         	167B4     	P2E_MB_BMC_RX_DP<0> 
          	               	2         	167B4     	P2E_MB_BMC_RX_R2_DP<0>

R4666     	Q_RES_0402LF   	          	          	                    
          	               	1         	167B4     	P2E_MB_BMC_RX_DN<0> 
          	               	2         	167B4     	P2E_MB_BMC_RX_R2_DN<0>

R4667     	Q_RES_0402LF   	          	          	                    
          	               	1         	306B4     	HSC_CSOUT           
          	               	2         	306B4     	A_HSC_LOW           

R4668     	Q_RES_0402LF   	          	          	                    
          	               	1         	306B4     	A_HSC_LOW           
          	               	2         	306B4     	GND                 

R4669     	Q_RES_0402LF   	          	          	                    
          	               	1         	306B4     	HSC_CSOUT           
          	               	2         	306B4     	A_HSC_HIGH          

R4670     	Q_RES_0402LF   	          	          	                    
          	               	1         	306B4     	A_HSC_HIGH          
          	               	2         	306B4     	GND                 

R4671     	Q_RES_0402LF   	          	          	                    
          	               	1         	306B3     	P3V3_AUX            
          	               	2         	306B3     	HSC_D_OC            

R4672     	Q_RES_0402LF   	          	          	                    
          	               	1         	306B2     	P3V3_AUX            
          	               	2         	306B2     	A_HSC_LOW_GATE      

R4673     	Q_RES_0402LF   	          	          	                    
          	               	1         	306B2     	A_HSC_LOW_GATE      
          	               	2         	306B2     	GND                 

R4674     	Q_RES_0402LF   	          	          	                    
          	               	1         	220B4     	FM_SLP_SUS_RSM_RST_N
          	               	2         	220A4     	GND                 

R4677     	Q_RES_0402LF   	          	          	                    
          	               	1         	260A4     	PWRGD_P3V3_R1       
          	               	2         	260A4     	PWRGD_P3V3          

R4678     	Q_RES_0402LF   	          	          	                    
          	               	1         	260B2     	PWRGD_P5V_ISO_R     
          	               	2         	260B2     	PWRGD_P5V_ISO       

R4679     	Q_RES_0402LF   	          	          	                    
          	               	1         	260A3     	P5V                 
          	               	2         	260A3     	PWRGD_P5V           

R4680     	Q_RES_0402LF   	          	          	                    
          	               	1         	260B2     	P12V_AUX            
          	               	2         	260B2     	PWRGD_P5V_N         

R4681     	Q_RES_0402LF   	          	          	                    
          	               	1         	260A4     	PWRGD_P3V3_R1       
          	               	2         	260A4     	GND                 

R4682     	Q_RES_0402LF   	          	          	                    
          	               	1         	260A3     	PWRGD_P5V           
          	               	2         	260A3     	GND                 

R4684     	Q_RES_0402LF   	          	          	                    
          	               	1         	305A1     	P12V_HSC_TEMP_ALERT_N
          	               	2         	305A1     	P12V_HSC_TEMP_ALERT_R_N

R4685     	Q_RES_0402LF   	          	          	                    
          	               	1         	305B1     	P3V3_AUX            
          	               	2         	305A1     	P12V_HSC_TEMP_ALERT_R_N

R4686     	Q_RES_0402LF   	          	          	                    
          	               	1         	305A1     	P3V3_AUX            
          	               	2         	305A1     	P12V_HSC_T_CRIT_R_N 

R4687     	Q_RES_0402LF   	          	          	                    
          	               	1         	251B4     	GND                 
          	               	2         	251B4     	HSC_TYPE_ADC_A1     

R4688     	Q_RES_0402LF   	          	          	                    
          	               	1         	251B4     	GND                 
          	               	2         	251B4     	HSC_TYPE_ADC_A0     

R4689     	Q_RES_0402LF   	          	          	                    
          	               	1         	251B4     	SMB_LM75_0_3V3AUX_SCL
          	               	2         	251B4     	SMB_HSC_TYPE_ADC_SCL

R4690     	Q_RES_0402LF   	          	          	                    
          	               	1         	251B4     	SMB_LM75_0_3V3AUX_SDA
          	               	2         	251B4     	SMB_HSC_TYPE_ADC_SDA

R4691     	Q_RES_0402LF   	          	          	                    
          	               	1         	251B3     	HSC_TYPE_ADC_A0     
          	               	2         	251B3     	SMB_HSC_TYPE_ADC_SDA

R4692     	Q_RES_0402LF   	          	          	                    
          	               	1         	251B2     	P3V3_AUX            
          	               	2         	251B2     	TP_HSC_TYPE_ADC_ALERT

R4693     	Q_RES_0402LF   	          	          	                    
          	               	1         	306B3     	HSC_CSOUT           
          	               	2         	306B3     	HSC_D_OC            

R4694     	Q_RES_0402LF   	          	          	                    
          	               	1         	167A4     	FM_P2E_BUF2_EQB1    
          	               	2         	167A4     	GND                 

R4695     	Q_RES_0402LF   	          	          	                    
          	               	1         	305B3     	SMB_SML1_PMBUS_HSC_SCL
          	               	2         	305B3     	SMB_SML1_PMBUS_HSC_MODULE_SCL

R4696     	Q_RES_0402LF   	          	          	                    
          	               	1         	305B3     	SMB_SML1_PMBUS_HSC_SDA
          	               	2         	305B3     	SMB_SML1_PMBUS_HSC_MODULE_SDA

R4697     	Q_RES_0402LF   	          	          	                    
          	               	1         	213A4     	RST_SRST_PLD_BMC_R_N
          	               	2         	213A4     	RST_SRST_PLD_BMC_N  

R4701     	Q_RES_0402LF   	          	          	                    
          	               	1         	245B2     	P3V3_AUX            
          	               	2         	245B2     	FM_FAN_PWR_EN       

R4702     	Q_RES_0402LF   	          	          	                    
          	               	1         	255B2     	LED_P12V_AUX_R1     
          	               	2         	255B2     	LED_P12V_AUX_R2     

R4703     	Q_RES_0402LF   	          	          	                    
          	               	1         	255B2     	LED_P12V_PSU_R1     
          	               	2         	255B2     	LED_P12V_PSU_R2     

R4704     	Q_RES_0402LF   	          	          	                    
          	               	1         	255B1     	LED_P12V_AUX_R2     
          	               	2         	255B1     	LED_P12V_AUX_R3     

R4705     	Q_RES_0402LF   	          	          	                    
          	               	1         	255B1     	LED_P12V_PSU_R2     
          	               	2         	255B1     	LED_P12V_PSU_R3     

R4706     	Q_RES_0402LF   	          	          	                    
          	               	1         	255B1     	LED_P12V_AUX_R3     
          	               	2         	255B1     	P12V_AUX            

R4707     	Q_RES_0402LF   	          	          	                    
          	               	1         	255B1     	LED_P12V_PSU_R3     
          	               	2         	255B1     	P12V_PSU            

R4708     	Q_RES_0402LF   	          	          	                    
          	               	1         	242B1     	P12V_SCM_FAULT_N    
          	               	2         	242B1     	P12V_SCM_FAULT_R_N  

R4709     	Q_RES_0402LF   	          	          	                    
          	               	1         	242A2     	P12V_SCM_FLTB_N     
          	               	2         	242A1     	P12V_SCM_FAULT_R_N  

R4710     	Q_RES_0402LF   	          	          	                    
          	               	1         	255B2     	P3V3_AUX            
          	               	2         	255A2     	LED_P12V_SCM_FAULT_D1

R4711     	Q_RES_0402LF   	          	          	                    
          	               	1         	255B1     	LED_P12V_SCM_FAULT  
          	               	2         	255B1     	P3V3_AUX            

R4712     	Q_RES_0402LF   	          	          	                    
          	               	1         	185A4     	RST_PFR_OVR_RTC     
          	               	2         	185A4     	GND                 

R4713     	Q_RES_0402LF   	          	          	                    
          	               	1         	185A4     	RST_PFR_OVR_SRTC    
          	               	2         	185A4     	GND                 

R4714     	Q_RES_0402LF   	          	          	                    
          	               	1         	213A4     	SMB_HOST_3V3AUX_SDA_R4
          	               	2         	213A4     	SMB_HOST_3V3AUX_PLD_SDA

R4715     	Q_RES_0402LF   	          	          	                    
          	               	1         	213A4     	SMB_HOST_3V3AUX_SCL_R4
          	               	2         	213A4     	SMB_HOST_3V3AUX_PLD_SCL

R4716     	Q_RES_0402LF   	          	          	                    
          	               	1         	224A4     	P3V3_AUX            
          	               	2         	224A4     	FM_AC_PWR_BTN_R_N   

R4717     	Q_RES_0402LF   	          	          	                    
          	               	1         	224A4     	FM_AC_PWR_BTN_R_N   
          	               	2         	224A3     	FM_AC_PWR_BTN_PLD_N 

R4718     	Q_RES_0402LF   	          	          	                    
          	               	1         	224A2     	FM_AC_PWR_BTN_PLD_ISO_R_N
          	               	2         	224A2     	FM_AC_PWR_BTN_PLD_ISO_N

R4719     	Q_RES_0402LF   	          	          	                    
          	               	1         	224A2     	P3V3_AUX            
          	               	2         	224A2     	FM_AC_PWR_BTN_PLD_ISO_N

R4720     	Q_RES_0402LF   	          	          	                    
          	               	1         	240B1     	FM_AC_PWR_BTN_N     
          	               	2         	240B1     	FM_AC_PWR_BTN_R_N   

R4721     	Q_RES_0402LF   	          	          	                    
          	               	1         	245B4     	FM_AC_PWR_BTN_R_N   
          	               	2         	245B4     	FM_AC_PWR_BTN_PDB_N 

R4722     	Q_RES_0402LF   	          	          	                    
          	               	1         	184B1     	FM_PCH_BMC_RST_R_N  
          	               	2         	184B1     	P3V3_AUX            

R4723     	Q_RES_0402LF   	          	          	                    
          	               	1         	215A4     	FM_PCH_BMC_RST_R_N  
          	               	2         	215A4     	FM_PCH_BMC_RST_N    

R4724     	Q_RES_0402LF   	          	          	                    
          	               	1         	144B4     	PRSNT_SWB_N         
          	               	2         	144B4     	GND                 

R4725     	Q_RES_0402LF   	          	          	                    
          	               	1         	144B4     	P3V3_AUX            
          	               	2         	144B4     	PRSNT_SWB           

R4726     	Q_RES_0402LF   	          	          	                    
          	               	1         	144B4     	P3V3_AUX            
          	               	2         	144B4     	PRSNT_SWB_ISO_N     

R4727     	Q_RES_0402LF   	          	          	                    
          	               	1         	144B4     	P3V3_AUX            
          	               	2         	144B4     	PRSNT_SWB_N         

R4728     	Q_RES_0402LF   	          	          	                    
          	               	1         	227A3     	PRSNT_SWB_ISO_N     
          	               	2         	227A3     	PRSNT_SWB_ISO_R1_N  

R4729     	Q_RES_0402LF   	          	          	                    
          	               	1         	227A3     	GPU_PRSNT_N_ISO     
          	               	2         	227A3     	GPU_PRSNT_N_ISO_R1  

R4730     	Q_RES_0402LF   	          	          	                    
          	               	1         	144B4     	P3V3_AUX            
          	               	2         	144B4     	PRSNT_CABLE_SWB_B2_N

R4731     	Q_RES_0402LF   	          	          	                    
          	               	1         	144B4     	PRSNT_CABLE_SWB_B2_N
          	               	2         	144B4     	GND                 

R4732     	Q_RES_0402LF   	          	          	                    
          	               	1         	144B4     	P3V3_AUX            
          	               	2         	144B4     	PRSNT_CABLE_SWB_B2  

R4733     	Q_RES_0402LF   	          	          	                    
          	               	1         	144B4     	P3V3_AUX            
          	               	2         	144B4     	PRSNT_CABLE_SWB_B2_ISO_N

R4734     	Q_RES_0402LF   	          	          	                    
          	               	1         	227A3     	PRSNT_CABLE_GPU_B3_ISO_N
          	               	2         	227A3     	PRSNT_CABLE_GPU_B3_ISO_R1_N

R4735     	Q_RES_0402LF   	          	          	                    
          	               	1         	227A3     	PRSNT_CABLE_SWB_B2_ISO_N
          	               	2         	227A3     	PRSNT_CABLE_SWB_B2_ISO_R_N

R4736     	Q_RES_0402LF   	          	          	                    
          	               	1         	227A3     	PRSNT_CABLE_GPU_A2_ISO_N
          	               	2         	227A3     	PRSNT_CABLE_GPU_A2_ISO_R1_N

R4737     	Q_RES_0402LF   	          	          	                    
          	               	1         	144A4     	P3V3_AUX            
          	               	2         	144A4     	PRSNT_CABLE_SWB_B1_N

R4738     	Q_RES_0402LF   	          	          	                    
          	               	1         	144A4     	PRSNT_CABLE_SWB_B1_N
          	               	2         	144A4     	GND                 

R4739     	Q_RES_0402LF   	          	          	                    
          	               	1         	144B4     	P3V3_AUX            
          	               	2         	144B4     	PRSNT_CABLE_SWB_B1  

R4740     	Q_RES_0402LF   	          	          	                    
          	               	1         	144B3     	P3V3_AUX            
          	               	2         	144B3     	PRSNT_CABLE_SWB_B1_ISO_N

R4741     	Q_RES_0402LF   	          	          	                    
          	               	1         	227A3     	PRSNT_CABLE_SWB_B1_ISO_N
          	               	2         	227A3     	PRSNT_CABLE_SWB_B1_ISO_R_N

R4742     	Q_RES_0402LF   	          	          	                    
          	               	1         	227A3     	PRSNT_CABLE_GPU_A1_ISO_N
          	               	2         	227A3     	PRSNT_CABLE_GPU_A1_ISO_R1_N

R4745     	Q_RES_0402LF   	          	          	                    
          	               	1         	158A3     	P3V3_AUX            
          	               	2         	158A3     	OCP_SFF_AUX_PWR_PLD_EN_R

R4746     	Q_RES_0402LF   	          	          	                    
          	               	1         	158A3     	HP_LVC3_OCP_V3_1_PWRGD_R
          	               	2         	158A3     	HP_LVC3_OCP_V3_1_PWRGD_R2

R4747     	Q_RES_0402LF   	          	          	                    
          	               	1         	158A3     	OCP_SFF_AUX_PWR_PLD_EN
          	               	2         	158A3     	OCP_SFF_AUX_PWR_PLD_EN_R

R4748     	Q_RES_0402LF   	          	          	                    
          	               	1         	158B2     	HP_LVC3_OCP_V3_1_PWRGD_R2
          	               	2         	158B2     	OCP_SFF_AUX_PWR_EN_R2

R4749     	Q_RES_0402LF   	          	          	                    
          	               	1         	158A2     	OCP_SFF_AUX_PWR_PLD_EN_R
          	               	2         	158A2     	OCP_SFF_AUX_PWR_EN_R2

R4750     	Q_RES_0402LF   	          	          	                    
          	               	1         	158A1     	OCP_SFF_AUX_PWR_EN_R2
          	               	2         	158A1     	OCP_SFF_AUX_PWR_EN  

R4751     	Q_RES_0402LF   	          	          	                    
          	               	1         	216A3     	HP_LVC3_OCP_V3_1_PWRGD_R
          	               	2         	216A3     	HP_LVC3_OCP_V3_1_FUSE_PWRGD

R4752     	Q_RES_0402LF   	          	          	                    
          	               	1         	156A3     	HP_LVC3_OCP_V3_1_PRSNT2_N_R
          	               	2         	156A3     	HP_LVC3_OCP_V3_1_PRSNT2_PLD_N

R4753     	Q_RES_0402LF   	          	          	                    
          	               	1         	162A3     	HP_LVC3_OCP_V3_2_PRSNT2_N_R
          	               	2         	162A3     	HP_LVC3_OCP_V3_2_PRSNT2_PLD_N

R4754     	Q_RES_0402LF   	          	          	                    
          	               	1         	164A3     	HP_LVC3_OCP_V3_2_PWRGD_R
          	               	2         	164A3     	HP_LVC3_OCP_V3_2_PWRGD_R2

R4755     	Q_RES_0402LF   	          	          	                    
          	               	1         	164A3     	OCP_V3_2_AUX_PWR_PLD_EN
          	               	2         	164A3     	OCP_V3_2_AUX_PWR_PLD_EN_R

R4756     	Q_RES_0402LF   	          	          	                    
          	               	1         	164A2     	P3V3_AUX            
          	               	2         	164A2     	OCP_V3_2_AUX_PWR_PLD_EN_R

R4757     	Q_RES_0402LF   	          	          	                    
          	               	1         	164A2     	HP_LVC3_OCP_V3_2_PWRGD_R2
          	               	2         	164A2     	OCP_V3_2_AUX_PWR_EN_R2

R4758     	Q_RES_0402LF   	          	          	                    
          	               	1         	164A2     	OCP_V3_2_AUX_PWR_PLD_EN_R
          	               	2         	164A2     	OCP_V3_2_AUX_PWR_EN_R2

R4759     	Q_RES_0402LF   	          	          	                    
          	               	1         	164A1     	OCP_V3_2_AUX_PWR_EN_R2
          	               	2         	164A1     	OCP_V3_2_AUX_PWR_EN 

R4760     	Q_RES_0402LF   	          	          	                    
          	               	1         	216A3     	HP_LVC3_OCP_V3_2_PWRGD_R
          	               	2         	216A3     	HP_LVC3_OCP_V3_2_FUSE_PWRGD

R4761     	Q_RES_0402LF   	          	          	                    
          	               	1         	162A2     	P3V3_AUX            
          	               	2         	162A2     	HP_LVC3_OCP_V3_2_PRSNT2_PLD_N

R4762     	Q_RES_0402LF   	          	          	                    
          	               	1         	156A2     	P3V3_AUX            
          	               	2         	156A2     	HP_LVC3_OCP_V3_1_PRSNT2_PLD_N

R4763     	Q_RES_0402LF   	          	          	                    
          	               	1         	164B3     	P3V3_AUX            
          	               	2         	164B3     	HP_OCP_V3_2_EN      

R4764     	Q_RES_0402LF   	          	          	                    
          	               	1         	158B3     	P3V3_AUX            
          	               	2         	158B3     	HP_OCP_V3_1_EN      

R4765     	Q_RES_0402LF   	          	          	                    
          	               	1         	216A3     	HP_LVC3_E1S_0_HSC_PWRGD
          	               	2         	216A3     	HP_LVC3_E1S_0_HSC_PWRGD_PLD

R4766     	Q_RES_0402LF   	          	          	                    
          	               	1         	183B4     	E1S_0_CLK_OE_N      
          	               	2         	183B4     	E1S_0_CLKREQ_N      

R4767     	Q_RES_0402LF   	          	          	                    
          	               	1         	191A4     	HP_E1S_0_P3V3_PWRGD 
          	               	2         	191A4     	HP_E1S_0_P3V3_PWRGD_PLD

R4768     	Q_RES_0402LF   	          	          	                    
          	               	1         	183A2     	E1S_0_CLK_OE_N      
          	               	2         	183A1     	P3V3_AUX            

R4769     	Q_RES_0402LF   	          	          	                    
          	               	1         	245A4     	FM_PDB_BUF_EN_R     
          	               	2         	245A4     	GND                 

R4770     	Q_RES_0402LF   	          	          	                    
          	               	1         	242A2     	HP_LVC3_SCM_HSC_PWRGD_R
          	               	2         	242A2     	HP_LVC3_SCM_HSC_PWRGD

R4771     	Q_RES_0402LF   	          	          	                    
          	               	1         	216A3     	HP_LVC3_SCM_HSC_PWRGD
          	               	2         	216A3     	HP_LVC3_SCM_HSC_PWRGD_PLD

R4772     	Q_RES_0402LF   	          	          	                    
          	               	1         	307B4     	P3V3_AUX            
          	               	2         	307B4     	UV_ADR_P2V5_COMP    

R4773     	Q_RES_0402LF   	          	          	                    
          	               	1         	307B4     	P3V3_AUX            
          	               	2         	307B4     	UV_P2V5_COMP        

R4774     	Q_RES_0402LF   	          	          	                    
          	               	1         	307B4     	P12V_AUX            
          	               	2         	307B4     	P12V_AUX_UV_ADR_TRIGGER

R4775     	Q_RES_0402LF   	          	          	                    
          	               	1         	307B4     	P12V_AUX_UV_ADR_TRIGGER
          	               	2         	307B4     	GND                 

R4776     	Q_RES_0402LF   	          	          	                    
          	               	1         	307B4     	P12V_AUX            
          	               	2         	307B4     	P12V_AUX_UV_TRIGGER 

R4777     	Q_RES_0402LF   	          	          	                    
          	               	1         	307B4     	P12V_AUX_UV_TRIGGER 
          	               	2         	307A4     	GND                 

R4778     	Q_RES_0402LF   	          	          	                    
          	               	1         	307B3     	P12V_AUX_UV_ADR_TRIGGER
          	               	2         	307B3     	FM_UV_ADR_TRIGGER_N_R2

R4779     	Q_RES_0402LF   	          	          	                    
          	               	1         	307B3     	P12V_AUX_UV_TRIGGER 
          	               	2         	307B3     	IRQ_UV_DETECT_R2_N  

R4780     	Q_RES_0402LF   	          	          	                    
          	               	1         	262B2     	PWRGD_P1V05_PCH_AUX_R
          	               	2         	262B2     	PWRGD_PVNN_PCH_AUX  

R4781     	Q_RES_0402LF   	          	          	                    
          	               	1         	292B4     	PWRGD_PVCCINFAON_CPU1
          	               	2         	292B4     	PWRGD_PVCCINFAON_CPU1_R

R4782     	Q_RES_0402LF   	          	          	                    
          	               	1         	307B2     	FM_UV_ADR_TRIGGER_N_R2
          	               	2         	307B2     	FM_UV_ADR_TRIGGER_N 

R4783     	Q_RES_0402LF   	          	          	                    
          	               	1         	307B2     	IRQ_UV_DETECT_R2_N  
          	               	2         	307B2     	IRQ_UV_DETECT_N     

R4784     	Q_RES_0402LF   	          	          	                    
          	               	1         	307B2     	P3V3_AUX            
          	               	2         	307B2     	FM_UV_ADR_TRIGGER_N 

R4785     	Q_RES_0402LF   	          	          	                    
          	               	1         	307B2     	P3V3_AUX            
          	               	2         	307B2     	IRQ_UV_DETECT_N     

R4786     	Q_RES_0402LF   	          	          	                    
          	               	1         	307A4     	P3V3_AUX            
          	               	2         	307A4     	DSW_PWROK_P2V5_COMP 

R4787     	Q_RES_0402LF   	          	          	                    
          	               	1         	307A3     	PWRGD_DSW_PWROK_TRIGGER
          	               	2         	307A3     	PWRGD_DSW_PWROK_R5  

R4788     	Q_RES_0402LF   	          	          	                    
          	               	1         	307A2     	PWRGD_DSW_PWROK_R5  
          	               	2         	307A2     	PWRGD_DSW_PWROK     

R4789     	Q_RES_0402LF   	          	          	                    
          	               	1         	307A2     	P3V3_AUX            
          	               	2         	307A2     	PWRGD_DSW_PWROK     

R4790     	Q_RES_0402LF   	          	          	                    
          	               	1         	307A4     	P12V_AUX            
          	               	2         	307A4     	PWRGD_DSW_PWROK_TRIGGER

R4791     	Q_RES_0402LF   	          	          	                    
          	               	1         	307A4     	PWRGD_DSW_PWROK_TRIGGER
          	               	2         	307A4     	GND                 

R4792     	Q_RES_0402LF   	          	          	                    
          	               	1         	306B4     	P3V3_AUX            
          	               	2         	306B4     	OC_P2V5_COMP        

R4793     	Q_RES_0402LF   	          	          	                    
          	               	1         	306B3     	HSC_OC_VOL          
          	               	2         	306B3     	HSC_D_OC_R2         

R4794     	Q_RES_0402LF   	          	          	                    
          	               	1         	306B2     	HSC_D_OC_R2         
          	               	2         	306B2     	A_HSC_LOW_GATE      

R4795     	Q_RES_0402LF   	          	          	                    
          	               	1         	306B4     	HSC_CSOUT           
          	               	2         	306B4     	HSC_OC_VOL          

R4796     	Q_RES_0402LF   	          	          	                    
          	               	1         	306B4     	HSC_OC_VOL          
          	               	2         	306B4     	GND                 

R4797     	Q_RES_0402LF   	          	          	                    
          	               	1         	306B2     	P3V3_AUX            
          	               	2         	306B2     	A_HSC_LOW_GATE      

R4798     	Q_RES_0402LF   	          	          	                    
          	               	1         	144A4     	P3V3_AUX            
          	               	2         	144A4     	PRSNT_CABLE_GPU_A3_N

R4799     	Q_RES_0402LF   	          	          	                    
          	               	1         	144A4     	PRSNT_CABLE_GPU_A3_N
          	               	2         	144A4     	GND                 

R4800     	Q_RES_0402LF   	          	          	                    
          	               	1         	144A4     	P3V3_AUX            
          	               	2         	144A4     	PRSNT_CABLE_GPU_A3  

R4801     	Q_RES_0402LF   	          	          	                    
          	               	1         	144A3     	P3V3_AUX            
          	               	2         	144A3     	PRSNT_CABLE_GPU_A3_ISO_N

R4802     	Q_RES_0402LF   	          	          	                    
          	               	1         	227A3     	PRSNT_CABLE_GPU_A3_ISO_N
          	               	2         	227A3     	PRSNT_CABLE_GPU_A3_ISO_R_N

R4803     	Q_RES_0402LF   	          	          	                    
          	               	1         	189B2     	P1V05_PCH_AUX       
          	               	2         	189B2     	P1V05_PCH_PLL_AUX   

R4804     	Q_RES_0402LF   	          	          	                    
          	               	1         	306A4     	P3V3_AUX            
          	               	2         	306A4     	U205_VDD            

R4805     	Q_RES_0402LF   	          	          	                    
          	               	1         	306B3     	P3V3_AUX            
          	               	2         	306B3     	U369_VDD            

R4806     	Q_RES_0402LF   	          	          	                    
          	               	1         	306B3     	P12V_AUX            
          	               	2         	306B3     	U206_VDD            

R4892     	Q_RES_0402LF   	          	          	                    
          	               	1         	305A3     	P12V_HSC_TEMP_R     
          	               	2         	305A3     	P12V_HSC_TEMP_D+    

R4893     	Q_RES_0402LF   	          	          	                    
          	               	1         	305A3     	P12V_HSC_TEMP_E     
          	               	2         	305A3     	P12V_HSC_TEMP_D-    

R4894     	Q_RES_0402LF   	          	          	                    
          	               	1         	305A1     	P12V_HSC_TEMP_SCL   
          	               	2         	305A1     	SMB_LM75_0_3V3AUX_SCL

R4895     	Q_RES_0402LF   	          	          	                    
          	               	1         	305A1     	P12V_HSC_TEMP_SDA   
          	               	2         	305A1     	SMB_LM75_0_3V3AUX_SDA

R4896     	Q_RES_0402LF   	          	          	                    
          	               	1         	305A2     	P12V_HSC_T_CRIT_N   
          	               	2         	305A2     	P12V_HSC_T_CRIT_R_N 

R4901     	Q_RES_0402LF   	          	          	                    
          	               	1         	301A4     	P12V_PSU_FUSE       
          	               	2         	301A4     	HSC_EN              

R5234     	Q_RES_0402LF   	          	          	                    
          	               	1         	152A2     	USB2_HUB_BUF_SWB_R_DP
          	               	2         	152A2     	USB2_HUB_BUF_SWB_DP 

R5236     	Q_RES_0402LF   	          	          	                    
          	               	1         	152A2     	USB2_HUB_BUF_SWB_R_DN
          	               	2         	152A2     	USB2_HUB_BUF_SWB_DN 

R5238     	Q_RES_0402LF   	          	          	                    
          	               	1         	152A3     	PD_U5201_EQ         
          	               	2         	152A3     	GND                 

R5377     	Q_RES_0402LF   	          	          	                    
          	               	1         	190A2     	HDD_ACTIVITY_BUF_N  
          	               	2         	190A2     	PU_BUFFER_HDD_ACTIVITY

R5487     	Q_RES_0402LF   	          	          	                    
          	               	1         	156B4     	HP_LVC3_OCP_V3_1_EN 
          	               	2         	156B4     	P3V3_OCP_EN_1_R     

SW5       	SW_PUSHBUTTON4P_24	          	          	                    
          	               	1         	201B3     	PD_RST_RTCRST_N     
          	               	2         	201B3     	PD_RST_RTCRST_N     
          	               	3         	201B2     	RST_RTCRST_N        
          	               	4         	201B2     	RST_RTCRST_N        

U1        	SOCKET4677_AZIF0045P001C01CS	          	          	                    
          	               	A9        	51B2      	M_A_CPU1_SB_DQS_DN<3>
          	               	A11       	73A2      	GND                 
          	               	A13       	73A2      	GND                 
          	               	A15       	52B2      	M_B_CPU1_SB_DQS_DN<3>
          	               	A17       	73A2      	GND                 
          	               	A19       	73A2      	GND                 
          	               	A21       	51B2      	M_A_CPU1_SB_DQS_DN<2>
          	               	A23       	73A2      	GND                 
          	               	A25       	73A2      	GND                 
          	               	A27       	51B2      	M_A_CPU1_SB_DQS_DN<1>
          	               	A29       	73A2      	GND                 
          	               	A31       	73A2      	GND                 
          	               	A33       	51B2      	M_A_CPU1_SB_DQS_DN<9>
          	               	A35       	73A2      	GND                 
          	               	A37       	73A2      	GND                 
          	               	A39       	51B2      	M_A_CPU1_SB_CA<6>   
          	               	A41       	73A2      	GND                 
          	               	A43       	45B3      	PWRGD_DRAMPWRGD_CPU1_AB_LVC1_R
          	               	A50       	73A2      	GND                 
          	               	A52       	51B2      	M_A_CPU1_SA_CA<0>   
          	               	A54       	73A2      	GND                 
          	               	A56       	73A2      	GND                 
          	               	A58       	51B2      	M_A_CPU1_SA_DQS_DN<4>
          	               	A60       	73A2      	GND                 
          	               	A62       	73A2      	GND                 
          	               	A64       	51B2      	M_A_CPU1_SA_DQS_DN<3>
          	               	AA1       	63B2      	UPI_CPU1_CPU0_P0P1_DN<6>
          	               	AA3       	68A1      	PVCCFA_EHV_CPU1     
          	               	AA5       	63B3      	UPI_CPU0_CPU1_P1P0_DN<5>
          	               	AA7       	69B2      	PVCCFA_EHV_FIVRA_CPU1
          	               	AA9       	60B3      	P5E_CPU1_PE0_RX_DN<5>
          	               	AA11      	69B2      	PVCCFA_EHV_FIVRA_CPU1
          	               	AA13      	60B2      	P5E_CPU1_PE0_TX_DN<4>
          	               	AA15      	69B2      	PVCCFA_EHV_FIVRA_CPU1
          	               	AA17      	53B3      	M_C_CPU1_SB_DQ<28>  
          	               	AA19      	73B4      	GND                 
          	               	AA21      	53B2      	M_C_CPU1_SB_DQS_DP<7>
          	               	AA23      	73B4      	GND                 
          	               	AA25      	73B4      	GND                 
          	               	AA27      	52B2      	M_B_CPU1_SB_DQS_DP<5>
          	               	AA29      	73B4      	GND                 
          	               	AA31      	73B4      	GND                 
          	               	AA33      	53B2      	M_C_CPU1_SB_DQS_DP<4>
          	               	AA35      	73B4      	GND                 
          	               	AA37      	73B4      	GND                 
          	               	AA39      	53A2      	M_C_CPU1_SB_PAR     
          	               	AA41      	73B4      	GND                 
          	               	AA43      	73B4      	GND                 
          	               	AA45      	52A3      	M_B_CPU1_CLK_DP<1>  
          	               	AA48      	73B4      	GND                 
          	               	AA50      	73B4      	GND                 
          	               	AA52      	53B2      	M_C_CPU1_SA_CA<1>   
          	               	AA54      	73B4      	GND                 
          	               	AA56      	73B4      	GND                 
          	               	AA58      	52B2      	M_B_CPU1_SA_DQS_DN<8>
          	               	AA60      	73B4      	GND                 
          	               	AA62      	73B4      	GND                 
          	               	AA64      	53B2      	M_C_CPU1_SA_DQS_DN<7>
          	               	AA66      	73B4      	GND                 
          	               	AA68      	73B4      	GND                 
          	               	AA70      	52B2      	M_B_CPU1_SA_DQS_DN<6>
          	               	AA72      	73B4      	GND                 
          	               	AA74      	73B4      	GND                 
          	               	AA76      	53B2      	M_C_CPU1_SA_DQS_DP<5>
          	               	AA78      	73B4      	GND                 
          	               	AA80      	73B4      	GND                 
          	               	AA82      	72A1      	GND                 
          	               	AA84      	72A1      	GND                 
          	               	AA86      	62B2      	P5E_CPU1_PE4_TX_DN<5>
          	               	AA88      	72A1      	GND                 
          	               	AA90      	62B3      	P5E_CPU1_PE4_RX_DP<5>
          	               	AB2       	63B2      	UPI_CPU1_CPU0_P0P1_DP<6>
          	               	AB4       	72A1      	GND                 
          	               	AB6       	63B3      	UPI_CPU0_CPU1_P1P0_DN<6>
          	               	AB8       	72A1      	GND                 
          	               	AB10      	60B3      	P5E_CPU1_PE0_RX_DN<6>
          	               	AB12      	72A1      	GND                 
          	               	AB14      	60B2      	P5E_CPU1_PE0_TX_DN<5>
          	               	AB16      	72A1      	GND                 
          	               	AB18      	53B2      	M_C_CPU1_SB_DQS_DN<3>
          	               	AB20      	72A1      	GND                 
          	               	AB22      	72A1      	GND                 
          	               	AB24      	54B2      	M_D_CPU1_SB_DQS_DN<2>
          	               	AB26      	72A1      	GND                 
          	               	AB28      	72A1      	GND                 
          	               	AB30      	53B2      	M_C_CPU1_SB_DQS_DN<1>
          	               	AB32      	72A1      	GND                 
          	               	AB34      	72A1      	GND                 
          	               	AB36      	53B2      	M_C_CPU1_SB_DQS_DN<0>
          	               	AB38      	72A1      	GND                 
          	               	AB40      	72A1      	GND                 
          	               	AB42      	54B2      	M_D_CPU1_SB_CA<6>   
          	               	AB44      	72A1      	GND                 
          	               	AB47      	72A1      	GND                 
          	               	AB49      	53A3      	M_C_CPU1_CLK_DN<0>  
          	               	AB51      	72A1      	GND                 
          	               	AB53      	72A1      	GND                 
          	               	AB55      	53B2      	M_C_CPU1_SA_DQS_DP<4>
          	               	AB57      	72A1      	GND                 
          	               	AB59      	72A1      	GND                 
          	               	AB61      	53B2      	M_C_CPU1_SA_DQS_DN<3>
          	               	AB63      	72A1      	GND                 
          	               	AB65      	72B1      	GND                 
          	               	AB67      	53B2      	M_C_CPU1_SA_DQS_DN<1>
          	               	AB69      	72B1      	GND                 
          	               	AB71      	72B1      	GND                 
          	               	AB73      	54B2      	M_D_CPU1_SA_DQS_DN<0>
          	               	AB75      	72B1      	GND                 
          	               	AB77      	72B1      	GND                 
          	               	AB79      	72B1      	GND                 
          	               	AB81      	72B1      	GND                 
          	               	AB83      	72B1      	GND                 
          	               	AB85      	62B2      	P5E_CPU1_PE4_TX_DP<5>
          	               	AB87      	72B1      	GND                 
          	               	AB89      	62B3      	P5E_CPU1_PE4_RX_DN<5>
          	               	AB91      	72B1      	GND                 
          	               	AC1       	72B1      	GND                 
          	               	AC3       	63B2      	UPI_CPU1_CPU0_P0P1_DP<7>
          	               	AC5       	72B1      	GND                 
          	               	AC7       	63B3      	UPI_CPU0_CPU1_P1P0_DP<6>
          	               	AC9       	72B1      	GND                 
          	               	AC11      	60B3      	P5E_CPU1_PE0_RX_DP<6>
          	               	AC13      	72B1      	GND                 
          	               	AC15      	60B2      	P5E_CPU1_PE0_TX_DP<5>
          	               	AC17      	53B3      	M_C_CPU1_SB_DQ<30>  
          	               	AC19      	53B3      	M_C_CPU1_SB_DQ<25>  
          	               	AC21      	72B1      	GND                 
          	               	AC23      	54B3      	M_D_CPU1_SB_DQ<20>  
          	               	AC25      	54B3      	M_D_CPU1_SB_DQ<17>  
          	               	AC27      	72B1      	GND                 
          	               	AC29      	53B3      	M_C_CPU1_SB_DQ<12>  
          	               	AC31      	53A3      	M_C_CPU1_SB_DQ<9>   
          	               	AC33      	72B1      	GND                 
          	               	AC35      	53A3      	M_C_CPU1_SB_DQ<4>   
          	               	AC37      	53A3      	M_C_CPU1_SB_DQ<1>   
          	               	AC39      	72B1      	GND                 
          	               	AC41      	54A2      	M_D_CPU1_SB_CS_N<0> 
          	               	AC43      	54B2      	M_D_CPU1_SB_CA<4>   
          	               	AC45      	72B1      	GND                 
          	               	AC48      	53A2      	M_C_CPU1_SA_RSP<0>  
          	               	AC50      	54A2      	M_D_CPU1_SA_RSP<1>  
          	               	AC52      	72B1      	GND                 
          	               	AC54      	53B3      	M_C_CPU1_SA_CB<4>   
          	               	AC56      	53B3      	M_C_CPU1_SA_CB<1>   
          	               	AC58      	72B1      	GND                 
          	               	AC60      	53B3      	M_C_CPU1_SA_DQ<28>  
          	               	AC62      	53B3      	M_C_CPU1_SA_DQ<25>  
          	               	AC64      	72B1      	GND                 
          	               	AC66      	53B3      	M_C_CPU1_SA_DQ<12>  
          	               	AC68      	53B3      	M_C_CPU1_SA_DQ<9>   
          	               	AC70      	72B1      	GND                 
          	               	AC72      	54B3      	M_D_CPU1_SA_DQ<4>   
          	               	AC74      	54B3      	M_D_CPU1_SA_DQ<1>   
          	               	AC76      	72B1      	GND                 
          	               	AC78      	48B3      	NC_CPU1_HBM2_VIEWDIG0
          	               	AC80      	65B3      	UPI_CPU0_CPU1_P2P2_DN<6>
          	               	AC82      	65B3      	UPI_CPU0_CPU1_P2P2_DP<7>
          	               	AC84      	72B1      	GND                 
          	               	AC86      	62B2      	P5E_CPU1_PE4_TX_DN<6>
          	               	AC88      	72B1      	GND                 
          	               	AC90      	62B3      	P5E_CPU1_PE4_RX_DP<6>
          	               	AD2       	63B2      	UPI_CPU1_CPU0_P0P1_DN<7>
          	               	AD4       	72B1      	GND                 
          	               	AD6       	63B3      	UPI_CPU0_CPU1_P1P0_DP<7>
          	               	AD8       	72B1      	GND                 
          	               	AD10      	60B3      	P5E_CPU1_PE0_RX_DP<7>
          	               	AD12      	72B1      	GND                 
          	               	AD14      	60B2      	P5E_CPU1_PE0_TX_DP<6>
          	               	AD16      	72B1      	GND                 
          	               	AD18      	53B2      	M_C_CPU1_SB_DQS_DP<3>
          	               	AD20      	53B3      	M_C_CPU1_SB_DQ<24>  
          	               	AD22      	54B3      	M_D_CPU1_SB_DQ<21>  
          	               	AD24      	54B2      	M_D_CPU1_SB_DQS_DP<2>
          	               	AD26      	54B3      	M_D_CPU1_SB_DQ<16>  
          	               	AD28      	53B3      	M_C_CPU1_SB_DQ<13>  
          	               	AD30      	53B2      	M_C_CPU1_SB_DQS_DP<1>
          	               	AD32      	53A3      	M_C_CPU1_SB_DQ<8>   
          	               	AD34      	53A3      	M_C_CPU1_SB_DQ<5>   
          	               	AD36      	53B2      	M_C_CPU1_SB_DQS_DP<0>
          	               	AD38      	53A3      	M_C_CPU1_SB_DQ<0>   
          	               	AD40      	54A2      	M_D_CPU1_SB_CS_N<3> 
          	               	AD42      	72B1      	GND                 
          	               	AD44      	54B2      	M_D_CPU1_SB_CA<2>   
          	               	AD47      	53A2      	M_C_CPU1_SA_RSP<1>  
          	               	AD49      	53A3      	M_C_CPU1_CLK_DP<0>  
          	               	AD51      	54A2      	M_D_CPU1_SA_RSP<0>  
          	               	AD53      	53B3      	M_C_CPU1_SA_CB<5>   
          	               	AD55      	53B2      	M_C_CPU1_SA_DQS_DN<4>
          	               	AD57      	53B3      	M_C_CPU1_SA_CB<0>   
          	               	AD59      	53B3      	M_C_CPU1_SA_DQ<29>  
          	               	AD61      	53B2      	M_C_CPU1_SA_DQS_DP<3>
          	               	AD63      	53B3      	M_C_CPU1_SA_DQ<24>  
          	               	AD65      	53B3      	M_C_CPU1_SA_DQ<13>  
          	               	AD67      	53B2      	M_C_CPU1_SA_DQS_DP<1>
          	               	AD69      	53B3      	M_C_CPU1_SA_DQ<8>   
          	               	AD71      	54B3      	M_D_CPU1_SA_DQ<5>   
          	               	AD73      	54B2      	M_D_CPU1_SA_DQS_DP<0>
          	               	AD75      	54B3      	M_D_CPU1_SA_DQ<0>   
          	               	AD77      	48B3      	NC_CPU1_HBM2_VIEWDIG1
          	               	AD79      	72B1      	GND                 
          	               	AD81      	65B3      	UPI_CPU0_CPU1_P2P2_DN<7>
          	               	AD83      	72B1      	GND                 
          	               	AD85      	69B2      	PVCCFA_EHV_FIVRA_CPU1
          	               	AD87      	62B2      	P5E_CPU1_PE4_TX_DP<6>
          	               	AD89      	69B2      	PVCCFA_EHV_FIVRA_CPU1
          	               	AD91      	62B3      	P5E_CPU1_PE4_RX_DN<6>
          	               	AE1       	63B2      	UPI_CPU1_CPU0_P0P1_DP<8>
          	               	AE3       	68A1      	PVCCFA_EHV_CPU1     
          	               	AE5       	63B3      	UPI_CPU0_CPU1_P1P0_DN<7>
          	               	AE7       	69B2      	PVCCFA_EHV_FIVRA_CPU1
          	               	AE9       	60B3      	P5E_CPU1_PE0_RX_DN<7>
          	               	AE11      	69B2      	PVCCFA_EHV_FIVRA_CPU1
          	               	AE13      	60B2      	P5E_CPU1_PE0_TX_DN<6>
          	               	AE15      	69B2      	PVCCFA_EHV_FIVRA_CPU1
          	               	AE17      	72B1      	GND                 
          	               	AE19      	72B1      	GND                 
          	               	AE21      	72B1      	GND                 
          	               	AE23      	72B1      	GND                 
          	               	AE25      	72B1      	GND                 
          	               	AE27      	72B1      	GND                 
          	               	AE29      	72B1      	GND                 
          	               	AE31      	72B1      	GND                 
          	               	AE33      	72B1      	GND                 
          	               	AE35      	72B1      	GND                 
          	               	AE37      	72B1      	GND                 
          	               	AE39      	72B1      	GND                 
          	               	AE41      	72B1      	GND                 
          	               	AE43      	72B1      	GND                 
          	               	AE45      	72B1      	GND                 
          	               	AE48      	72B1      	GND                 
          	               	AE50      	72B1      	GND                 
          	               	AE52      	72B1      	GND                 
          	               	AE54      	72B1      	GND                 
          	               	AE56      	72B1      	GND                 
          	               	AE58      	72B1      	GND                 
          	               	AE60      	72B1      	GND                 
          	               	AE62      	72B1      	GND                 
          	               	AE64      	72B1      	GND                 
          	               	AE66      	72B1      	GND                 
          	               	AE68      	72A2      	GND                 
          	               	AE70      	72A2      	GND                 
          	               	AE72      	72A2      	GND                 
          	               	AE74      	72A2      	GND                 
          	               	AE76      	72A2      	GND                 
          	               	AE78      	72A2      	GND                 
          	               	AE80      	65B3      	UPI_CPU0_CPU1_P2P2_DP<6>
          	               	AE82      	65B3      	UPI_CPU0_CPU1_P2P2_DN<9>
          	               	AE84      	72A2      	GND                 
          	               	AE86      	62B2      	P5E_CPU1_PE4_TX_DN<7>
          	               	AE88      	72A2      	GND                 
          	               	AE90      	62B3      	P5E_CPU1_PE4_RX_DP<7>
          	               	AF2       	63B2      	UPI_CPU1_CPU0_P0P1_DN<8>
          	               	AF4       	72A2      	GND                 
          	               	AF6       	63B3      	UPI_CPU0_CPU1_P1P0_DN<8>
          	               	AF8       	72A2      	GND                 
          	               	AF10      	60B3      	P5E_CPU1_PE0_RX_DN<8>
          	               	AF12      	72A2      	GND                 
          	               	AF14      	60B2      	P5E_CPU1_PE0_TX_DN<7>
          	               	AF16      	72A2      	GND                 
          	               	AF18      	53B2      	M_C_CPU1_SB_DQS_DN<8>
          	               	AF20      	53B3      	M_C_CPU1_SB_DQ<26>  
          	               	AF22      	54B3      	M_D_CPU1_SB_DQ<23>  
          	               	AF24      	54B2      	M_D_CPU1_SB_DQS_DN<7>
          	               	AF26      	54B3      	M_D_CPU1_SB_DQ<18>  
          	               	AF28      	53B3      	M_C_CPU1_SB_DQ<15>  
          	               	AF30      	53B2      	M_C_CPU1_SB_DQS_DN<6>
          	               	AF32      	53A3      	M_C_CPU1_SB_DQ<10>  
          	               	AF34      	53A3      	M_C_CPU1_SB_DQ<7>   
          	               	AF36      	53B2      	M_C_CPU1_SB_DQS_DN<5>
          	               	AF38      	53A3      	M_C_CPU1_SB_DQ<2>   
          	               	AF40      	54A2      	M_D_CPU1_SB_CS_N<2> 
          	               	AF42      	72A2      	GND                 
          	               	AF44      	54B2      	M_D_CPU1_SB_CA<3>   
          	               	AF47      	53A2      	M_C_CPU1_SB_RSP<1>  
          	               	AF49      	53A3      	M_C_CPU1_CLK_DN<1>  
          	               	AF51      	54A2      	M_D_CPU1_SB_RSP<0>  
          	               	AF53      	53B3      	M_C_CPU1_SA_CB<7>   
          	               	AF55      	53B2      	M_C_CPU1_SA_DQS_DP<9>
          	               	AF57      	53B3      	M_C_CPU1_SA_CB<2>   
          	               	AF59      	53B3      	M_C_CPU1_SA_DQ<31>  
          	               	AF61      	53B2      	M_C_CPU1_SA_DQS_DN<8>
          	               	AF63      	53B3      	M_C_CPU1_SA_DQ<26>  
          	               	AF65      	53B3      	M_C_CPU1_SA_DQ<15>  
          	               	AF67      	53B2      	M_C_CPU1_SA_DQS_DP<6>
          	               	AF69      	53B3      	M_C_CPU1_SA_DQ<10>  
          	               	AF71      	54B3      	M_D_CPU1_SA_DQ<7>   
          	               	AF73      	54B2      	M_D_CPU1_SA_DQS_DP<5>
          	               	AF75      	54B3      	M_D_CPU1_SA_DQ<2>   
          	               	AF77      	69B2      	PVCCFA_EHV_FIVRA_CPU1
          	               	AF79      	65B3      	UPI_CPU0_CPU1_P2P2_DN<8>
          	               	AF81      	72A2      	GND                 
          	               	AF83      	65B3      	UPI_CPU0_CPU1_P2P2_DP<9>
          	               	AF85      	62B2      	P5E_CPU1_PE4_TX_DP<7>
          	               	AF87      	72A2      	GND                 
          	               	AF89      	62B3      	P5E_CPU1_PE4_RX_DN<7>
          	               	AF91      	72A2      	GND                 
          	               	AG1       	72A2      	GND                 
          	               	AG3       	63B2      	UPI_CPU1_CPU0_P0P1_DP<9>
          	               	AG5       	72A2      	GND                 
          	               	AG7       	63B3      	UPI_CPU0_CPU1_P1P0_DP<8>
          	               	AG9       	72A2      	GND                 
          	               	AG11      	60B3      	P5E_CPU1_PE0_RX_DP<8>
          	               	AG13      	72A2      	GND                 
          	               	AG15      	60B2      	P5E_CPU1_PE0_TX_DP<7>
          	               	AG17      	53B3      	M_C_CPU1_SB_DQ<29>  
          	               	AG19      	53B3      	M_C_CPU1_SB_DQ<27>  
          	               	AG21      	72A2      	GND                 
          	               	AG23      	54B3      	M_D_CPU1_SB_DQ<22>  
          	               	AG25      	54B3      	M_D_CPU1_SB_DQ<19>  
          	               	AG27      	72A2      	GND                 
          	               	AG29      	53B3      	M_C_CPU1_SB_DQ<14>  
          	               	AG31      	53B3      	M_C_CPU1_SB_DQ<11>  
          	               	AG33      	72B2      	GND                 
          	               	AG35      	53A3      	M_C_CPU1_SB_DQ<6>   
          	               	AG37      	53A3      	M_C_CPU1_SB_DQ<3>   
          	               	AG39      	72B2      	GND                 
          	               	AG41      	54A2      	M_D_CPU1_SB_CS_N<1> 
          	               	AG43      	54B2      	M_D_CPU1_SB_CA<5>   
          	               	AG45      	72B2      	GND                 
          	               	AG48      	53A2      	M_C_CPU1_SB_RSP<0>  
          	               	AG50      	54A2      	M_D_CPU1_SB_RSP<1>  
          	               	AG52      	72B2      	GND                 
          	               	AG54      	53B3      	M_C_CPU1_SA_CB<6>   
          	               	AG56      	53B3      	M_C_CPU1_SA_CB<3>   
          	               	AG58      	72B2      	GND                 
          	               	AG60      	53B3      	M_C_CPU1_SA_DQ<30>  
          	               	AG62      	53B3      	M_C_CPU1_SA_DQ<27>  
          	               	AG64      	72B2      	GND                 
          	               	AG66      	53B3      	M_C_CPU1_SA_DQ<14>  
          	               	AG68      	53B3      	M_C_CPU1_SA_DQ<11>  
          	               	AG70      	72B2      	GND                 
          	               	AG72      	54B3      	M_D_CPU1_SA_DQ<6>   
          	               	AG74      	54B3      	M_D_CPU1_SA_DQ<3>   
          	               	AG76      	72B2      	GND                 
          	               	AG78      	69B2      	PVCCFA_EHV_FIVRA_CPU1
          	               	AG80      	65B3      	UPI_CPU0_CPU1_P2P2_DP<8>
          	               	AG82      	65B3      	UPI_CPU0_CPU1_P2P2_DN<11>
          	               	AG84      	72B2      	GND                 
          	               	AG86      	62B2      	P5E_CPU1_PE4_TX_DN<8>
          	               	AG88      	72B2      	GND                 
          	               	AG90      	62B3      	P5E_CPU1_PE4_RX_DP<8>
          	               	AH2       	63B2      	UPI_CPU1_CPU0_P0P1_DN<9>
          	               	AH4       	72B2      	GND                 
          	               	AH6       	63B3      	UPI_CPU0_CPU1_P1P0_DN<9>
          	               	AH8       	72B2      	GND                 
          	               	AH10      	60B3      	P5E_CPU1_PE0_RX_DP<9>
          	               	AH12      	72B2      	GND                 
          	               	AH14      	60B2      	P5E_CPU1_PE0_TX_DP<8>
          	               	AH16      	72B2      	GND                 
          	               	AH18      	53B2      	M_C_CPU1_SB_DQS_DP<8>
          	               	AH20      	72B2      	GND                 
          	               	AH22      	72B2      	GND                 
          	               	AH24      	54B2      	M_D_CPU1_SB_DQS_DP<7>
          	               	AH26      	72B2      	GND                 
          	               	AH28      	72B2      	GND                 
          	               	AH30      	53B2      	M_C_CPU1_SB_DQS_DP<6>
          	               	AH32      	72B2      	GND                 
          	               	AH34      	72B2      	GND                 
          	               	AH36      	53B2      	M_C_CPU1_SB_DQS_DP<5>
          	               	AH38      	72B2      	GND                 
          	               	AH40      	72B2      	GND                 
          	               	AH42      	54A2      	M_D_CPU1_SB_PAR     
          	               	AH44      	72B2      	GND                 
          	               	AH47      	72B2      	GND                 
          	               	AH49      	53A3      	M_C_CPU1_CLK_DP<1>  
          	               	AH51      	72B2      	GND                 
          	               	AH53      	72B2      	GND                 
          	               	AH55      	53B2      	M_C_CPU1_SA_DQS_DN<9>
          	               	AH57      	72B2      	GND                 
          	               	AH59      	72B2      	GND                 
          	               	AH61      	53B2      	M_C_CPU1_SA_DQS_DP<8>
          	               	AH63      	72B2      	GND                 
          	               	AH65      	72B2      	GND                 
          	               	AH67      	53B2      	M_C_CPU1_SA_DQS_DN<6>
          	               	AH69      	72B2      	GND                 
          	               	AH71      	72B2      	GND                 
          	               	AH73      	54B2      	M_D_CPU1_SA_DQS_DN<5>
          	               	AH75      	72B2      	GND                 
          	               	AH77      	72B2      	GND                 
          	               	AH79      	72B2      	GND                 
          	               	AH81      	65B3      	UPI_CPU0_CPU1_P2P2_DP<10>
          	               	AH83      	72B2      	GND                 
          	               	AH85      	69B2      	PVCCFA_EHV_FIVRA_CPU1
          	               	AH87      	62B2      	P5E_CPU1_PE4_TX_DP<8>
          	               	AH89      	69B2      	PVCCFA_EHV_FIVRA_CPU1
          	               	AH91      	62B3      	P5E_CPU1_PE4_RX_DN<8>
          	               	AJ1       	63B2      	UPI_CPU1_CPU0_P0P1_DP<10>
          	               	AJ3       	68A1      	PVCCFA_EHV_CPU1     
          	               	AJ5       	63B3      	UPI_CPU0_CPU1_P1P0_DP<9>
          	               	AJ7       	69B2      	PVCCFA_EHV_FIVRA_CPU1
          	               	AJ9       	60B3      	P5E_CPU1_PE0_RX_DN<9>
          	               	AJ11      	69B2      	PVCCFA_EHV_FIVRA_CPU1
          	               	AJ13      	60B2      	P5E_CPU1_PE0_TX_DN<8>
          	               	AJ15      	69B2      	PVCCFA_EHV_FIVRA_CPU1
          	               	AJ17      	53B3      	M_C_CPU1_SB_DQ<31>  
          	               	AJ19      	72B2      	GND                 
          	               	AJ21      	54B2      	M_D_CPU1_SB_DQS_DN<3>
          	               	AJ23      	72B2      	GND                 
          	               	AJ25      	72B2      	GND                 
          	               	AJ27      	54B2      	M_D_CPU1_SB_DQS_DN<1>
          	               	AJ29      	72B2      	GND                 
          	               	AJ31      	72B2      	GND                 
          	               	AJ33      	54B2      	M_D_CPU1_SB_DQS_DN<0>
          	               	AJ35      	72B2      	GND                 
          	               	AJ37      	72B2      	GND                 
          	               	AJ39      	54B2      	M_D_CPU1_SB_DQS_DN<9>
          	               	AJ41      	72B2      	GND                 
          	               	AJ43      	72B2      	GND                 
          	               	AJ45      	54A3      	M_D_CPU1_CLK_DN<0>  
          	               	AJ48      	72B2      	GND                 
          	               	AJ50      	72B2      	GND                 
          	               	AJ52      	54B2      	M_D_CPU1_SA_CA<0>   
          	               	AJ54      	72B2      	GND                 
          	               	AJ56      	72B2      	GND                 
          	               	AJ58      	54B2      	M_D_CPU1_SA_DQS_DN<4>
          	               	AJ60      	72B2      	GND                 
          	               	AJ62      	72B2      	GND                 
          	               	AJ64      	54B2      	M_D_CPU1_SA_DQS_DN<3>
          	               	AJ66      	72B2      	GND                 
          	               	AJ68      	72B2      	GND                 
          	               	AJ70      	54B2      	M_D_CPU1_SA_DQS_DN<2>
          	               	AJ72      	72B2      	GND                 
          	               	AJ74      	72B2      	GND                 
          	               	AJ76      	54B2      	M_D_CPU1_SA_DQS_DN<1>
          	               	AJ78      	72B2      	GND                 
          	               	AJ80      	65B3      	UPI_CPU0_CPU1_P2P2_DN<10>
          	               	AJ82      	65B3      	UPI_CPU0_CPU1_P2P2_DP<11>
          	               	AJ84      	72B2      	GND                 
          	               	AJ86      	62B2      	P5E_CPU1_PE4_TX_DN<9>
          	               	AJ88      	72B2      	GND                 
          	               	AJ90      	62B3      	P5E_CPU1_PE4_RX_DP<9>
          	               	AK2       	63B2      	UPI_CPU1_CPU0_P0P1_DN<10>
          	               	AK4       	72A2      	GND                 
          	               	AK6       	63B3      	UPI_CPU0_CPU1_P1P0_DN<10>
          	               	AK8       	72A2      	GND                 
          	               	AK10      	60B3      	P5E_CPU1_PE0_RX_DN<10>
          	               	AK12      	72A2      	GND                 
          	               	AK14      	60B2      	P5E_CPU1_PE0_TX_DN<9>
          	               	AK16      	72A2      	GND                 
          	               	AK18      	72A2      	GND                 
          	               	AK20      	54B3      	M_D_CPU1_SB_DQ<28>  
          	               	AK22      	54B3      	M_D_CPU1_SB_DQ<25>  
          	               	AK24      	72A2      	GND                 
          	               	AK26      	54B3      	M_D_CPU1_SB_DQ<12>  
          	               	AK28      	54A3      	M_D_CPU1_SB_DQ<9>   
          	               	AK30      	72A2      	GND                 
          	               	AK32      	54A3      	M_D_CPU1_SB_DQ<4>   
          	               	AK34      	54A3      	M_D_CPU1_SB_DQ<1>   
          	               	AK36      	72A2      	GND                 
          	               	AK38      	54A3      	M_D_CPU1_SB_CB<0>   
          	               	AK40      	54A3      	M_D_CPU1_SB_CB<5>   
          	               	AK42      	72A2      	GND                 
          	               	AK44      	54A2      	M_D_CPU1_SB_CA<0>   
          	               	AK47      	52A2      	M_B_CPU1_SA_RSP<1>  
          	               	AK49      	72A2      	GND                 
          	               	AK51      	54B2      	M_D_CPU1_SA_CA<2>   
          	               	AK53      	54A2      	M_D_CPU1_SA_CS_N<1> 
          	               	AK55      	72A2      	GND                 
          	               	AK57      	54B3      	M_D_CPU1_SA_CB<4>   
          	               	AK59      	54B3      	M_D_CPU1_SA_CB<1>   
          	               	AK61      	72A2      	GND                 
          	               	AK63      	54B3      	M_D_CPU1_SA_DQ<28>  
          	               	AK65      	54B3      	M_D_CPU1_SA_DQ<25>  
          	               	AK67      	72A2      	GND                 
          	               	AK69      	54B3      	M_D_CPU1_SA_DQ<20>  
          	               	AK71      	54B3      	M_D_CPU1_SA_DQ<17>  
          	               	AK73      	72A2      	GND                 
          	               	AK75      	54B3      	M_D_CPU1_SA_DQ<12>  
          	               	AK77      	54B3      	M_D_CPU1_SA_DQ<9>   
          	               	AK79      	72A2      	GND                 
          	               	AK81      	72A2      	GND                 
          	               	AK83      	72A2      	GND                 
          	               	AK85      	62B2      	P5E_CPU1_PE4_TX_DP<9>
          	               	AK87      	72A2      	GND                 
          	               	AK89      	62B3      	P5E_CPU1_PE4_RX_DN<9>
          	               	AK91      	72A2      	GND                 
          	               	AL1       	72A2      	GND                 
          	               	AL3       	63B2      	UPI_CPU1_CPU0_P0P1_DP<11>
          	               	AL5       	72A2      	GND                 
          	               	AL7       	63B3      	UPI_CPU0_CPU1_P1P0_DP<10>
          	               	AL9       	72A2      	GND                 
          	               	AL11      	60B3      	P5E_CPU1_PE0_RX_DP<10>
          	               	AL13      	72B2      	GND                 
          	               	AL15      	60B2      	P5E_CPU1_PE0_TX_DP<9>
          	               	AL17      	72B2      	GND                 
          	               	AL19      	54B3      	M_D_CPU1_SB_DQ<29>  
          	               	AL21      	54B2      	M_D_CPU1_SB_DQS_DP<3>
          	               	AL23      	54B3      	M_D_CPU1_SB_DQ<24>  
          	               	AL25      	54B3      	M_D_CPU1_SB_DQ<13>  
          	               	AL27      	54B2      	M_D_CPU1_SB_DQS_DP<1>
          	               	AL29      	54A3      	M_D_CPU1_SB_DQ<8>   
          	               	AL31      	54A3      	M_D_CPU1_SB_DQ<5>   
          	               	AL33      	54B2      	M_D_CPU1_SB_DQS_DP<0>
          	               	AL35      	54A3      	M_D_CPU1_SB_DQ<0>   
          	               	AL37      	54A3      	M_D_CPU1_SB_CB<1>   
          	               	AL39      	54B2      	M_D_CPU1_SB_DQS_DP<9>
          	               	AL41      	54A3      	M_D_CPU1_SB_CB<4>   
          	               	AL43      	54A2      	M_D_CPU1_SB_CA<1>   
          	               	AL45      	54A3      	M_D_CPU1_CLK_DP<0>  
          	               	AL48      	52A2      	M_B_CPU1_SA_RSP<0>  
          	               	AL50      	54B2      	M_D_CPU1_SA_CA<4>   
          	               	AL52      	72B2      	GND                 
          	               	AL54      	54A2      	M_D_CPU1_SA_CS_N<0> 
          	               	AL56      	54B3      	M_D_CPU1_SA_CB<5>   
          	               	AL58      	54B2      	M_D_CPU1_SA_DQS_DP<4>
          	               	AL60      	54B3      	M_D_CPU1_SA_CB<0>   
          	               	AL62      	54B3      	M_D_CPU1_SA_DQ<29>  
          	               	AL64      	54B2      	M_D_CPU1_SA_DQS_DP<3>
          	               	AL66      	54B3      	M_D_CPU1_SA_DQ<24>  
          	               	AL68      	54B3      	M_D_CPU1_SA_DQ<21>  
          	               	AL70      	54B2      	M_D_CPU1_SA_DQS_DP<2>
          	               	AL72      	54B3      	M_D_CPU1_SA_DQ<16>  
          	               	AL74      	54B3      	M_D_CPU1_SA_DQ<13>  
          	               	AL76      	54B2      	M_D_CPU1_SA_DQS_DP<1>
          	               	AL78      	54B3      	M_D_CPU1_SA_DQ<8>   
          	               	AL80      	72B2      	GND                 
          	               	AL82      	72B2      	GND                 
          	               	AL84      	72B2      	GND                 
          	               	AL86      	62B2      	P5E_CPU1_PE4_TX_DN<10>
          	               	AL88      	72B2      	GND                 
          	               	AL90      	62B3      	P5E_CPU1_PE4_RX_DP<10>
          	               	AM2       	63B2      	UPI_CPU1_CPU0_P0P1_DN<11>
          	               	AM4       	72B2      	GND                 
          	               	AM6       	63B3      	UPI_CPU0_CPU1_P1P0_DP<11>
          	               	AM8       	72B2      	GND                 
          	               	AM10      	60B3      	P5E_CPU1_PE0_RX_DN<11>
          	               	AM12      	72B2      	GND                 
          	               	AM14      	60B2      	P5E_CPU1_PE0_TX_DP<10>
          	               	AM16      	72B2      	GND                 
          	               	AM18      	72B2      	GND                 
          	               	AM20      	72B2      	GND                 
          	               	AM22      	72B2      	GND                 
          	               	AM24      	72B2      	GND                 
          	               	AM26      	72B2      	GND                 
          	               	AM28      	72B2      	GND                 
          	               	AM30      	72B2      	GND                 
          	               	AM32      	72B2      	GND                 
          	               	AM34      	72B2      	GND                 
          	               	AM36      	72B2      	GND                 
          	               	AM38      	72B2      	GND                 
          	               	AM40      	72B2      	GND                 
          	               	AM42      	72B2      	GND                 
          	               	AM44      	72B2      	GND                 
          	               	AM47      	72B2      	GND                 
          	               	AM49      	72B2      	GND                 
          	               	AM51      	72B2      	GND                 
          	               	AM53      	72B2      	GND                 
          	               	AM55      	72B2      	GND                 
          	               	AM57      	72B2      	GND                 
          	               	AM59      	72B2      	GND                 
          	               	AM61      	72B2      	GND                 
          	               	AM63      	72B2      	GND                 
          	               	AM65      	72B2      	GND                 
          	               	AM67      	72B2      	GND                 
          	               	AM69      	72B2      	GND                 
          	               	AM71      	72B2      	GND                 
          	               	AM73      	72B2      	GND                 
          	               	AM75      	72B2      	GND                 
          	               	AM77      	72B2      	GND                 
          	               	AM79      	69B2      	PVCCFA_EHV_FIVRA_CPU1
          	               	AM81      	65B2      	UPI_CPU1_CPU0_P2P2_DN<12>
          	               	AM83      	65B2      	UPI_CPU1_CPU0_P2P2_DP<13>
          	               	AM85      	69B2      	PVCCFA_EHV_FIVRA_CPU1
          	               	AM87      	62B2      	P5E_CPU1_PE4_TX_DP<10>
          	               	AM89      	69B2      	PVCCFA_EHV_FIVRA_CPU1
          	               	AM91      	62B3      	P5E_CPU1_PE4_RX_DN<10>
          	               	AN1       	63B2      	UPI_CPU1_CPU0_P0P1_DP<12>
          	               	AN3       	68A1      	PVCCFA_EHV_CPU1     
          	               	AN5       	63B3      	UPI_CPU0_CPU1_P1P0_DN<11>
          	               	AN7       	69B2      	PVCCFA_EHV_FIVRA_CPU1
          	               	AN9       	60B3      	P5E_CPU1_PE0_RX_DP<11>
          	               	AN11      	69B2      	PVCCFA_EHV_FIVRA_CPU1
          	               	AN13      	60B2      	P5E_CPU1_PE0_TX_DN<10>
          	               	AN15      	69B2      	PVCCFA_EHV_FIVRA_CPU1
          	               	AN17      	50B3      	NC_CPU1_UPI0_APROBE<0>
          	               	AN19      	54B3      	M_D_CPU1_SB_DQ<31>  
          	               	AN21      	54B2      	M_D_CPU1_SB_DQS_DN<8>
          	               	AN23      	54B3      	M_D_CPU1_SB_DQ<26>  
          	               	AN25      	54B3      	M_D_CPU1_SB_DQ<15>  
          	               	AN27      	54B2      	M_D_CPU1_SB_DQS_DN<6>
          	               	AN29      	54A3      	M_D_CPU1_SB_DQ<10>  
          	               	AN31      	54A3      	M_D_CPU1_SB_DQ<7>   
          	               	AN33      	54B2      	M_D_CPU1_SB_DQS_DN<5>
          	               	AN35      	54A3      	M_D_CPU1_SB_DQ<2>   
          	               	AN37      	54A3      	M_D_CPU1_SB_CB<3>   
          	               	AN39      	54B2      	M_D_CPU1_SB_DQS_DP<4>
          	               	AN41      	54A3      	M_D_CPU1_SB_CB<6>   
          	               	AN43      	54B2      	M_D_CPU1_SA_CA<6>   
          	               	AN45      	54A3      	M_D_CPU1_CLK_DN<1>  
          	               	AN48      	52A2      	M_B_CPU1_SB_RSP<0>  
          	               	AN50      	54B2      	M_D_CPU1_SA_CA<5>   
          	               	AN52      	72B2      	GND                 
          	               	AN54      	54A2      	M_D_CPU1_SA_CS_N<2> 
          	               	AN56      	54B3      	M_D_CPU1_SA_CB<7>   
          	               	AN58      	54B2      	M_D_CPU1_SA_DQS_DN<9>
          	               	AN60      	54B3      	M_D_CPU1_SA_CB<2>   
          	               	AN62      	54B3      	M_D_CPU1_SA_DQ<31>  
          	               	AN64      	54B2      	M_D_CPU1_SA_DQS_DN<8>
          	               	AN66      	54B3      	M_D_CPU1_SA_DQ<26>  
          	               	AN68      	54B3      	M_D_CPU1_SA_DQ<23>  
          	               	AN70      	54B2      	M_D_CPU1_SA_DQS_DN<7>
          	               	AN72      	54B3      	M_D_CPU1_SA_DQ<18>  
          	               	AN74      	54B3      	M_D_CPU1_SA_DQ<15>  
          	               	AN76      	54B2      	M_D_CPU1_SA_DQS_DN<6>
          	               	AN78      	54B3      	M_D_CPU1_SA_DQ<10>  
          	               	AN80      	69B2      	PVCCFA_EHV_FIVRA_CPU1
          	               	AN82      	65B2      	UPI_CPU1_CPU0_P2P2_DN<13>
          	               	AN84      	72B2      	GND                 
          	               	AN86      	62B2      	P5E_CPU1_PE4_TX_DP<11>
          	               	AN88      	72B2      	GND                 
          	               	AN90      	62B3      	P5E_CPU1_PE4_RX_DP<11>
          	               	AP2       	63B2      	UPI_CPU1_CPU0_P0P1_DN<12>
          	               	AP4       	72B2      	GND                 
          	               	AP6       	63B3      	UPI_CPU0_CPU1_P1P0_DN<12>
          	               	AP8       	72B2      	GND                 
          	               	AP10      	60B3      	P5E_CPU1_PE0_RX_DN<12>
          	               	AP12      	72B2      	GND                 
          	               	AP14      	60B2      	P5E_CPU1_PE0_TX_DN<11>
          	               	AP16      	72B2      	GND                 
          	               	AP18      	72B2      	GND                 
          	               	AP20      	54B3      	M_D_CPU1_SB_DQ<30>  
          	               	AP22      	54B3      	M_D_CPU1_SB_DQ<27>  
          	               	AP24      	72B2      	GND                 
          	               	AP26      	54B3      	M_D_CPU1_SB_DQ<14>  
          	               	AP28      	54B3      	M_D_CPU1_SB_DQ<11>  
          	               	AP30      	72B2      	GND                 
          	               	AP32      	54A3      	M_D_CPU1_SB_DQ<6>   
          	               	AP34      	54A3      	M_D_CPU1_SB_DQ<3>   
          	               	AP36      	72B2      	GND                 
          	               	AP38      	54A3      	M_D_CPU1_SB_CB<2>   
          	               	AP40      	54A3      	M_D_CPU1_SB_CB<7>   
          	               	AP42      	72B2      	GND                 
          	               	AP44      	54B2      	M_D_CPU1_SA_PAR     
          	               	AP47      	52A2      	M_B_CPU1_SB_RSP<1>  
          	               	AP49      	72B2      	GND                 
          	               	AP51      	54B2      	M_D_CPU1_SA_CA<3>   
          	               	AP53      	54A2      	M_D_CPU1_SA_CS_N<3> 
          	               	AP55      	72B2      	GND                 
          	               	AP57      	54B3      	M_D_CPU1_SA_CB<6>   
          	               	AP59      	54B3      	M_D_CPU1_SA_CB<3>   
          	               	AP61      	72B2      	GND                 
          	               	AP63      	54B3      	M_D_CPU1_SA_DQ<30>  
          	               	AP65      	54B3      	M_D_CPU1_SA_DQ<27>  
          	               	AP67      	72B2      	GND                 
          	               	AP69      	54B3      	M_D_CPU1_SA_DQ<22>  
          	               	AP71      	54B3      	M_D_CPU1_SA_DQ<19>  
          	               	AP73      	72B2      	GND                 
          	               	AP75      	54B3      	M_D_CPU1_SA_DQ<14>  
          	               	AP77      	54B3      	M_D_CPU1_SA_DQ<11>  
          	               	AP79      	72A3      	GND                 
          	               	AP81      	65B2      	UPI_CPU1_CPU0_P2P2_DP<12>
          	               	AP83      	72A3      	GND                 
          	               	AP85      	62B2      	P5E_CPU1_PE4_TX_DN<11>
          	               	AP87      	72A3      	GND                 
          	               	AP89      	62B3      	P5E_CPU1_PE4_RX_DN<11>
          	               	AP91      	72A3      	GND                 
          	               	AR1       	72A3      	GND                 
          	               	AR3       	63B2      	UPI_CPU1_CPU0_P0P1_DP<13>
          	               	AR5       	72A3      	GND                 
          	               	AR7       	63B3      	UPI_CPU0_CPU1_P1P0_DP<12>
          	               	AR9       	72A3      	GND                 
          	               	AR11      	60B3      	P5E_CPU1_PE0_RX_DP<12>
          	               	AR13      	72A3      	GND                 
          	               	AR15      	60B2      	P5E_CPU1_PE0_TX_DP<11>
          	               	AR17      	50B3      	NC_CPU1_UPI0_APROBE<1>
          	               	AR19      	72A3      	GND                 
          	               	AR21      	54B2      	M_D_CPU1_SB_DQS_DP<8>
          	               	AR23      	72A3      	GND                 
          	               	AR25      	72A3      	GND                 
          	               	AR27      	54B2      	M_D_CPU1_SB_DQS_DP<6>
          	               	AR29      	72A3      	GND                 
          	               	AR31      	72A3      	GND                 
          	               	AR33      	54B2      	M_D_CPU1_SB_DQS_DP<5>
          	               	AR35      	72A3      	GND                 
          	               	AR37      	72A3      	GND                 
          	               	AR39      	54B2      	M_D_CPU1_SB_DQS_DN<4>
          	               	AR41      	72A3      	GND                 
          	               	AR43      	72A3      	GND                 
          	               	AR45      	54A3      	M_D_CPU1_CLK_DP<1>  
          	               	AR48      	72A3      	GND                 
          	               	AR50      	72A3      	GND                 
          	               	AR52      	54B2      	M_D_CPU1_SA_CA<1>   
          	               	AR54      	72A3      	GND                 
          	               	AR56      	72A3      	GND                 
          	               	AR58      	54B2      	M_D_CPU1_SA_DQS_DP<9>
          	               	AR60      	72A3      	GND                 
          	               	AR62      	72B3      	GND                 
          	               	AR64      	54B2      	M_D_CPU1_SA_DQS_DP<8>
          	               	AR66      	72B3      	GND                 
          	               	AR68      	72B3      	GND                 
          	               	AR70      	54B2      	M_D_CPU1_SA_DQS_DP<7>
          	               	AR72      	72B3      	GND                 
          	               	AR74      	72B3      	GND                 
          	               	AR76      	54B2      	M_D_CPU1_SA_DQS_DP<6>
          	               	AR78      	72B3      	GND                 
          	               	AR80      	65B2      	UPI_CPU1_CPU0_P2P2_DN<14>
          	               	AR82      	72B3      	GND                 
          	               	AR84      	72B3      	GND                 
          	               	AR86      	62B2      	P5E_CPU1_PE4_TX_DN<12>
          	               	AR88      	72B3      	GND                 
          	               	AR90      	62B3      	P5E_CPU1_PE4_RX_DP<12>
          	               	AT2       	63B2      	UPI_CPU1_CPU0_P0P1_DN<13>
          	               	AT4       	72B3      	GND                 
          	               	AT6       	63B3      	UPI_CPU0_CPU1_P1P0_DP<13>
          	               	AT8       	72B3      	GND                 
          	               	AT10      	60B3      	P5E_CPU1_PE0_RX_DP<13>
          	               	AT12      	72B3      	GND                 
          	               	AT14      	60B2      	P5E_CPU1_PE0_TX_DP<12>
          	               	AT16      	72B3      	GND                 
          	               	AT18      	44B2      	PD_CPU1_BIST_ENABLE 
          	               	AT20      	72B3      	GND                 
          	               	AT22      	72B3      	GND                 
          	               	AT24      	45B2      	CPU1_RSVD<4>        
          	               	AT26      	72B3      	GND                 
          	               	AT28      	72B3      	GND                 
          	               	AT30      	44B3      	CLK_100M_DB2000_CPU1_BCLK0_DN
          	               	AT32      	72B3      	GND                 
          	               	AT34      	72B3      	GND                 
          	               	AT36      	68B2      	PVCCD_HV_CPU1       
          	               	AT38      	72B3      	GND                 
          	               	AT40      	72B3      	GND                 
          	               	AT42      	51A2      	M_A_CPU1_SA_RSP<0>  
          	               	AT44      	72B3      	GND                 
          	               	AT47      	53A2      	M_C_CPU1_ALERT_N    
          	               	AT49      	51A2      	M_A_CPU1_ALERT_N    
          	               	AT51      	72B3      	GND                 
          	               	AT53      	72B3      	GND                 
          	               	AT55      	68B2      	PVCCD_HV_CPU1       
          	               	AT57      	72B3      	GND                 
          	               	AT59      	72B3      	GND                 
          	               	AT61      	68A1      	PVCCFA_EHV_CPU1     
          	               	AT63      	72B3      	GND                 
          	               	AT65      	72B3      	GND                 
          	               	AT67      	50B3      	NC_CPU1_UPI2_APROBE<1>
          	               	AT69      	72B3      	GND                 
          	               	AT71      	72B3      	GND                 
          	               	AT73      	69B2      	PVCCFA_EHV_FIVRA_CPU1
          	               	AT75      	72B3      	GND                 
          	               	AT77      	72B3      	GND                 
          	               	AT79      	72B3      	GND                 
          	               	AT81      	65B2      	UPI_CPU1_CPU0_P2P2_DP<14>
          	               	AT83      	65B2      	UPI_CPU1_CPU0_P2P2_DN<15>
          	               	AT85      	47B4      	VSENSE_PVCCFA_EHV_FIVRA_CPU1_DN
          	               	AT87      	62B2      	P5E_CPU1_PE4_TX_DP<12>
          	               	AT89      	69B2      	PVCCFA_EHV_FIVRA_CPU1
          	               	AT91      	62B3      	P5E_CPU1_PE4_RX_DN<12>
          	               	AU1       	63B2      	UPI_CPU1_CPU0_P0P1_DN<14>
          	               	AU3       	68B2      	PVCCD_HV_CPU1       
          	               	AU5       	63B3      	UPI_CPU0_CPU1_P1P0_DN<13>
          	               	AU7       	68B2      	PVCCD_HV_CPU1       
          	               	AU9       	60B3      	P5E_CPU1_PE0_RX_DN<13>
          	               	AU11      	47B4      	VSENSE_PVCCFA_EHV_CPU1_DP
          	               	AU13      	60B2      	P5E_CPU1_PE0_TX_DN<12>
          	               	AU15      	69B2      	PVCCFA_EHV_FIVRA_CPU1
          	               	AU17      	44B2      	PU_CPU1_FRMAGENT    
          	               	AU19      	45B2      	H_CPU1_PROCHOT_LVC1_N
          	               	AU21      	45B2      	H_CPU1_MEMHOT_IN_LVC1_N
          	               	AU23      	44B2      	PU_CPU1_SAFE_MODE_BOOT
          	               	AU25      	45B2      	CPU1_RSVD<6>        
          	               	AU27      	72B3      	GND                 
          	               	AU29      	44B3      	CLK_100M_DB2000_CPU1_BCLK2_DN
          	               	AU31      	72B3      	GND                 
          	               	AU33      	47B4      	NC_CPU1_DDR23_VIEWDIG1
          	               	AU35      	68B2      	PVCCD_HV_CPU1       
          	               	AU37      	72B3      	GND                 
          	               	AU39      	72B3      	GND                 
          	               	AU41      	72B3      	GND                 
          	               	AU43      	51A2      	M_A_CPU1_SA_RSP<1>  
          	               	AU45      	72B3      	GND                 
          	               	AU48      	72B3      	GND                 
          	               	AU50      	44B2      	RST_CPU1_DRAM_AB_N  
          	               	AU52      	49B3      	TP_CPU1_SPARE5      
          	               	AU54      	68B2      	PVCCD_HV_CPU1       
          	               	AU56      	47B4      	NC_CPU1_DDR01_VIEWDIG1
          	               	AU58      	47B4      	NC_CPU1_DDR01_VIEWDIG0
          	               	AU60      	68A1      	PVCCFA_EHV_CPU1     
          	               	AU62      	46B4      	NC_SPI_CPU1_NCM_CLK 
          	               	AU64      	46B4      	NC_ESPI_IBL_CPU1_IO2
          	               	AU66      	50B2      	NC_CPU1_PE4_APROBE<1>
          	               	AU68      	50B3      	NC_CPU1_UPI2_APROBE<0>
          	               	AU70      	72B3      	GND                 
          	               	AU72      	72B3      	GND                 
          	               	AU74      	72B3      	GND                 
          	               	AU76      	72B3      	GND                 
          	               	AU78      	65B2      	UPI_CPU1_CPU0_P2P2_DN<11>
          	               	AU80      	72B3      	GND                 
          	               	AU82      	65B2      	UPI_CPU1_CPU0_P2P2_DP<16>
          	               	AU84      	72B3      	GND                 
          	               	AU86      	62B2      	P5E_CPU1_PE4_TX_DN<13>
          	               	AU88      	72B3      	GND                 
          	               	AU90      	62B3      	P5E_CPU1_PE4_RX_DP<13>
          	               	AV2       	63B2      	UPI_CPU1_CPU0_P0P1_DP<14>
          	               	AV4       	72B3      	GND                 
          	               	AV6       	63B3      	UPI_CPU0_CPU1_P1P0_DN<14>
          	               	AV8       	72B3      	GND                 
          	               	AV10      	60B3      	P5E_CPU1_PE0_RX_DN<14>
          	               	AV12      	72B3      	GND                 
          	               	AV14      	60B2      	P5E_CPU1_PE0_TX_DN<13>
          	               	AV16      	72B3      	GND                 
          	               	AV18      	45B2      	H_CPU1_NMI_LVC1_N   
          	               	AV20      	45B3      	PWRGD_CPU1_LVC1     
          	               	AV22      	44B3      	H_CPU1_PREQ_QS_GTL_R_N
          	               	AV24      	45B2      	H_CPU1_MEMTRIP_LVC1_R_N
          	               	AV26      	45B2      	CPU1_RSVD<15>       
          	               	AV28      	44B3      	CLK_100M_DB2000_CPU1_BCLK2_DP
          	               	AV30      	44B3      	CLK_100M_DB2000_CPU1_BCLK0_DP
          	               	AV32      	47B4      	NC_CPU1_DDR23_VIEWDIG0
          	               	AV34      	68B2      	PVCCD_HV_CPU1       
          	               	AV36      	68B2      	PVCCD_HV_CPU1       
          	               	AV38      	47B3      	NC_CPU1_THERMADC    
          	               	AV40      	47B3      	NC_CPU1_THERMADA    
          	               	AV42      	51A2      	M_A_CPU1_SB_RSP<1>  
          	               	AV44      	51A2      	M_A_CPU1_SB_RSP<0>  
          	               	AV47      	54A2      	M_D_CPU1_ALERT_N    
          	               	AV49      	52A2      	M_B_CPU1_ALERT_N    
          	               	AV51      	44B2      	RST_CPU1_DRAM_CD_N  
          	               	AV53      	68B2      	PVCCD_HV_CPU1       
          	               	AV55      	68B2      	PVCCD_HV_CPU1       
          	               	AV57      	45B2      	FM_CPU_FBRK_DEBUG_R_N
          	               	AV59      	45B2      	TP_EV_CPU1_EXT_BGREF
          	               	AV61      	68A1      	PVCCFA_EHV_CPU1     
          	               	AV63      	46B4      	NC_SPI_S3M_CPU1_CS1_LVC1_R_N
          	               	AV65      	48B2      	NC_CPU1_MDFI_DIE01_EW0
          	               	AV67      	50B2      	NC_CPU1_PE4_APROBE<0>
          	               	AV69      	46B2      	FM_S3M_CPU1_LVC1_GPIO_2
          	               	AV71      	46B2      	FM_S3M_CPU1_LVC1_GPIO_1
          	               	AV73      	65B3      	UPI_CPU0_CPU1_P2P2_DN<13>
          	               	AV75      	65B3      	UPI_CPU0_CPU1_P2P2_DP<16>
          	               	AV77      	72B3      	GND                 
          	               	AV79      	65B2      	UPI_CPU1_CPU0_P2P2_DP<11>
          	               	AV81      	65B2      	UPI_CPU1_CPU0_P2P2_DN<16>
          	               	AV83      	65B2      	UPI_CPU1_CPU0_P2P2_DP<15>
          	               	AV85      	62B2      	P5E_CPU1_PE4_TX_DP<13>
          	               	AV87      	72B3      	GND                 
          	               	AV89      	62B3      	P5E_CPU1_PE4_RX_DN<13>
          	               	AV91      	72B3      	GND                 
          	               	AW1       	72B3      	GND                 
          	               	AW3       	63B2      	UPI_CPU1_CPU0_P0P1_DP<15>
          	               	AW5       	72B3      	GND                 
          	               	AW7       	63B3      	UPI_CPU0_CPU1_P1P0_DP<14>
          	               	AW9       	72B3      	GND                 
          	               	AW11      	60B3      	P5E_CPU1_PE0_RX_DP<14>
          	               	AW13      	72B3      	GND                 
          	               	AW15      	60B2      	P5E_CPU1_PE0_TX_DP<13>
          	               	AW17      	44B2      	PD_CPU1_DMIMODE_OVERRIDE
          	               	AW19      	46B2      	TP_FM_WAKE_CPU1_N   
          	               	AW21      	72A4      	GND                 
          	               	AW23      	72A4      	GND                 
          	               	AW25      	72A4      	GND                 
          	               	AW60      	68A1      	PVCCFA_EHV_CPU1     
          	               	AW62      	72A4      	GND                 
          	               	AW64      	46B4      	NC_SPI_S3M_CPU1_IO1_LVC1_R
          	               	AW66      	72A4      	GND                 
          	               	AW68      	72A4      	GND                 
          	               	AW70      	46B2      	FM_S3M_CPU1_LVC1_GPIO_4
          	               	AW72      	72A4      	GND                 
          	               	AW74      	65B3      	UPI_CPU0_CPU1_P2P2_DN<16>
          	               	AW76      	69B2      	PVCCFA_EHV_FIVRA_CPU1
          	               	AW78      	65B2      	UPI_CPU1_CPU0_P2P2_DN<10>
          	               	AW80      	72A4      	GND                 
          	               	AW82      	72A4      	GND                 
          	               	AW84      	72A4      	GND                 
          	               	AW86      	62B2      	P5E_CPU1_PE4_TX_DN<14>
          	               	AW88      	72A4      	GND                 
          	               	AW90      	62B3      	P5E_CPU1_PE4_RX_DP<14>
          	               	AY2       	63B2      	UPI_CPU1_CPU0_P0P1_DN<15>
          	               	AY4       	72A4      	GND                 
          	               	AY6       	63B3      	UPI_CPU0_CPU1_P1P0_DP<15>
          	               	AY8       	72A4      	GND                 
          	               	AY10      	60B3      	P5E_CPU1_PE0_RX_DP<15>
          	               	AY12      	72A4      	GND                 
          	               	AY14      	60B2      	P5E_CPU1_PE0_TX_DP<14>
          	               	AY16      	72A4      	GND                 
          	               	AY18      	68B3      	PVCCINFAON_CPU1     
          	               	AY20      	45B3      	PU_TAP_ODT_CPU1_EN  
          	               	AY22      	45B2      	H_CPU1_ERR1_LVC1_R_N
          	               	AY24      	48B2      	NC_CPU1_SOC_SPARE0  
          	               	AY26      	45B2      	CPU1_RSVD<25>       
          	               	AY61      	46B4      	NC_SPI_CPU1_NCM_IO1 
          	               	AY63      	44B2      	FM_CPU1_PKGID1      
          	               	AY65      	45B2      	CPU1_RSVD<27>       
          	               	AY67      	46B4      	NC_SPI_CPU1_NCM_CS0_N
          	               	AY69      	46B2      	FM_S3M_CPU1_LVC1_GPIO_3
          	               	AY71      	72A4      	GND                 
          	               	AY73      	65B3      	UPI_CPU0_CPU1_P2P2_DP<13>
          	               	AY75      	65B3      	UPI_CPU0_CPU1_P2P2_DN<14>
          	               	AY77      	72A4      	GND                 
          	               	AY79      	72A4      	GND                 
          	               	AY81      	72A4      	GND                 
          	               	AY83      	72A4      	GND                 
          	               	AY85      	47B4      	VSENSE_PVCCFA_EHV_FIVRA_CPU1_DP
          	               	AY87      	62B2      	P5E_CPU1_PE4_TX_DP<14>
          	               	AY89      	69B2      	PVCCFA_EHV_FIVRA_CPU1
          	               	AY91      	62B3      	P5E_CPU1_PE4_RX_DN<14>
          	               	B6        	73A2      	GND                 
          	               	B8        	51B3      	M_A_CPU1_SB_DQ<28>  
          	               	B10       	51B3      	M_A_CPU1_SB_DQ<25>  
          	               	B12       	73A2      	GND                 
          	               	B14       	52B3      	M_B_CPU1_SB_DQ<30>  
          	               	B16       	52B3      	M_B_CPU1_SB_DQ<25>  
          	               	B18       	73A2      	GND                 
          	               	B20       	51B3      	M_A_CPU1_SB_DQ<20>  
          	               	B22       	51B3      	M_A_CPU1_SB_DQ<17>  
          	               	B24       	73A2      	GND                 
          	               	B26       	51B3      	M_A_CPU1_SB_DQ<12>  
          	               	B28       	51A3      	M_A_CPU1_SB_DQ<9>   
          	               	B30       	73B2      	GND                 
          	               	B32       	51A3      	M_A_CPU1_SB_CB<0>   
          	               	B34       	51A3      	M_A_CPU1_SB_CB<5>   
          	               	B36       	73B2      	GND                 
          	               	B38       	51A2      	M_A_CPU1_SB_CS_N<0> 
          	               	B40       	51B2      	M_A_CPU1_SB_CA<4>   
          	               	B42       	73B2      	GND                 
          	               	B44       	51A3      	M_A_CPU1_CLK_DN<0>  
          	               	B49       	73B2      	GND                 
          	               	B51       	51B2      	M_A_CPU1_SA_CA<2>   
          	               	B53       	51A2      	M_A_CPU1_SA_CS_N<1> 
          	               	B55       	73B2      	GND                 
          	               	B57       	51B3      	M_A_CPU1_SA_CB<4>   
          	               	B59       	51B3      	M_A_CPU1_SA_CB<1>   
          	               	B61       	73B2      	GND                 
          	               	B63       	51B3      	M_A_CPU1_SA_DQ<28>  
          	               	B65       	51B3      	M_A_CPU1_SA_DQ<25>  
          	               	B67       	73B2      	GND                 
          	               	B69       	51B3      	M_A_CPU1_SA_DQ<20>  
          	               	B71       	51B2      	M_A_CPU1_SA_DQS_DN<2>
          	               	B73       	51B3      	M_A_CPU1_SA_DQ<16>  
          	               	B75       	73B2      	GND                 
          	               	B77       	51B2      	M_A_CPU1_SA_DQS_DN<0>
          	               	B79       	51B3      	M_A_CPU1_SA_DQ<1>   
          	               	B81       	51B3      	M_A_CPU1_SA_DQ<0>   
          	               	B83       	73B2      	GND                 
          	               	B85       	65B2      	UPI_CPU1_CPU0_P2P2_DN<0>
          	               	B87       	73B2      	GND                 
          	               	BA1       	63B2      	UPI_CPU1_CPU0_P0P1_DP<16>
          	               	BA3       	68B2      	PVCCD_HV_CPU1       
          	               	BA5       	63B3      	UPI_CPU0_CPU1_P1P0_DN<15>
          	               	BA7       	68B2      	PVCCD_HV_CPU1       
          	               	BA9       	60B3      	P5E_CPU1_PE0_RX_DN<15>
          	               	BA11      	47B4      	VSENSE_PVCCFA_EHV_CPU1_DN
          	               	BA13      	60B2      	P5E_CPU1_PE0_TX_DN<14>
          	               	BA15      	68B3      	PVCCINFAON_CPU1     
          	               	BA17      	72A4      	GND                 
          	               	BA19      	68B2      	PVNN_MAIN_CPU1      
          	               	BA21      	68B2      	P3V3_AUX            
          	               	BA23      	50B3      	PU_CPU1_UPI0_AC_COUPLING
          	               	BA25      	48B2      	NC_CPU1_SOC_SPARE4  
          	               	BA60      	72A4      	GND                 
          	               	BA62      	46B4      	NC_SPI_S3M_CPU1_IO0_LVC1_R
          	               	BA64      	72B4      	GND                 
          	               	BA66      	46B4      	NC_SPI_CPU1_NCM_IO0 
          	               	BA68      	46B4      	NC_SPI_S3M_CPU1_OE_LVC1_R_N
          	               	BA70      	46B2      	FM_S3M_CPU1_LVC1_GPIO_0
          	               	BA72      	65B3      	UPI_CPU0_CPU1_P2P2_DN<12>
          	               	BA74      	72B4      	GND                 
          	               	BA76      	65B3      	UPI_CPU0_CPU1_P2P2_DP<14>
          	               	BA78      	65B2      	UPI_CPU1_CPU0_P2P2_DP<10>
          	               	BA80      	65B2      	UPI_CPU1_CPU0_P2P2_DN<17>
          	               	BA82      	65B2      	UPI_CPU1_CPU0_P2P2_DP<18>
          	               	BA84      	72B4      	GND                 
          	               	BA86      	62B2      	P5E_CPU1_PE4_TX_DN<15>
          	               	BA88      	72B4      	GND                 
          	               	BA90      	62B3      	P5E_CPU1_PE4_RX_DP<15>
          	               	BB2       	63B2      	UPI_CPU1_CPU0_P0P1_DN<16>
          	               	BB4       	72B4      	GND                 
          	               	BB6       	63B3      	UPI_CPU0_CPU1_P1P0_DN<16>
          	               	BB8       	72B4      	GND                 
          	               	BB10      	72B4      	GND                 
          	               	BB12      	72B4      	GND                 
          	               	BB14      	60B2      	P5E_CPU1_PE0_TX_DN<15>
          	               	BB16      	72B4      	GND                 
          	               	BB18      	59B3      	TP_DMI_CPU1_PCH_RX_C_DN<0>
          	               	BB20      	72B4      	GND                 
          	               	BB22      	72B4      	GND                 
          	               	BB24      	72B4      	GND                 
          	               	BB26      	72B4      	GND                 
          	               	BB61      	46B4      	NC_SPI_S3M_CPU1_CS0_LVC1_R_N
          	               	BB63      	72B4      	GND                 
          	               	BB65      	50B3      	PU_CPU1_UPI2_AC_COUPLING
          	               	BB67      	46B4      	NC_SPI_CPU1_NCM_OE_N
          	               	BB69      	72B4      	GND                 
          	               	BB71      	72B4      	GND                 
          	               	BB73      	65B3      	UPI_CPU0_CPU1_P2P2_DP<12>
          	               	BB75      	65B3      	UPI_CPU0_CPU1_P2P2_DN<15>
          	               	BB77      	72B4      	GND                 
          	               	BB79      	72B4      	GND                 
          	               	BB81      	65B2      	UPI_CPU1_CPU0_P2P2_DP<17>
          	               	BB83      	72B4      	GND                 
          	               	BB85      	62B2      	P5E_CPU1_PE4_TX_DP<15>
          	               	BB87      	72B4      	GND                 
          	               	BB89      	62B3      	P5E_CPU1_PE4_RX_DN<15>
          	               	BB91      	72B4      	GND                 
          	               	BC1       	72B4      	GND                 
          	               	BC3       	63B2      	UPI_CPU1_CPU0_P0P1_DP<17>
          	               	BC5       	72B4      	GND                 
          	               	BC7       	63B3      	UPI_CPU0_CPU1_P1P0_DP<16>
          	               	BC9       	72B4      	GND                 
          	               	BC11      	60A3      	P5E_CPU1_PE1_RX_DN<15>
          	               	BC13      	72B4      	GND                 
          	               	BC15      	60B2      	P5E_CPU1_PE0_TX_DP<15>
          	               	BC17      	72B4      	GND                 
          	               	BC19      	59B3      	TP_DMI_CPU1_PCH_RX_C_DP<0>
          	               	BC21      	68B2      	P3V3_AUX            
          	               	BC23      	47B3      	TP_CPU1_IFST_DONE_LVC1_R
          	               	BC25      	46B2      	TP_I3C_MNG3_BMC_SW_SDA
          	               	BC60      	68B3      	PVCCINFAON_CPU1     
          	               	BC62      	72B4      	GND                 
          	               	BC64      	46B4      	NC_SPI_S3M_CPU1_CLK_LVC1_R
          	               	BC66      	72B4      	GND                 
          	               	BC68      	50B2      	TP_TRC_CPU1_PTI<21> 
          	               	BC70      	50B2      	TP_TRC_CPU1_PTI<16> 
          	               	BC72      	72B4      	GND                 
          	               	BC74      	65B3      	UPI_CPU0_CPU1_P2P2_DP<23>
          	               	BC76      	72B4      	GND                 
          	               	BC78      	72B4      	GND                 
          	               	BC80      	65B2      	UPI_CPU1_CPU0_P2P2_DP<20>
          	               	BC82      	65B2      	UPI_CPU1_CPU0_P2P2_DN<18>
          	               	BC84      	72B4      	GND                 
          	               	BC86      	72B4      	GND                 
          	               	BC88      	72B4      	GND                 
          	               	BC90      	47B4      	VSENSE_PVCCIN_CPU1_DN
          	               	BD2       	63B2      	UPI_CPU1_CPU0_P0P1_DN<17>
          	               	BD4       	72B4      	GND                 
          	               	BD6       	63B3      	UPI_CPU0_CPU1_P1P0_DP<17>
          	               	BD8       	72B4      	GND                 
          	               	BD10      	60B3      	P5E_CPU1_PE1_RX_DP<15>
          	               	BD12      	72B4      	GND                 
          	               	BD14      	60B2      	P5E_CPU1_PE1_TX_DP<15>
          	               	BD16      	72B4      	GND                 
          	               	BD18      	59B3      	TP_DMI_CPU1_PCH_RX_C_DP<1>
          	               	BD20      	72B4      	GND                 
          	               	BD22      	45B2      	H_CPU1_ERR2_LVC1_R_N
          	               	BD24      	47B4      	H_PMAX_TRIGGER_IO_CPU1
          	               	BD26      	45B2      	SVID_DIO0_CPU1      
          	               	BD61      	46B4      	NC_SPI_S3M_CPU1_IO3_LVC1_R
          	               	BD63      	46B4      	NC_ESPI_IBL_CPU1_ALERT1_N
          	               	BD65      	46B4      	NC_SPI_S3M_CPU1_IO2_LVC1_R
          	               	BD67      	50B2      	TP_TRC_CPU1_PTI<23> 
          	               	BD69      	50B2      	TP_TRC_CPU1_PTI<18> 
          	               	BD71      	48B2      	NC_CPU1_MDFI_DIE01_NS1
          	               	BD73      	65B3      	UPI_CPU0_CPU1_P2P2_DN<23>
          	               	BD75      	65B3      	UPI_CPU0_CPU1_P2P2_DP<15>
          	               	BD77      	49B3      	TP_CPU1_SPARE13     
          	               	BD79      	65B2      	UPI_CPU1_CPU0_P2P2_DN<20>
          	               	BD81      	72B4      	GND                 
          	               	BD83      	65B2      	UPI_CPU1_CPU0_P2P2_DP<19>
          	               	BD85      	72B4      	GND                 
          	               	BD87      	47B4      	VSENSE_PVCCIN_CPU1_DP
          	               	BD89      	72B4      	GND                 
          	               	BD91      	68B4      	PVCCIN_CPU1         
          	               	BE1       	63B2      	UPI_CPU1_CPU0_P0P1_DP<18>
          	               	BE3       	68B2      	PVCCD_HV_CPU1       
          	               	BE5       	63B3      	UPI_CPU0_CPU1_P1P0_DN<17>
          	               	BE7       	68B2      	PVCCD_HV_CPU1       
          	               	BE9       	60B3      	P5E_CPU1_PE1_RX_DP<14>
          	               	BE11      	68B2      	PVCCD_HV_CPU1       
          	               	BE13      	60A2      	P5E_CPU1_PE1_TX_DN<15>
          	               	BE15      	68B3      	PVCCINFAON_CPU1     
          	               	BE17      	59B3      	TP_DMI_CPU1_PCH_RX_C_DN<1>
          	               	BE19      	68B2      	PVNN_MAIN_CPU1      
          	               	BE21      	48B2      	TP_CPU1_DIE_HVM_EN_LVC1
          	               	BE23      	47B3      	TP_CPU1_IFST_KOT_LVC1_R
          	               	BE25      	46B2      	TP_I3C_MNG3_BMC_SW_SCL
          	               	BE60      	68B3      	PVCCINFAON_CPU1     
          	               	BE62      	46B4      	NC_ESPI_IBL_CPU1_ALERT0_N
          	               	BE64      	72B4      	GND                 
          	               	BE66      	72B4      	GND                 
          	               	BE68      	72B4      	GND                 
          	               	BE70      	50B2      	TP_TRC_CPU1_PTI<17> 
          	               	BE72      	69B2      	PVCCFA_EHV_FIVRA_CPU1
          	               	BE74      	72B4      	GND                 
          	               	BE76      	72B4      	GND                 
          	               	BE78      	72B4      	GND                 
          	               	BE80      	65B2      	UPI_CPU1_CPU0_P2P2_DP<22>
          	               	BE82      	65B2      	UPI_CPU1_CPU0_P2P2_DN<19>
          	               	BE84      	72B4      	GND                 
          	               	BE86      	68B4      	PVCCIN_CPU1         
          	               	BE88      	68B4      	PVCCIN_CPU1         
          	               	BE90      	68B4      	PVCCIN_CPU1         
          	               	BF2       	63B2      	UPI_CPU1_CPU0_P0P1_DN<18>
          	               	BF4       	72B4      	GND                 
          	               	BF6       	63B3      	UPI_CPU0_CPU1_P1P0_DN<18>
          	               	BF8       	72B4      	GND                 
          	               	BF10      	60A3      	P5E_CPU1_PE1_RX_DN<14>
          	               	BF12      	72B4      	GND                 
          	               	BF14      	60A2      	P5E_CPU1_PE1_TX_DN<14>
          	               	BF16      	72B4      	GND                 
          	               	BF18      	59B3      	TP_DMI_CPU1_PCH_RX_C_DN<2>
          	               	BF20      	72B4      	GND                 
          	               	BF22      	45B2      	H_CPU1_ERR0_LVC1_R_N
          	               	BF24      	47B3      	TP_CPU1_IFST_TRIG_LVC1_R
          	               	BF26      	45B2      	SVID_CLK1_CPU1      
          	               	BF61      	72B4      	GND                 
          	               	BF63      	72B4      	GND                 
          	               	BF65      	46B4      	NC_ESPI_IBL_CPU1_CS0_N
          	               	BF67      	50B2      	TP_TRC_CPU1_PTI2_CLK
          	               	BF69      	50B2      	TP_TRC_CPU1_PTI<19> 
          	               	BF71      	48B2      	NC_CPU1_MDFI_DIE01_NS0
          	               	BF73      	72B4      	GND                 
          	               	BF75      	72B4      	GND                 
          	               	BF77      	69B2      	PVCCFA_EHV_FIVRA_CPU1
          	               	BF79      	72A4      	GND                 
          	               	BF81      	65B2      	UPI_CPU1_CPU0_P2P2_DN<21>
          	               	BF83      	72A4      	GND                 
          	               	BF85      	68B4      	PVCCIN_CPU1         
          	               	BF87      	68B4      	PVCCIN_CPU1         
          	               	BF89      	68B4      	PVCCIN_CPU1         
          	               	BF91      	68B4      	PVCCIN_CPU1         
          	               	BG1       	72A4      	GND                 
          	               	BG3       	63B2      	UPI_CPU1_CPU0_P0P1_DP<19>
          	               	BG5       	72A4      	GND                 
          	               	BG7       	63B3      	UPI_CPU0_CPU1_P1P0_DP<18>
          	               	BG9       	72A4      	GND                 
          	               	BG11      	60A3      	P5E_CPU1_PE1_RX_DN<13>
          	               	BG13      	72A4      	GND                 
          	               	BG15      	60B2      	P5E_CPU1_PE1_TX_DP<14>
          	               	BG17      	72A4      	GND                 
          	               	BG19      	59B3      	TP_DMI_CPU1_PCH_RX_C_DP<2>
          	               	BG21      	72A4      	GND                 
          	               	BG23      	72A4      	GND                 
          	               	BG25      	72A4      	GND                 
          	               	BG60      	68B3      	PVCCINFAON_CPU1     
          	               	BG62      	46B4      	NC_ESPI_IBL_CPU1_CLK
          	               	BG64      	46B4      	NC_ESPI_IBL_CPU1_RESET_N
          	               	BG66      	50B2      	TP_TRC_CPU1_PTI<27> 
          	               	BG68      	50B2      	TP_TRC_CPU1_PTI<22> 
          	               	BG70      	72A4      	GND                 
          	               	BG72      	44B2      	FM_CPU1_PROC_ID0    
          	               	BG74      	65B3      	UPI_CPU0_CPU1_P2P2_DN<20>
          	               	BG76      	65B3      	UPI_CPU0_CPU1_P2P2_DP<17>
          	               	BG78      	48B3      	NC_CPU1_HBM3_VIEWDIG0
          	               	BG80      	65B2      	UPI_CPU1_CPU0_P2P2_DN<22>
          	               	BG82      	65B2      	UPI_CPU1_CPU0_P2P2_DP<21>
          	               	BG84      	68B4      	PVCCIN_CPU1         
          	               	BG86      	68B4      	PVCCIN_CPU1         
          	               	BG88      	68B4      	PVCCIN_CPU1         
          	               	BG90      	68B4      	PVCCIN_CPU1         
          	               	BH2       	63B2      	UPI_CPU1_CPU0_P0P1_DN<19>
          	               	BH4       	72A4      	GND                 
          	               	BH6       	63B3      	UPI_CPU0_CPU1_P1P0_DP<19>
          	               	BH8       	72A4      	GND                 
          	               	BH10      	60B3      	P5E_CPU1_PE1_RX_DP<13>
          	               	BH12      	72A4      	GND                 
          	               	BH14      	60B2      	P5E_CPU1_PE1_TX_DP<13>
          	               	BH16      	72A4      	GND                 
          	               	BH18      	59B3      	TP_DMI_CPU1_PCH_RX_C_DP<3>
          	               	BH20      	72A4      	GND                 
          	               	BH22      	47B3      	H_CPU1_RMCA_LVC1_R_N
          	               	BH24      	44B3      	PECI_CPU1_GTL_R     
          	               	BH26      	45B2      	SVID_CLK0_CPU1      
          	               	BH61      	45B3      	RST_CPU1_LVC1_N     
          	               	BH63      	46B4      	NC_ESPI_IBL_CPU1_OE_N
          	               	BH65      	46B4      	NC_ESPI_IBL_CPU1_CS1_N
          	               	BH67      	72A4      	GND                 
          	               	BH69      	50B2      	TP_TRC_CPU1_PTI<20> 
          	               	BH71      	44B2      	FM_CPU1_PROC_ID1    
          	               	BH73      	72A4      	GND                 
          	               	BH75      	65B3      	UPI_CPU0_CPU1_P2P2_DN<17>
          	               	BH77      	72A4      	GND                 
          	               	BH79      	69B2      	PVCCFA_EHV_FIVRA_CPU1
          	               	BH81      	72A4      	GND                 
          	               	BH83      	72A4      	GND                 
          	               	BH85      	68B4      	PVCCIN_CPU1         
          	               	BH87      	68B4      	PVCCIN_CPU1         
          	               	BH89      	68B4      	PVCCIN_CPU1         
          	               	BH91      	68B4      	PVCCIN_CPU1         
          	               	BJ1       	63B2      	UPI_CPU1_CPU0_P0P1_DP<20>
          	               	BJ3       	68B2      	PVCCD_HV_CPU1       
          	               	BJ5       	63B3      	UPI_CPU0_CPU1_P1P0_DN<19>
          	               	BJ7       	68B2      	PVCCD_HV_CPU1       
          	               	BJ9       	60B3      	P5E_CPU1_PE1_RX_DP<12>
          	               	BJ11      	68B2      	PVCCD_HV_CPU1       
          	               	BJ13      	60A2      	P5E_CPU1_PE1_TX_DN<13>
          	               	BJ15      	68B3      	PVCCINFAON_CPU1     
          	               	BJ17      	59B3      	TP_DMI_CPU1_PCH_RX_C_DN<3>
          	               	BJ19      	68B1      	PVNN_MAIN_CPU1      
          	               	BJ21      	48B2      	NC_CPU1_MDFI_DIE00_NS1
          	               	BJ23      	47B3      	DBP_CPU1_HOOK8_MBP2_GTL_QS_R_N
          	               	BJ25      	45B2      	SVID_ALERT1_CPU1_N  
          	               	BJ60      	68B3      	PVCCINFAON_CPU1     
          	               	BJ62      	72A4      	GND                 
          	               	BJ64      	46B4      	NC_ESPI_IBL_CPU1_IO1
          	               	BJ66      	50B2      	TP_TRC_CPU1_PTI<28> 
          	               	BJ68      	72B4      	GND                 
          	               	BJ70      	45B2      	CPU1_RSVD<54>       
          	               	BJ72      	69B2      	PVCCFA_EHV_FIVRA_CPU1
          	               	BJ74      	65B3      	UPI_CPU0_CPU1_P2P2_DP<20>
          	               	BJ76      	65B3      	UPI_CPU0_CPU1_P2P2_DN<18>
          	               	BJ78      	69A3      	PVCCFA_EHV_FIVRA_CPU1
          	               	BJ80      	72B4      	GND                 
          	               	BJ82      	72B4      	GND                 
          	               	BJ84      	72B4      	GND                 
          	               	BJ86      	72B4      	GND                 
          	               	BJ88      	72B4      	GND                 
          	               	BJ90      	72B4      	GND                 
          	               	BK2       	63B2      	UPI_CPU1_CPU0_P0P1_DN<20>
          	               	BK4       	72B4      	GND                 
          	               	BK6       	63B3      	UPI_CPU0_CPU1_P1P0_DN<20>
          	               	BK8       	72B4      	GND                 
          	               	BK10      	60A3      	P5E_CPU1_PE1_RX_DN<12>
          	               	BK12      	72B4      	GND                 
          	               	BK14      	60A2      	P5E_CPU1_PE1_TX_DN<12>
          	               	BK16      	72B4      	GND                 
          	               	BK18      	59B3      	TP_DMI_CPU1_PCH_RX_C_DN<4>
          	               	BK20      	72B4      	GND                 
          	               	BK22      	48B2      	NC_CPU1_MDFI_DIE00_NS0
          	               	BK24      	47B3      	DBP_CPU1_HOOK9_MBP3_GTL_QS_R_N
          	               	BK26      	45B2      	SVID_ALERT0_CPU1_N  
          	               	BK61      	68B3      	PVCCINFAON_CPU1     
          	               	BK63      	46B4      	NC_ESPI_IBL_CPU1_IO0
          	               	BK65      	72B4      	GND                 
          	               	BK67      	50B2      	TP_TRC_CPU1_PTI3_CLK
          	               	BK69      	50B2      	TP_TRC_CPU1_PTI<24> 
          	               	BK71      	72B4      	GND                 
          	               	BK73      	65B3      	UPI_CPU0_CPU1_P2P2_DN<22>
          	               	BK75      	72B4      	GND                 
          	               	BK77      	65B3      	UPI_CPU0_CPU1_P2P2_DP<18>
          	               	BK79      	72B4      	GND                 
          	               	BK81      	68B4      	PVCCIN_CPU1         
          	               	BK83      	68B4      	PVCCIN_CPU1         
          	               	BK85      	68B4      	PVCCIN_CPU1         
          	               	BK87      	68B4      	PVCCIN_CPU1         
          	               	BK89      	68B4      	PVCCIN_CPU1         
          	               	BK91      	68B4      	PVCCIN_CPU1         
          	               	BL1       	72B4      	GND                 
          	               	BL3       	63B2      	UPI_CPU1_CPU0_P0P1_DP<21>
          	               	BL5       	72B4      	GND                 
          	               	BL7       	63B3      	UPI_CPU0_CPU1_P1P0_DP<20>
          	               	BL9       	72B4      	GND                 
          	               	BL11      	60A3      	P5E_CPU1_PE1_RX_DN<11>
          	               	BL13      	72B4      	GND                 
          	               	BL15      	60B2      	P5E_CPU1_PE1_TX_DP<12>
          	               	BL17      	72B4      	GND                 
          	               	BL19      	59B3      	TP_DMI_CPU1_PCH_RX_C_DP<4>
          	               	BL21      	50B2      	NC_CPU1_PE0_APROBE<1>
          	               	BL23      	47B3      	DBP_CPU1_MBP0_GTL_R_N
          	               	BL25      	45B2      	SVID_DIO1_CPU1      
          	               	BL60      	48B3      	NC_CPU1_HBM3_VIEWDIG1
          	               	BL62      	45B2      	H_CPU1_THERMTRIP_LVC1_R_N
          	               	BL64      	44B2      	FM_CPU1_PKGID0      
          	               	BL66      	50B2      	TP_TRC_CPU1_PTI<29> 
          	               	BL68      	72B4      	GND                 
          	               	BL70      	72B4      	GND                 
          	               	BL72      	72B4      	GND                 
          	               	BL74      	65B3      	UPI_CPU0_CPU1_P2P2_DP<22>
          	               	BL76      	65B3      	UPI_CPU0_CPU1_P2P2_DN<19>
          	               	BL78      	72B4      	GND                 
          	               	BL80      	68B4      	PVCCIN_CPU1         
          	               	BL82      	68B4      	PVCCIN_CPU1         
          	               	BL84      	68B4      	PVCCIN_CPU1         
          	               	BL86      	68B4      	PVCCIN_CPU1         
          	               	BL88      	68B4      	PVCCIN_CPU1         
          	               	BL90      	68B4      	PVCCIN_CPU1         
          	               	BM2       	63B2      	UPI_CPU1_CPU0_P0P1_DN<21>
          	               	BM4       	72B4      	GND                 
          	               	BM6       	63B3      	UPI_CPU0_CPU1_P1P0_DP<21>
          	               	BM8       	72B4      	GND                 
          	               	BM10      	60B3      	P5E_CPU1_PE1_RX_DP<11>
          	               	BM12      	72B4      	GND                 
          	               	BM14      	60B2      	P5E_CPU1_PE1_TX_DP<11>
          	               	BM16      	72B4      	GND                 
          	               	BM18      	59B3      	TP_DMI_CPU1_PCH_RX_C_DP<5>
          	               	BM20      	72B4      	GND                 
          	               	BM22      	72B4      	GND                 
          	               	BM24      	72B4      	GND                 
          	               	BM26      	72B4      	GND                 
          	               	BM61      	72B4      	GND                 
          	               	BM63      	46B4      	NC_ESPI_IBL_CPU1_IO3
          	               	BM65      	48B2      	NC_CPU1_SOC_SPARE1  
          	               	BM67      	50B2      	TP_TRC_CPU1_PTI<30> 
          	               	BM69      	50B2      	TP_TRC_CPU1_PTI<25> 
          	               	BM71      	65B2      	UPI_CPU1_CPU0_P2P2_DN<23>
          	               	BM73      	72B4      	GND                 
          	               	BM75      	65B3      	UPI_CPU0_CPU1_P2P2_DP<21>
          	               	BM77      	72B4      	GND                 
          	               	BM79      	68B4      	PVCCIN_CPU1         
          	               	BM81      	68B4      	PVCCIN_CPU1         
          	               	BM83      	68B4      	PVCCIN_CPU1         
          	               	BM85      	68B4      	PVCCIN_CPU1         
          	               	BM87      	68B4      	PVCCIN_CPU1         
          	               	BM89      	68B4      	PVCCIN_CPU1         
          	               	BM91      	68B4      	PVCCIN_CPU1         
          	               	BN3       	63B2      	UPI_CPU1_CPU0_P0P1_DP<22>
          	               	BN5       	63B3      	UPI_CPU0_CPU1_P1P0_DN<21>
          	               	BN7       	68B2      	PVCCD_HV_CPU1       
          	               	BN9       	60A3      	P5E_CPU1_PE1_RX_DP<10>
          	               	BN11      	47B4      	VSENSE_PVCCD_HV_CPU1_DN
          	               	BN13      	60A2      	P5E_CPU1_PE1_TX_DN<11>
          	               	BN15      	68B3      	PVCCINFAON_CPU1     
          	               	BN17      	59B3      	TP_DMI_CPU1_PCH_RX_C_DN<5>
          	               	BN19      	68B1      	PVNN_MAIN_CPU1      
          	               	BN21      	50B2      	NC_CPU1_PE0_APROBE<0>
          	               	BN23      	44B2      	H_CPU1_BMCINIT_LVC1 
          	               	BN25      	47B3      	DBP_CPU1_MBP1_GTL_R_N
          	               	BN27      	50B3      	TP_TRC_CPU1_PTI<12> 
          	               	BN29      	50B3      	TP_TRC_CPU1_PTI<14> 
          	               	BN31      	72B4      	GND                 
          	               	BN33      	68B4      	PVCCIN_CPU1         
          	               	BN35      	68B4      	PVCCIN_CPU1         
          	               	BN37      	68B4      	PVCCIN_CPU1         
          	               	BN39      	68B4      	PVCCIN_CPU1         
          	               	BN41      	68B4      	PVCCIN_CPU1         
          	               	BN43      	67A1      	PVCCIN_CPU1         
          	               	BN45      	67A1      	PVCCIN_CPU1         
          	               	BN48      	67A1      	PVCCIN_CPU1         
          	               	BN50      	67A1      	PVCCIN_CPU1         
          	               	BN52      	67A1      	PVCCIN_CPU1         
          	               	BN54      	67A1      	PVCCIN_CPU1         
          	               	BN56      	67A1      	PVCCIN_CPU1         
          	               	BN58      	67A1      	PVCCIN_CPU1         
          	               	BN60      	67A1      	PVCCIN_CPU1         
          	               	BN62      	72B4      	GND                 
          	               	BN64      	44B2      	FM_CPU1_PKGID2      
          	               	BN66      	50B2      	TP_TRC_CPU1_PTI<31> 
          	               	BN68      	50B2      	TP_TRC_CPU1_PTI<26> 
          	               	BN70      	72B4      	GND                 
          	               	BN72      	65B2      	UPI_CPU1_CPU0_P2P2_DP<23>
          	               	BN74      	65B3      	UPI_CPU0_CPU1_P2P2_DN<21>
          	               	BN76      	65B3      	UPI_CPU0_CPU1_P2P2_DP<19>
          	               	BN78      	67A1      	PVCCIN_CPU1         
          	               	BN80      	67A1      	PVCCIN_CPU1         
          	               	BN82      	67A1      	PVCCIN_CPU1         
          	               	BN84      	67A1      	PVCCIN_CPU1         
          	               	BN86      	67A1      	PVCCIN_CPU1         
          	               	BN88      	67A1      	PVCCIN_CPU1         
          	               	BN90      	67A1      	PVCCIN_CPU1         
          	               	BP2       	72B4      	GND                 
          	               	BP4       	72B4      	GND                 
          	               	BP6       	63B3      	UPI_CPU0_CPU1_P1P0_DP<22>
          	               	BP8       	72B4      	GND                 
          	               	BP10      	60A3      	P5E_CPU1_PE1_RX_DN<10>
          	               	BP12      	72B4      	GND                 
          	               	BP14      	60A2      	P5E_CPU1_PE1_TX_DN<10>
          	               	BP16      	72B4      	GND                 
          	               	BP18      	59B3      	TP_DMI_CPU1_PCH_RX_C_DN<6>
          	               	BP20      	72B4      	GND                 
          	               	BP22      	48B2      	NC_CPU1_MDFI_DIE00_EW0
          	               	BP24      	45B2      	H_CPU1_CATERR_LVC1_R_N
          	               	BP26      	44B3      	H_CPU1_PRDY_QS_GTL_R_N
          	               	BP28      	50B3      	TP_TRC_CPU1_PTI<13> 
          	               	BP30      	50B3      	TP_TRC_CPU1_PTI<15> 
          	               	BP32      	67A1      	PVCCIN_CPU1         
          	               	BP34      	67A1      	PVCCIN_CPU1         
          	               	BP36      	67A1      	PVCCIN_CPU1         
          	               	BP38      	67A1      	PVCCIN_CPU1         
          	               	BP40      	67A1      	PVCCIN_CPU1         
          	               	BP42      	67B1      	PVCCIN_CPU1         
          	               	BP44      	67B1      	PVCCIN_CPU1         
          	               	BP47      	67B1      	PVCCIN_CPU1         
          	               	BP49      	67B1      	PVCCIN_CPU1         
          	               	BP51      	67B1      	PVCCIN_CPU1         
          	               	BP53      	67B1      	PVCCIN_CPU1         
          	               	BP55      	67B1      	PVCCIN_CPU1         
          	               	BP57      	67B1      	PVCCIN_CPU1         
          	               	BP59      	67B1      	PVCCIN_CPU1         
          	               	BP61      	67B1      	PVCCIN_CPU1         
          	               	BP63      	72B4      	GND                 
          	               	BP65      	48B2      	NC_CPU1_SOC_SPARE5  
          	               	BP67      	45B2      	CPU1_RSVD<64>       
          	               	BP69      	45B2      	CPU1_RSVD<65>       
          	               	BP71      	72B4      	GND                 
          	               	BP73      	72B4      	GND                 
          	               	BP75      	72B4      	GND                 
          	               	BP77      	72B4      	GND                 
          	               	BP79      	67B1      	PVCCIN_CPU1         
          	               	BP81      	67B1      	PVCCIN_CPU1         
          	               	BP83      	67B1      	PVCCIN_CPU1         
          	               	BP85      	67B1      	PVCCIN_CPU1         
          	               	BP87      	67B1      	PVCCIN_CPU1         
          	               	BP89      	67B1      	PVCCIN_CPU1         
          	               	BR3       	63B2      	UPI_CPU1_CPU0_P0P1_DN<22>
          	               	BR5       	72B4      	GND                 
          	               	BR7       	63B3      	UPI_CPU0_CPU1_P1P0_DN<22>
          	               	BR9       	72B4      	GND                 
          	               	BR11      	60A3      	P5E_CPU1_PE1_RX_DN<9>
          	               	BR13      	72B4      	GND                 
          	               	BR15      	60A2      	P5E_CPU1_PE1_TX_DP<10>
          	               	BR17      	72B4      	GND                 
          	               	BR19      	59B3      	TP_DMI_CPU1_PCH_RX_C_DP<6>
          	               	BR21      	48B2      	NC_CPU1_MDFI_DIE00_EW1
          	               	BR23      	44B2      	TP_CPU1_BR23        
          	               	BR25      	44B3      	JTAG_DBP_CPU1_QS_GTL_R_TMS
          	               	BR27      	72B4      	GND                 
          	               	BR29      	72B4      	GND                 
          	               	BR31      	72B4      	GND                 
          	               	BR33      	72B4      	GND                 
          	               	BR35      	71A1      	GND                 
          	               	BR37      	71A1      	GND                 
          	               	BR39      	71A1      	GND                 
          	               	BR41      	71A1      	GND                 
          	               	BR43      	71A1      	GND                 
          	               	BR45      	71A1      	GND                 
          	               	BR48      	71A1      	GND                 
          	               	BR50      	71A1      	GND                 
          	               	BR52      	71A1      	GND                 
          	               	BR54      	71A1      	GND                 
          	               	BR56      	71A1      	GND                 
          	               	BR58      	71A1      	GND                 
          	               	BR60      	67B1      	PVCCIN_CPU1         
          	               	BR62      	67B1      	PVCCIN_CPU1         
          	               	BR64      	71A1      	GND                 
          	               	BR66      	71A1      	GND                 
          	               	BR68      	71A1      	GND                 
          	               	BR70      	71A1      	GND                 
          	               	BR72      	71A1      	GND                 
          	               	BR74      	71A1      	GND                 
          	               	BR76      	71A1      	GND                 
          	               	BR78      	67B1      	PVCCIN_CPU1         
          	               	BR80      	71A1      	GND                 
          	               	BR82      	71A1      	GND                 
          	               	BR84      	71A1      	GND                 
          	               	BR86      	71B1      	GND                 
          	               	BR88      	71B1      	GND                 
          	               	BR90      	71B1      	GND                 
          	               	BT2       	63B2      	UPI_CPU1_CPU0_P0P1_DN<23>
          	               	BT4       	71B1      	GND                 
          	               	BT6       	63B3      	UPI_CPU0_CPU1_P1P0_DP<23>
          	               	BT8       	71B1      	GND                 
          	               	BT10      	60A3      	P5E_CPU1_PE1_RX_DP<9>
          	               	BT12      	71B1      	GND                 
          	               	BT14      	60A2      	P5E_CPU1_PE1_TX_DP<9>
          	               	BT16      	71B1      	GND                 
          	               	BT18      	59B3      	TP_DMI_CPU1_PCH_RX_C_DP<7>
          	               	BT20      	71B1      	GND                 
          	               	BT22      	44B3      	I3C_SPD_DDRABCD_CPU1_SCL
          	               	BT24      	44B3      	JTAG_DBP_CPU1_GTL_R_TCK
          	               	BT26      	44B2      	PU_CPU1_TXT_AGENT   
          	               	BT28      	50B3      	TP_TRC_CPU1_PTI<9>  
          	               	BT30      	50B3      	TP_TRC_CPU1_PTI<11> 
          	               	BT32      	67B1      	PVCCIN_CPU1         
          	               	BT34      	67B1      	PVCCIN_CPU1         
          	               	BT36      	67B1      	PVCCIN_CPU1         
          	               	BT38      	67B1      	PVCCIN_CPU1         
          	               	BT40      	67B1      	PVCCIN_CPU1         
          	               	BT42      	67B1      	PVCCIN_CPU1         
          	               	BT44      	67B1      	PVCCIN_CPU1         
          	               	BT47      	67B1      	PVCCIN_CPU1         
          	               	BT49      	67B1      	PVCCIN_CPU1         
          	               	BT51      	67B1      	PVCCIN_CPU1         
          	               	BT53      	67B1      	PVCCIN_CPU1         
          	               	BT55      	67B1      	PVCCIN_CPU1         
          	               	BT57      	67B1      	PVCCIN_CPU1         
          	               	BT59      	67B1      	PVCCIN_CPU1         
          	               	BT61      	67B1      	PVCCIN_CPU1         
          	               	BT63      	67B1      	PVCCIN_CPU1         
          	               	BT65      	67B1      	PVCCIN_CPU1         
          	               	BT67      	67B1      	PVCCIN_CPU1         
          	               	BT69      	67B1      	PVCCIN_CPU1         
          	               	BT71      	67B1      	PVCCIN_CPU1         
          	               	BT73      	67B1      	PVCCIN_CPU1         
          	               	BT75      	67B1      	PVCCIN_CPU1         
          	               	BT77      	67B1      	PVCCIN_CPU1         
          	               	BT79      	67B1      	PVCCIN_CPU1         
          	               	BT81      	67B1      	PVCCIN_CPU1         
          	               	BT83      	67B1      	PVCCIN_CPU1         
          	               	BT85      	67B1      	PVCCIN_CPU1         
          	               	BT87      	67B1      	PVCCIN_CPU1         
          	               	BT89      	67B1      	PVCCIN_CPU1         
          	               	BU3       	63B2      	UPI_CPU1_CPU0_P0P1_DP<23>
          	               	BU5       	63B3      	UPI_CPU0_CPU1_P1P0_DN<23>
          	               	BU7       	71B1      	GND                 
          	               	BU9       	60A3      	P5E_CPU1_PE1_RX_DP<8>
          	               	BU11      	47B4      	VSENSE_PVCCD_HV_CPU1_DP
          	               	BU13      	60A2      	P5E_CPU1_PE1_TX_DN<9>
          	               	BU15      	71B1      	GND                 
          	               	BU17      	59B3      	TP_DMI_CPU1_PCH_RX_C_DN<7>
          	               	BU19      	71B1      	GND                 
          	               	BU21      	71B1      	GND                 
          	               	BU23      	71B1      	GND                 
          	               	BU25      	71B1      	GND                 
          	               	BU27      	50B3      	TP_TRC_CPU1_PTI<8>  
          	               	BU29      	50B3      	TP_TRC_CPU1_PTI<10> 
          	               	BU31      	71B1      	GND                 
          	               	BU33      	67B1      	PVCCIN_CPU1         
          	               	BU35      	67B1      	PVCCIN_CPU1         
          	               	BU37      	67B1      	PVCCIN_CPU1         
          	               	BU39      	67B1      	PVCCIN_CPU1         
          	               	BU41      	67B1      	PVCCIN_CPU1         
          	               	BU43      	67B1      	PVCCIN_CPU1         
          	               	BU45      	67A2      	PVCCIN_CPU1         
          	               	BU48      	67A2      	PVCCIN_CPU1         
          	               	BU50      	67A2      	PVCCIN_CPU1         
          	               	BU52      	67A2      	PVCCIN_CPU1         
          	               	BU54      	67A2      	PVCCIN_CPU1         
          	               	BU56      	67A2      	PVCCIN_CPU1         
          	               	BU58      	67A2      	PVCCIN_CPU1         
          	               	BU60      	67A2      	PVCCIN_CPU1         
          	               	BU62      	67A2      	PVCCIN_CPU1         
          	               	BU64      	67A2      	PVCCIN_CPU1         
          	               	BU66      	67A2      	PVCCIN_CPU1         
          	               	BU68      	67A2      	PVCCIN_CPU1         
          	               	BU70      	67A2      	PVCCIN_CPU1         
          	               	BU72      	67A2      	PVCCIN_CPU1         
          	               	BU74      	67A2      	PVCCIN_CPU1         
          	               	BU76      	67A2      	PVCCIN_CPU1         
          	               	BU78      	67A2      	PVCCIN_CPU1         
          	               	BU80      	67A2      	PVCCIN_CPU1         
          	               	BU82      	67A2      	PVCCIN_CPU1         
          	               	BU84      	67A2      	PVCCIN_CPU1         
          	               	BU86      	67A2      	PVCCIN_CPU1         
          	               	BU88      	67B2      	PVCCIN_CPU1         
          	               	BU90      	67B2      	PVCCIN_CPU1         
          	               	BV2       	71B1      	GND                 
          	               	BV4       	71B1      	GND                 
          	               	BV6       	71B1      	GND                 
          	               	BV8       	71B1      	GND                 
          	               	BV10      	60A3      	P5E_CPU1_PE1_RX_DN<8>
          	               	BV12      	71B1      	GND                 
          	               	BV14      	60A2      	P5E_CPU1_PE1_TX_DN<8>
          	               	BV16      	71B1      	GND                 
          	               	BV18      	71B1      	GND                 
          	               	BV20      	71B1      	GND                 
          	               	BV22      	50B3      	NC_CPU1_UPI1_APROBE<0>
          	               	BV24      	44B3      	JTAG_DBP_CPU1_GTL_R_TDI
          	               	BV26      	45B3      	FM_PEHPCPU1_ALERT_N 
          	               	BV28      	50B3      	TP_TRC_CPU1_PTI<7>  
          	               	BV30      	50B3      	TP_TRC_CPU1_PTI<5>  
          	               	BV32      	67B2      	PVCCIN_CPU1         
          	               	BV34      	67B2      	PVCCIN_CPU1         
          	               	BV36      	67B2      	PVCCIN_CPU1         
          	               	BV38      	67B2      	PVCCIN_CPU1         
          	               	BV40      	67B2      	PVCCIN_CPU1         
          	               	BV42      	67B2      	PVCCIN_CPU1         
          	               	BV44      	67B2      	PVCCIN_CPU1         
          	               	BV47      	67B2      	PVCCIN_CPU1         
          	               	BV49      	67B2      	PVCCIN_CPU1         
          	               	BV51      	67B2      	PVCCIN_CPU1         
          	               	BV53      	67B2      	PVCCIN_CPU1         
          	               	BV55      	67B2      	PVCCIN_CPU1         
          	               	BV57      	67B2      	PVCCIN_CPU1         
          	               	BV59      	67B2      	PVCCIN_CPU1         
          	               	BV61      	67B2      	PVCCIN_CPU1         
          	               	BV63      	67B2      	PVCCIN_CPU1         
          	               	BV65      	67B2      	PVCCIN_CPU1         
          	               	BV67      	67B2      	PVCCIN_CPU1         
          	               	BV69      	67B2      	PVCCIN_CPU1         
          	               	BV71      	67B2      	PVCCIN_CPU1         
          	               	BV73      	67B2      	PVCCIN_CPU1         
          	               	BV75      	67B2      	PVCCIN_CPU1         
          	               	BV77      	67B2      	PVCCIN_CPU1         
          	               	BV79      	67B2      	PVCCIN_CPU1         
          	               	BV81      	67B2      	PVCCIN_CPU1         
          	               	BV83      	67B2      	PVCCIN_CPU1         
          	               	BV85      	67B2      	PVCCIN_CPU1         
          	               	BV87      	67B2      	PVCCIN_CPU1         
          	               	BV89      	67B2      	PVCCIN_CPU1         
          	               	BW3       	71B1      	GND                 
          	               	BW5       	71B1      	GND                 
          	               	BW7       	64B2      	UPI_CPU1_CPU0_P1P0_DP<23>
          	               	BW9       	71B1      	GND                 
          	               	BW11      	60A3      	P5E_CPU1_PE1_RX_DN<7>
          	               	BW13      	71B1      	GND                 
          	               	BW15      	60A2      	P5E_CPU1_PE1_TX_DP<8>
          	               	BW17      	71B1      	GND                 
          	               	BW19      	59B2      	TP_DMI_CPU1_PCH_TX_DN<0>
          	               	BW21      	50B3      	NC_CPU1_DMI_APROBE<1>
          	               	BW23      	50B2      	NC_CPU1_PE2_APROBE<1>
          	               	BW25      	44B2      	JTAG_CPU1_MUX_GTL_TDO
          	               	BW27      	71B1      	GND                 
          	               	BW29      	71B1      	GND                 
          	               	BW31      	71B1      	GND                 
          	               	BW33      	67B2      	PVCCIN_CPU1         
          	               	BW35      	67B2      	PVCCIN_CPU1         
          	               	BW37      	67B2      	PVCCIN_CPU1         
          	               	BW39      	67B2      	PVCCIN_CPU1         
          	               	BW41      	67B2      	PVCCIN_CPU1         
          	               	BW43      	67B2      	PVCCIN_CPU1         
          	               	BW45      	67B2      	PVCCIN_CPU1         
          	               	BW48      	67B2      	PVCCIN_CPU1         
          	               	BW50      	67B2      	PVCCIN_CPU1         
          	               	BW52      	67B2      	PVCCIN_CPU1         
          	               	BW54      	67B2      	PVCCIN_CPU1         
          	               	BW56      	67B2      	PVCCIN_CPU1         
          	               	BW58      	67B2      	PVCCIN_CPU1         
          	               	BW60      	67B2      	PVCCIN_CPU1         
          	               	BW62      	67B2      	PVCCIN_CPU1         
          	               	BW64      	67B2      	PVCCIN_CPU1         
          	               	BW66      	67B2      	PVCCIN_CPU1         
          	               	BW68      	67B2      	PVCCIN_CPU1         
          	               	BW70      	67B2      	PVCCIN_CPU1         
          	               	BW72      	67B2      	PVCCIN_CPU1         
          	               	BW74      	67B2      	PVCCIN_CPU1         
          	               	BW76      	67B2      	PVCCIN_CPU1         
          	               	BW78      	67B2      	PVCCIN_CPU1         
          	               	BW80      	67A3      	PVCCIN_CPU1         
          	               	BW82      	67A3      	PVCCIN_CPU1         
          	               	BW84      	67A3      	PVCCIN_CPU1         
          	               	BW86      	67A3      	PVCCIN_CPU1         
          	               	BW88      	67A3      	PVCCIN_CPU1         
          	               	BW90      	67A3      	PVCCIN_CPU1         
          	               	BY2       	64B3      	UPI_CPU0_CPU1_P0P1_DP<23>
          	               	BY4       	71B1      	GND                 
          	               	BY6       	64B2      	UPI_CPU1_CPU0_P1P0_DN<23>
          	               	BY8       	71B1      	GND                 
          	               	BY10      	60A3      	P5E_CPU1_PE1_RX_DP<7>
          	               	BY12      	71B1      	GND                 
          	               	BY14      	60A2      	P5E_CPU1_PE1_TX_DP<7>
          	               	BY16      	71B1      	GND                 
          	               	BY18      	59B2      	TP_DMI_CPU1_PCH_TX_DP<1>
          	               	BY20      	71B1      	GND                 
          	               	BY22      	44B3      	I3C_SPD_DDRABCD_CPU1_SDA
          	               	BY24      	44B2      	PD_EXT_CLK_SEL_CPU1 
          	               	BY26      	45B3      	SMB_PEHPCPU1_GTL_SDA
          	               	BY28      	50B3      	TP_TRC_CPU1_PTI1_CLK
          	               	BY30      	50B3      	TP_TRC_CPU1_PTI<3>  
          	               	BY32      	67A3      	PVCCIN_CPU1         
          	               	BY34      	67A3      	PVCCIN_CPU1         
          	               	BY36      	67A3      	PVCCIN_CPU1         
          	               	BY38      	67A3      	PVCCIN_CPU1         
          	               	BY40      	67A3      	PVCCIN_CPU1         
          	               	BY42      	67A3      	PVCCIN_CPU1         
          	               	BY44      	67A3      	PVCCIN_CPU1         
          	               	BY47      	67A3      	PVCCIN_CPU1         
          	               	BY49      	67A3      	PVCCIN_CPU1         
          	               	BY51      	67A3      	PVCCIN_CPU1         
          	               	BY53      	67A3      	PVCCIN_CPU1         
          	               	BY55      	67A3      	PVCCIN_CPU1         
          	               	BY57      	67A3      	PVCCIN_CPU1         
          	               	BY59      	67A3      	PVCCIN_CPU1         
          	               	BY61      	67A3      	PVCCIN_CPU1         
          	               	BY63      	67B3      	PVCCIN_CPU1         
          	               	BY65      	67B3      	PVCCIN_CPU1         
          	               	BY67      	67B3      	PVCCIN_CPU1         
          	               	BY69      	67B3      	PVCCIN_CPU1         
          	               	BY71      	67B3      	PVCCIN_CPU1         
          	               	BY73      	67B3      	PVCCIN_CPU1         
          	               	BY75      	67B3      	PVCCIN_CPU1         
          	               	BY77      	67B3      	PVCCIN_CPU1         
          	               	BY79      	67B3      	PVCCIN_CPU1         
          	               	BY81      	67B3      	PVCCIN_CPU1         
          	               	BY83      	67B3      	PVCCIN_CPU1         
          	               	BY85      	67B3      	PVCCIN_CPU1         
          	               	BY87      	67B3      	PVCCIN_CPU1         
          	               	BY89      	67B3      	PVCCIN_CPU1         
          	               	C5        	73B2      	GND                 
          	               	C7        	51B3      	M_A_CPU1_SB_DQ<29>  
          	               	C9        	51B2      	M_A_CPU1_SB_DQS_DP<3>
          	               	C11       	51B3      	M_A_CPU1_SB_DQ<24>  
          	               	C13       	52B3      	M_B_CPU1_SB_DQ<28>  
          	               	C15       	52B2      	M_B_CPU1_SB_DQS_DP<3>
          	               	C17       	52B3      	M_B_CPU1_SB_DQ<24>  
          	               	C19       	51B3      	M_A_CPU1_SB_DQ<21>  
          	               	C21       	51B2      	M_A_CPU1_SB_DQS_DP<2>
          	               	C23       	51B3      	M_A_CPU1_SB_DQ<16>  
          	               	C25       	51B3      	M_A_CPU1_SB_DQ<13>  
          	               	C27       	51B2      	M_A_CPU1_SB_DQS_DP<1>
          	               	C29       	51A3      	M_A_CPU1_SB_DQ<8>   
          	               	C31       	51A3      	M_A_CPU1_SB_CB<1>   
          	               	C33       	51B2      	M_A_CPU1_SB_DQS_DP<9>
          	               	C35       	51A3      	M_A_CPU1_SB_CB<4>   
          	               	C37       	51A2      	M_A_CPU1_SB_CS_N<1> 
          	               	C39       	73B2      	GND                 
          	               	C41       	51B2      	M_A_CPU1_SB_CA<2>   
          	               	C43       	51A3      	M_A_CPU1_CLK_DP<0>  
          	               	C45       	73B2      	GND                 
          	               	C48       	51B2      	M_A_CPU1_SA_CA<6>   
          	               	C50       	51B2      	M_A_CPU1_SA_CA<4>   
          	               	C52       	73B2      	GND                 
          	               	C54       	51A2      	M_A_CPU1_SA_CS_N<0> 
          	               	C56       	51B3      	M_A_CPU1_SA_CB<5>   
          	               	C58       	51B2      	M_A_CPU1_SA_DQS_DP<4>
          	               	C60       	51B3      	M_A_CPU1_SA_CB<0>   
          	               	C62       	51B3      	M_A_CPU1_SA_DQ<29>  
          	               	C64       	51B2      	M_A_CPU1_SA_DQS_DP<3>
          	               	C66       	51B3      	M_A_CPU1_SA_DQ<24>  
          	               	C68       	51B3      	M_A_CPU1_SA_DQ<21>  
          	               	C70       	51B2      	M_A_CPU1_SA_DQS_DP<2>
          	               	C72       	73B2      	GND                 
          	               	C74       	73B2      	GND                 
          	               	C76       	51B3      	M_A_CPU1_SA_DQ<4>   
          	               	C78       	73B2      	GND                 
          	               	C80       	73B2      	GND                 
          	               	C82       	73B2      	GND                 
          	               	C84       	69A2      	PVCCFA_EHV_FIVRA_CPU1
          	               	C86       	73B2      	GND                 
          	               	C88       	69A2      	PVCCFA_EHV_FIVRA_CPU1
          	               	CA3       	71B1      	GND                 
          	               	CA5       	64B2      	UPI_CPU1_CPU0_P1P0_DN<22>
          	               	CA7       	68B2      	PVCCD_HV_CPU1       
          	               	CA9       	60A3      	P5E_CPU1_PE1_RX_DP<6>
          	               	CA11      	47B4      	VSENSE_PVCCINFAON_CPU1_DP
          	               	CA13      	60A2      	P5E_CPU1_PE1_TX_DN<7>
          	               	CA15      	68B3      	PVCCINFAON_CPU1     
          	               	CA17      	59B2      	TP_DMI_CPU1_PCH_TX_DN<1>
          	               	CA19      	59B2      	TP_DMI_CPU1_PCH_TX_DP<0>
          	               	CA21      	50B3      	NC_CPU1_DMI_APROBE<0>
          	               	CA23      	50B3      	NC_CPU1_UPI1_APROBE<1>
          	               	CA25      	45B3      	SMB_PEHPCPU1_GTL_SCL
          	               	CA27      	50B3      	TP_TRC_CPU1_PTI<6>  
          	               	CA29      	50B3      	TP_TRC_CPU1_PTI<4>  
          	               	CA31      	71B1      	GND                 
          	               	CA33      	67B3      	PVCCIN_CPU1         
          	               	CA35      	67B3      	PVCCIN_CPU1         
          	               	CA37      	67B3      	PVCCIN_CPU1         
          	               	CA39      	67B3      	PVCCIN_CPU1         
          	               	CA41      	67B3      	PVCCIN_CPU1         
          	               	CA43      	67B3      	PVCCIN_CPU1         
          	               	CA45      	67B3      	PVCCIN_CPU1         
          	               	CA48      	67B3      	PVCCIN_CPU1         
          	               	CA50      	67B3      	PVCCIN_CPU1         
          	               	CA52      	67B3      	PVCCIN_CPU1         
          	               	CA54      	67B3      	PVCCIN_CPU1         
          	               	CA56      	67B3      	PVCCIN_CPU1         
          	               	CA58      	67B3      	PVCCIN_CPU1         
          	               	CA60      	67B3      	PVCCIN_CPU1         
          	               	CA62      	67B3      	PVCCIN_CPU1         
          	               	CA64      	67B3      	PVCCIN_CPU1         
          	               	CA66      	67B3      	PVCCIN_CPU1         
          	               	CA68      	67B3      	PVCCIN_CPU1         
          	               	CA70      	67B3      	PVCCIN_CPU1         
          	               	CA72      	67B3      	PVCCIN_CPU1         
          	               	CA74      	67B3      	PVCCIN_CPU1         
          	               	CA76      	67B3      	PVCCIN_CPU1         
          	               	CA78      	67B3      	PVCCIN_CPU1         
          	               	CA80      	67B3      	PVCCIN_CPU1         
          	               	CA82      	67B3      	PVCCIN_CPU1         
          	               	CA84      	67B3      	PVCCIN_CPU1         
          	               	CA86      	67B3      	PVCCIN_CPU1         
          	               	CA88      	67B3      	PVCCIN_CPU1         
          	               	CA90      	67B3      	PVCCIN_CPU1         
          	               	CB2       	64B3      	UPI_CPU0_CPU1_P0P1_DN<23>
          	               	CB4       	71B1      	GND                 
          	               	CB6       	64B2      	UPI_CPU1_CPU0_P1P0_DP<22>
          	               	CB8       	71B1      	GND                 
          	               	CB10      	60A3      	P5E_CPU1_PE1_RX_DN<6>
          	               	CB12      	71B1      	GND                 
          	               	CB14      	60A2      	P5E_CPU1_PE1_TX_DN<6>
          	               	CB16      	71B1      	GND                 
          	               	CB18      	59B2      	TP_DMI_CPU1_PCH_TX_DN<2>
          	               	CB20      	71B1      	GND                 
          	               	CB22      	71B1      	GND                 
          	               	CB24      	71B1      	GND                 
          	               	CB26      	71B1      	GND                 
          	               	CB28      	71B1      	GND                 
          	               	CB30      	50B3      	TP_TRC_CPU1_PTI0_CLK
          	               	CB32      	71B1      	GND                 
          	               	CB34      	71B1      	GND                 
          	               	CB36      	71B1      	GND                 
          	               	CB38      	71B1      	GND                 
          	               	CB40      	71B1      	GND                 
          	               	CB42      	71B1      	GND                 
          	               	CB44      	71B1      	GND                 
          	               	CB47      	71B1      	GND                 
          	               	CB49      	71B1      	GND                 
          	               	CB51      	71B1      	GND                 
          	               	CB53      	71B1      	GND                 
          	               	CB55      	71A2      	GND                 
          	               	CB57      	71A2      	GND                 
          	               	CB59      	71A2      	GND                 
          	               	CB61      	67B3      	PVCCIN_CPU1         
          	               	CB63      	71A2      	GND                 
          	               	CB65      	71A2      	GND                 
          	               	CB67      	71A2      	GND                 
          	               	CB69      	71A2      	GND                 
          	               	CB71      	71A2      	GND                 
          	               	CB73      	71A2      	GND                 
          	               	CB75      	67B3      	PVCCIN_CPU1         
          	               	CB77      	67B3      	PVCCIN_CPU1         
          	               	CB79      	71A2      	GND                 
          	               	CB81      	71A2      	GND                 
          	               	CB83      	71A2      	GND                 
          	               	CB85      	71A2      	GND                 
          	               	CB87      	71A2      	GND                 
          	               	CB89      	71A2      	GND                 
          	               	CC3       	64B3      	UPI_CPU0_CPU1_P0P1_DP<22>
          	               	CC5       	71A2      	GND                 
          	               	CC7       	64B2      	UPI_CPU1_CPU0_P1P0_DP<21>
          	               	CC9       	71A2      	GND                 
          	               	CC11      	60A3      	P5E_CPU1_PE1_RX_DN<5>
          	               	CC13      	71A2      	GND                 
          	               	CC15      	60A2      	P5E_CPU1_PE1_TX_DP<6>
          	               	CC17      	71A2      	GND                 
          	               	CC19      	59B2      	TP_DMI_CPU1_PCH_TX_DP<2>
          	               	CC21      	50B2      	NC_CPU1_PE1_APROBE<1>
          	               	CC23      	50B2      	NC_CPU1_PE2_APROBE<0>
          	               	CC25      	45B3      	TP_H_SBLINK7_CPU1_PMDOWN
          	               	CC27      	50B3      	TP_TRC_CPU1_PTI<2>  
          	               	CC29      	50B3      	TP_TRC_CPU1_PTI<0>  
          	               	CC31      	71A2      	GND                 
          	               	CC33      	67B3      	PVCCIN_CPU1         
          	               	CC35      	67B3      	PVCCIN_CPU1         
          	               	CC37      	67B3      	PVCCIN_CPU1         
          	               	CC39      	67B3      	PVCCIN_CPU1         
          	               	CC41      	67B3      	PVCCIN_CPU1         
          	               	CC43      	67B3      	PVCCIN_CPU1         
          	               	CC45      	67B3      	PVCCIN_CPU1         
          	               	CC48      	67B3      	PVCCIN_CPU1         
          	               	CC50      	67A4      	PVCCIN_CPU1         
          	               	CC52      	67A4      	PVCCIN_CPU1         
          	               	CC54      	67A4      	PVCCIN_CPU1         
          	               	CC56      	67A4      	PVCCIN_CPU1         
          	               	CC58      	67A4      	PVCCIN_CPU1         
          	               	CC60      	67A4      	PVCCIN_CPU1         
          	               	CC62      	71A2      	GND                 
          	               	CC64      	47B3      	NC_CPU1_LGSSPARE4   
          	               	CC66      	48B2      	NC_CPU1_MDFI_DIE01_EW1
          	               	CC68      	68B2      	PVPP_HBM_CPU1       
          	               	CC70      	71A2      	GND                 
          	               	CC72      	71B2      	GND                 
          	               	CC74      	71B2      	GND                 
          	               	CC76      	67A4      	PVCCIN_CPU1         
          	               	CC78      	67A4      	PVCCIN_CPU1         
          	               	CC80      	67A4      	PVCCIN_CPU1         
          	               	CC82      	67A4      	PVCCIN_CPU1         
          	               	CC84      	67A4      	PVCCIN_CPU1         
          	               	CC86      	67A4      	PVCCIN_CPU1         
          	               	CC88      	67A4      	PVCCIN_CPU1         
          	               	CC90      	67A4      	PVCCIN_CPU1         
          	               	CD2       	64B3      	UPI_CPU0_CPU1_P0P1_DN<22>
          	               	CD4       	71B2      	GND                 
          	               	CD6       	64B2      	UPI_CPU1_CPU0_P1P0_DN<21>
          	               	CD8       	71B2      	GND                 
          	               	CD10      	60A3      	P5E_CPU1_PE1_RX_DP<5>
          	               	CD12      	71B2      	GND                 
          	               	CD14      	60A2      	P5E_CPU1_PE1_TX_DP<5>
          	               	CD16      	71B2      	GND                 
          	               	CD18      	59B2      	TP_DMI_CPU1_PCH_TX_DP<3>
          	               	CD20      	71B2      	GND                 
          	               	CD22      	48B2      	NC_CPU1_MDFI_DIE10_NS1
          	               	CD24      	45B3      	TP_H_SBLINK4_CPU1_PMDOWN
          	               	CD26      	48B2      	NC_CPU1_MDFI_DIE10_EW0
          	               	CD28      	50B3      	TP_TRC_CPU1_PTI<1>  
          	               	CD30      	48B2      	NC_CPU1_MDFI_DIE10_EW1
          	               	CD32      	67A4      	PVCCIN_CPU1         
          	               	CD34      	67A4      	PVCCIN_CPU1         
          	               	CD36      	67A4      	PVCCIN_CPU1         
          	               	CD38      	67A4      	PVCCIN_CPU1         
          	               	CD40      	67A4      	PVCCIN_CPU1         
          	               	CD42      	67A4      	PVCCIN_CPU1         
          	               	CD44      	67A4      	PVCCIN_CPU1         
          	               	CD47      	67B4      	PVCCIN_CPU1         
          	               	CD49      	67B4      	PVCCIN_CPU1         
          	               	CD51      	67B4      	PVCCIN_CPU1         
          	               	CD53      	67B4      	PVCCIN_CPU1         
          	               	CD55      	67B4      	PVCCIN_CPU1         
          	               	CD57      	67B4      	PVCCIN_CPU1         
          	               	CD59      	67B4      	PVCCIN_CPU1         
          	               	CD61      	71B2      	GND                 
          	               	CD63      	46B4      	SMB_S3M_CPU1_SDA    
          	               	CD65      	46B2      	TP_SGPIO_S3M_CPU1_GSXRST_N
          	               	CD67      	68B2      	PVPP_HBM_CPU1       
          	               	CD69      	49B3      	TP_CPU1_SPARE11     
          	               	CD71      	44B3      	CPU1_RSVD<82>       
          	               	CD73      	66B2      	NC                  
          	               	CD75      	71B2      	GND                 
          	               	CD77      	71B2      	GND                 
          	               	CD79      	67B4      	PVCCIN_CPU1         
          	               	CD81      	67B4      	PVCCIN_CPU1         
          	               	CD83      	67B4      	PVCCIN_CPU1         
          	               	CD85      	67B4      	PVCCIN_CPU1         
          	               	CD87      	67B4      	PVCCIN_CPU1         
          	               	CD89      	67B4      	PVCCIN_CPU1         
          	               	CE1       	64B3      	UPI_CPU0_CPU1_P0P1_DP<21>
          	               	CE3       	71B2      	GND                 
          	               	CE5       	64B2      	UPI_CPU1_CPU0_P1P0_DN<20>
          	               	CE7       	68B2      	PVCCD_HV_CPU1       
          	               	CE9       	60A3      	P5E_CPU1_PE1_RX_DP<4>
          	               	CE11      	47B4      	VSENSE_PVCCINFAON_CPU1_DN
          	               	CE13      	60A2      	P5E_CPU1_PE1_TX_DN<5>
          	               	CE15      	68B1      	PVCCINFAON_CPU1     
          	               	CE17      	59B2      	TP_DMI_CPU1_PCH_TX_DN<3>
          	               	CE19      	68B3      	PVCCINFAON_CPU1     
          	               	CE21      	50B2      	NC_CPU1_PE1_APROBE<0>
          	               	CE23      	45B3      	TP_H_SBLINK6_CPU1_PMDOWN
          	               	CE25      	45B3      	TP_H_SBLINK4_CPU1_PMSYNC
          	               	CE60      	71B2      	GND                 
          	               	CE62      	47B3      	NC_CPU1_LGSSPARE3   
          	               	CE64      	46B4      	SMB_S3M_CPU1_SCL    
          	               	CE66      	71B2      	GND                 
          	               	CE68      	68B2      	PVPP_HBM_CPU1       
          	               	CE70      	44B3      	CPU1_RSVD<85>       
          	               	CE72      	71B2      	GND                 
          	               	CE74      	69A3      	PVCCFA_EHV_FIVRA_CPU1
          	               	CE76      	71B2      	GND                 
          	               	CE78      	71B2      	GND                 
          	               	CE80      	67B4      	PVCCIN_CPU1         
          	               	CE82      	67B4      	PVCCIN_CPU1         
          	               	CE84      	67B4      	PVCCIN_CPU1         
          	               	CE86      	67B4      	PVCCIN_CPU1         
          	               	CE88      	67B4      	PVCCIN_CPU1         
          	               	CE90      	67B4      	PVCCIN_CPU1         
          	               	CF2       	64B3      	UPI_CPU0_CPU1_P0P1_DN<21>
          	               	CF4       	71B2      	GND                 
          	               	CF6       	64B2      	UPI_CPU1_CPU0_P1P0_DP<20>
          	               	CF8       	71B2      	GND                 
          	               	CF10      	60A3      	P5E_CPU1_PE1_RX_DN<4>
          	               	CF12      	71B2      	GND                 
          	               	CF14      	60A2      	P5E_CPU1_PE1_TX_DN<4>
          	               	CF16      	71B2      	GND                 
          	               	CF18      	59B2      	TP_DMI_CPU1_PCH_TX_DN<4>
          	               	CF20      	71B2      	GND                 
          	               	CF22      	48B2      	NC_CPU1_MDFI_DIE10_NS0
          	               	CF24      	45B3      	TP_H_SBLINK7_CPU1_PMSYNC
          	               	CF26      	45B2      	H_CPU1_MEMHOT_OUT_LVC1_R_N
          	               	CF61      	46B2      	PUD_PCH_BOOT_MODE_CPU1
          	               	CF63      	46B2      	TP_SGPIO_S3M_CPU1_GSXCLK
          	               	CF65      	46B2      	TP_SGPIO_S3M_CPU1_GSXDOUT
          	               	CF67      	68B2      	PVPP_HBM_CPU1       
          	               	CF69      	71B2      	GND                 
          	               	CF71      	71B2      	GND                 
          	               	CF73      	66B2      	NC                  
          	               	CF75      	66B2      	NC                  
          	               	CF77      	66B2      	NC                  
          	               	CF79      	67B4      	PVCCIN_CPU1         
          	               	CF81      	67B4      	PVCCIN_CPU1         
          	               	CF83      	67B4      	PVCCIN_CPU1         
          	               	CF85      	67B4      	PVCCIN_CPU1         
          	               	CF87      	67B4      	PVCCIN_CPU1         
          	               	CF89      	67B4      	PVCCIN_CPU1         
          	               	CF91      	67B4      	PVCCIN_CPU1         
          	               	CG1       	71B2      	GND                 
          	               	CG3       	64B3      	UPI_CPU0_CPU1_P0P1_DP<20>
          	               	CG5       	71B2      	GND                 
          	               	CG7       	64B2      	UPI_CPU1_CPU0_P1P0_DP<19>
          	               	CG9       	71B2      	GND                 
          	               	CG11      	60A3      	P5E_CPU1_PE1_RX_DN<3>
          	               	CG13      	71B2      	GND                 
          	               	CG15      	60A2      	P5E_CPU1_PE1_TX_DP<4>
          	               	CG17      	71B2      	GND                 
          	               	CG19      	59B2      	TP_DMI_CPU1_PCH_TX_DP<4>
          	               	CG21      	71B2      	GND                 
          	               	CG23      	71B2      	GND                 
          	               	CG25      	71B2      	GND                 
          	               	CG60      	49B3      	TP_CPU1_SPARE10     
          	               	CG62      	71B2      	GND                 
          	               	CG64      	71B2      	GND                 
          	               	CG66      	45B3      	FM_CPU1_SKTOCC_LVT3_N
          	               	CG68      	68B2      	PVPP_HBM_CPU1       
          	               	CG70      	71B2      	GND                 
          	               	CG72      	71B2      	GND                 
          	               	CG74      	71B2      	GND                 
          	               	CG76      	66B2      	NC                  
          	               	CG78      	71B2      	GND                 
          	               	CG80      	67B4      	PVCCIN_CPU1         
          	               	CG82      	67B4      	PVCCIN_CPU1         
          	               	CG84      	67B4      	PVCCIN_CPU1         
          	               	CG86      	67B4      	PVCCIN_CPU1         
          	               	CG88      	67B4      	PVCCIN_CPU1         
          	               	CG90      	67B4      	PVCCIN_CPU1         
          	               	CH2       	64B3      	UPI_CPU0_CPU1_P0P1_DN<20>
          	               	CH4       	71B2      	GND                 
          	               	CH6       	64B2      	UPI_CPU1_CPU0_P1P0_DN<19>
          	               	CH8       	71B2      	GND                 
          	               	CH10      	60A3      	P5E_CPU1_PE1_RX_DP<3>
          	               	CH12      	71B2      	GND                 
          	               	CH14      	60A2      	P5E_CPU1_PE1_TX_DP<3>
          	               	CH16      	71B2      	GND                 
          	               	CH18      	59B2      	TP_DMI_CPU1_PCH_TX_DP<5>
          	               	CH20      	71B2      	GND                 
          	               	CH22      	45B3      	PD_CPU1_ENH_MCECC_DIS
          	               	CH24      	45B3      	TP_H_SBLINK6_CPU1_PMSYNC
          	               	CH26      	45B3      	TP_H_SBLINK3_CPU1_PMSYNC
          	               	CH61      	49B3      	TP_CPU1_SPARE9      
          	               	CH63      	46B2      	TP_SGPIO_S3M_CPU1_GSXDIN
          	               	CH65      	46B2      	PU_S3M_CPU1_CPLD_STATUS
          	               	CH67      	71B2      	GND                 
          	               	CH69      	48B2      	NC_CPU1_MDFI_DIE11_EW1
          	               	CH71      	46B4      	TP_PWRGD_S0_PWROK_CPU1_LVC1
          	               	CH73      	71B2      	GND                 
          	               	CH75      	66B2      	NC                  
          	               	CH77      	66B2      	NC                  
          	               	CH79      	71B2      	GND                 
          	               	CH81      	67B4      	PVCCIN_CPU1         
          	               	CH83      	71B2      	GND                 
          	               	CH85      	71B2      	GND                 
          	               	CH87      	71B2      	GND                 
          	               	CH89      	71B2      	GND                 
          	               	CH91      	67B4      	PVCCIN_CPU1         
          	               	CJ1       	64B3      	UPI_CPU0_CPU1_P0P1_DN<19>
          	               	CJ3       	68B1      	PVCCINFAON_CPU1     
          	               	CJ5       	64B2      	UPI_CPU1_CPU0_P1P0_DN<18>
          	               	CJ7       	68B1      	PVCCINFAON_CPU1     
          	               	CJ9       	60A3      	P5E_CPU1_PE1_RX_DP<2>
          	               	CJ11      	68B3      	PVCCINFAON_CPU1     
          	               	CJ13      	60A2      	P5E_CPU1_PE1_TX_DN<3>
          	               	CJ15      	68B1      	PVCCINFAON_CPU1     
          	               	CJ17      	59B2      	TP_DMI_CPU1_PCH_TX_DN<5>
          	               	CJ19      	68B3      	PVCCINFAON_CPU1     
          	               	CJ21      	46B4      	TP_CPU1_IBL_GRST_WARN_CPU1_N
          	               	CJ23      	46B2      	TP_I2C_S3M_RTC_CPU1_SDA
          	               	CJ25      	46B2      	TP_I2C_S3M_RTC_CPU1_RST_N
          	               	CJ60      	71B2      	GND                 
          	               	CJ62      	45B2      	CPU1_RSVD<98>       
          	               	CJ64      	46B2      	PU_S3M_CPU1_CPLD_CONFD
          	               	CJ66      	46B2      	TP_SGPIO_S3M_CPU1_GSXDLOAD
          	               	CJ68      	48B2      	NC_CPU1_MDFI_DIE11_NS0
          	               	CJ70      	48B2      	NC_CPU1_MDFI_DIE11_EW0
          	               	CJ72      	44B3      	PUD_XTAL_CPU1_MODE1 
          	               	CJ74      	66B2      	NC                  
          	               	CJ76      	71B2      	GND                 
          	               	CJ78      	66B2      	NC                  
          	               	CJ80      	71B2      	GND                 
          	               	CJ82      	67B4      	PVCCIN_CPU1         
          	               	CJ84      	67B4      	PVCCIN_CPU1         
          	               	CJ86      	67B4      	PVCCIN_CPU1         
          	               	CJ88      	67B4      	PVCCIN_CPU1         
          	               	CJ90      	67B4      	PVCCIN_CPU1         
          	               	CK2       	64B3      	UPI_CPU0_CPU1_P0P1_DP<19>
          	               	CK4       	71B2      	GND                 
          	               	CK6       	64B2      	UPI_CPU1_CPU0_P1P0_DP<18>
          	               	CK8       	71B2      	GND                 
          	               	CK10      	60A3      	P5E_CPU1_PE1_RX_DN<2>
          	               	CK12      	71B2      	GND                 
          	               	CK14      	60A2      	P5E_CPU1_PE1_TX_DN<2>
          	               	CK16      	71B2      	GND                 
          	               	CK18      	59B2      	TP_DMI_CPU1_PCH_TX_DN<6>
          	               	CK20      	71B2      	GND                 
          	               	CK22      	46B2      	TP_FM_SYS_RST_CPU1_N
          	               	CK24      	46B4      	TP_FM_IBL_PWRBTN_CPU1_N
          	               	CK26      	71B2      	GND                 
          	               	CK61      	49B3      	TP_CPU1_SPARE8      
          	               	CK63      	71A2      	GND                 
          	               	CK65      	46B2      	FM_S3M_CPU1_CPLD_CONFIG_N
          	               	CK67      	48B2      	NC_CPU1_MDFI_DIE11_NS1
          	               	CK69      	71A2      	GND                 
          	               	CK71      	50B3      	PU_CPU1_UPI3_AC_COUPLING
          	               	CK73      	69A3      	PVCCFA_EHV_FIVRA_CPU1
          	               	CK75      	66B2      	NC                  
          	               	CK77      	66B2      	NC                  
          	               	CK79      	69B3      	PVCCFA_EHV_FIVRA_CPU1
          	               	CK81      	71A2      	GND                 
          	               	CK83      	67B4      	PVCCIN_CPU1         
          	               	CK85      	67B4      	PVCCIN_CPU1         
          	               	CK87      	67B4      	PVCCIN_CPU1         
          	               	CK89      	67B4      	PVCCIN_CPU1         
          	               	CK91      	67B4      	PVCCIN_CPU1         
          	               	CL1       	71A2      	GND                 
          	               	CL3       	64B3      	UPI_CPU0_CPU1_P0P1_DN<18>
          	               	CL5       	71A2      	GND                 
          	               	CL7       	64B2      	UPI_CPU1_CPU0_P1P0_DP<17>
          	               	CL9       	71A2      	GND                 
          	               	CL11      	60A3      	P5E_CPU1_PE1_RX_DN<1>
          	               	CL13      	71A2      	GND                 
          	               	CL15      	60A2      	P5E_CPU1_PE1_TX_DP<2>
          	               	CL17      	71A2      	GND                 
          	               	CL19      	59B2      	TP_DMI_CPU1_PCH_TX_DP<6>
          	               	CL21      	45B3      	CPU1_RSVD<107>      
          	               	CL23      	46B2      	TP_I2C_S3M_RTC_CPU1_SCL
          	               	CL25      	45B3      	TP_H_SBLINK2_CPU1_PMSYNC
          	               	CL60      	49B3      	TP_CPU1_SPARE7      
          	               	CL62      	71A2      	GND                 
          	               	CL64      	45B2      	CPU1_RSVD<110>      
          	               	CL66      	46B2      	TP_CPU1_SSC_SYNC    
          	               	CL68      	50B2      	NC_CPU1_PE3_APROBE<0>
          	               	CL70      	49B3      	TP_CPU1_SPARE12     
          	               	CL72      	44B3      	PUD_XTAL_CPU1_MODE0 
          	               	CL74      	71A2      	GND                 
          	               	CL76      	66B2      	NC                  
          	               	CL78      	71A2      	GND                 
          	               	CL80      	71A2      	GND                 
          	               	CL82      	71A2      	GND                 
          	               	CL84      	67B4      	PVCCIN_CPU1         
          	               	CL86      	67B4      	PVCCIN_CPU1         
          	               	CL88      	67B4      	PVCCIN_CPU1         
          	               	CL90      	67B4      	PVCCIN_CPU1         
          	               	CM2       	64B3      	UPI_CPU0_CPU1_P0P1_DP<18>
          	               	CM4       	71A2      	GND                 
          	               	CM6       	64B2      	UPI_CPU1_CPU0_P1P0_DN<17>
          	               	CM8       	71A2      	GND                 
          	               	CM10      	60A3      	P5E_CPU1_PE1_RX_DP<1>
          	               	CM12      	71A2      	GND                 
          	               	CM14      	60A2      	P5E_CPU1_PE1_TX_DP<1>
          	               	CM16      	71A2      	GND                 
          	               	CM18      	59B2      	TP_DMI_CPU1_PCH_TX_DP<7>
          	               	CM20      	71A2      	GND                 
          	               	CM22      	71A2      	GND                 
          	               	CM24      	71A2      	GND                 
          	               	CM26      	45B3      	TP_H_SBLINK3_CPU1_PMDOWN
          	               	CM61      	71A2      	GND                 
          	               	CM63      	45B2      	CPU1_RSVD<115>      
          	               	CM65      	71A2      	GND                 
          	               	CM67      	71B2      	GND                 
          	               	CM69      	50B2      	NC_CPU1_PE3_APROBE<1>
          	               	CM71      	45B3      	SMB_S3M_CPU1_PIROM_3V3AUX_SDA_1
          	               	CM73      	69B3      	PVCCFA_EHV_FIVRA_CPU1
          	               	CM75      	66B2      	NC                  
          	               	CM77      	66B2      	NC                  
          	               	CM79      	71B2      	GND                 
          	               	CM81      	71B2      	GND                 
          	               	CM83      	71B2      	GND                 
          	               	CM85      	71B2      	GND                 
          	               	CM87      	67B4      	PVCCIN_CPU1         
          	               	CM89      	67B4      	PVCCIN_CPU1         
          	               	CM91      	67B4      	PVCCIN_CPU1         
          	               	CN1       	64B3      	UPI_CPU0_CPU1_P0P1_DN<17>
          	               	CN3       	68B1      	PVCCINFAON_CPU1     
          	               	CN5       	64B2      	UPI_CPU1_CPU0_P1P0_DN<16>
          	               	CN7       	68B1      	PVCCINFAON_CPU1     
          	               	CN9       	60A3      	P5E_CPU1_PE1_RX_DP<0>
          	               	CN11      	68B1      	PVCCINFAON_CPU1     
          	               	CN13      	60A2      	P5E_CPU1_PE1_TX_DN<1>
          	               	CN15      	68B1      	PVCCINFAON_CPU1     
          	               	CN17      	59B2      	TP_DMI_CPU1_PCH_TX_DN<7>
          	               	CN19      	68B3      	PVCCINFAON_CPU1     
          	               	CN21      	46B4      	TP_FM_IBL_SLPS4_CPU1_R_N
          	               	CN23      	46B4      	NC_FM_IBL_ADR_ACK_CPU1
          	               	CN25      	45B3      	H_CPU0_PMDOWN_CPU1  
          	               	CN60      	47B3      	NC_CPU1_LGSSPARE1   
          	               	CN62      	45B2      	CPU1_RSVD<120>      
          	               	CN64      	68B1      	PVCCINFAON_CPU1     
          	               	CN66      	68B1      	PVCCINFAON_CPU1     
          	               	CN68      	71B2      	GND                 
          	               	CN70      	71B2      	GND                 
          	               	CN72      	71B2      	GND                 
          	               	CN74      	71B2      	GND                 
          	               	CN76      	71B2      	GND                 
          	               	CN78      	69B3      	PVCCFA_EHV_FIVRA_CPU1
          	               	CN80      	66B3      	GND                 
          	               	CN82      	66B3      	GND                 
          	               	CN84      	71B2      	GND                 
          	               	CN86      	71B2      	GND                 
          	               	CN88      	67B4      	PVCCIN_CPU1         
          	               	CN90      	67B4      	PVCCIN_CPU1         
          	               	CP2       	64B3      	UPI_CPU0_CPU1_P0P1_DP<17>
          	               	CP4       	71B2      	GND                 
          	               	CP6       	64B2      	UPI_CPU1_CPU0_P1P0_DP<16>
          	               	CP8       	71B2      	GND                 
          	               	CP10      	60A3      	P5E_CPU1_PE1_RX_DN<0>
          	               	CP12      	71B2      	GND                 
          	               	CP14      	60A2      	P5E_CPU1_PE1_TX_DN<0>
          	               	CP16      	71B2      	GND                 
          	               	CP18      	71B2      	GND                 
          	               	CP20      	45B2      	H_CPU1_PM_FAST_WAKE_N
          	               	CP22      	46B4      	TP_JTAG_CPU1_PLD_TDO_R
          	               	CP24      	46B4      	NC_FM_IBL_ADR_COMPLETE_CPU1_R
          	               	CP26      	45B3      	TP_H_SBLINK2_CPU1_PMDOWN
          	               	CP61      	47B3      	NC_CPU1_LGSSPARE5   
          	               	CP63      	68B3      	PVCCINFAON_CPU1     
          	               	CP65      	68B1      	PVCCINFAON_CPU1     
          	               	CP67      	68B1      	PVCCINFAON_CPU1     
          	               	CP69      	50B3      	NC_CPU1_UPI3_APROBE<0>
          	               	CP71      	45B3      	PD_PIROM_CPU1_ADDR2 
          	               	CP73      	69B3      	PVCCFA_EHV_FIVRA_CPU1
          	               	CP75      	71B2      	GND                 
          	               	CP77      	71B2      	GND                 
          	               	CP79      	71B2      	GND                 
          	               	CP81      	66B3      	GND                 
          	               	CP83      	71B2      	GND                 
          	               	CP85      	61A2      	P5E_CPU1_PE3_TX_DN<15>
          	               	CP87      	71B2      	GND                 
          	               	CP89      	67B4      	PVCCIN_CPU1         
          	               	CP91      	71B2      	GND                 
          	               	CR1       	71B2      	GND                 
          	               	CR3       	64B3      	UPI_CPU0_CPU1_P0P1_DN<16>
          	               	CR5       	71B2      	GND                 
          	               	CR7       	64B2      	UPI_CPU1_CPU0_P1P0_DP<15>
          	               	CR9       	71B2      	GND                 
          	               	CR11      	71B2      	GND                 
          	               	CR13      	71B2      	GND                 
          	               	CR15      	60A2      	P5E_CPU1_PE1_TX_DP<0>
          	               	CR17      	71B2      	GND                 
          	               	CR19      	45B3      	TP_H_SBLINK5_CPU1_PMSYNC
          	               	CR21      	46B4      	TP_FM_IBL_SLPS3_CPU1_R_N
          	               	CR23      	45B2      	CPU1_RSVD<126>      
          	               	CR25      	48B2      	NC_CPU1_VIEWPIN_GNR2
          	               	CR60      	47B3      	NC_CPU1_LGSSPARE0   
          	               	CR62      	71B2      	GND                 
          	               	CR64      	71B2      	GND                 
          	               	CR66      	68B1      	PVCCINFAON_CPU1     
          	               	CR68      	50B3      	NC_CPU1_UPI3_APROBE<1>
          	               	CR70      	45B3      	PU_PIROM_CPU1_ADDR0 
          	               	CR72      	45B3      	PU_PIROM_CPU1_SM_WP 
          	               	CR74      	66B2      	NC                  
          	               	CR76      	66B2      	NC                  
          	               	CR78      	71B2      	GND                 
          	               	CR80      	66B3      	GND                 
          	               	CR82      	66B3      	GND                 
          	               	CR84      	71B2      	GND                 
          	               	CR86      	61B2      	P5E_CPU1_PE3_TX_DP<15>
          	               	CR88      	71B2      	GND                 
          	               	CR90      	71B2      	GND                 
          	               	CT2       	64B3      	UPI_CPU0_CPU1_P0P1_DP<16>
          	               	CT4       	71B2      	GND                 
          	               	CT6       	64B2      	UPI_CPU1_CPU0_P1P0_DN<15>
          	               	CT8       	71B2      	GND                 
          	               	CT10      	71B2      	GND                 
          	               	CT12      	71B2      	GND                 
          	               	CT14      	61B2      	P5E_CPU1_PE2_TX_DP<0>
          	               	CT16      	71B2      	GND                 
          	               	CT18      	44B3      	I3C_SPD_DDREFGH_CPU1_SDA
          	               	CT20      	44B2      	PD_CPU1_TXT_PLTEN   
          	               	CT22      	46B4      	TP_JTAG_CPU1_PLD_TDI
          	               	CT24      	46B4      	NC_FM_IBL_ADR_TRIGGER_CPU1_R
          	               	CT26      	48B2      	NC_CPU1_VIEWPIN_GNR0
          	               	CT61      	44B2      	PU_CPU1_SOCKET_ID2  
          	               	CT63      	68B3      	PVCCINFAON_CPU1     
          	               	CT65      	68B1      	PVCCINFAON_CPU1     
          	               	CT67      	68B1      	PVCCINFAON_CPU1     
          	               	CT69      	71B2      	GND                 
          	               	CT71      	45B3      	PD_PIROM_CPU1_ADDR1 
          	               	CT73      	71B2      	GND                 
          	               	CT75      	66B2      	NC                  
          	               	CT77      	69B3      	PVCCFA_EHV_FIVRA_CPU1
          	               	CT79      	66B3      	GND                 
          	               	CT81      	71B2      	GND                 
          	               	CT83      	66B3      	GND                 
          	               	CT85      	69B3      	PVCCFA_EHV_FIVRA_CPU1
          	               	CT87      	61A2      	P5E_CPU1_PE3_TX_DN<14>
          	               	CT89      	71B2      	GND                 
          	               	CT91      	61B3      	P5E_CPU1_PE3_RX_DP<15>
          	               	CU1       	64B3      	UPI_CPU0_CPU1_P0P1_DP<15>
          	               	CU3       	68B1      	PVCCINFAON_CPU1     
          	               	CU5       	64B2      	UPI_CPU1_CPU0_P1P0_DN<14>
          	               	CU7       	68B1      	PVCCINFAON_CPU1     
          	               	CU9       	61B3      	P5E_CPU1_PE2_RX_DN<0>
          	               	CU11      	68B1      	PVCCINFAON_CPU1     
          	               	CU13      	61B2      	P5E_CPU1_PE2_TX_DN<0>
          	               	CU15      	68B1      	PVCCINFAON_CPU1     
          	               	CU17      	44B3      	I3C_SPD_DDREFGH_CPU1_SCL
          	               	CU19      	71B2      	GND                 
          	               	CU21      	71B2      	GND                 
          	               	CU23      	71B2      	GND                 
          	               	CU25      	71B2      	GND                 
          	               	CU60      	71B2      	GND                 
          	               	CU62      	47B3      	NC_CPU1_LGSSPARE2   
          	               	CU64      	68B1      	PVCCINFAON_CPU1     
          	               	CU66      	71B2      	GND                 
          	               	CU68      	71B2      	GND                 
          	               	CU70      	45B3      	SMB_S3M_CPU1_PIROM_3V3AUX_SCL_1
          	               	CU72      	71B2      	GND                 
          	               	CU74      	66B2      	NC                  
          	               	CU76      	66B2      	NC                  
          	               	CU78      	71B2      	GND                 
          	               	CU80      	66B3      	GND                 
          	               	CU82      	66B3      	GND                 
          	               	CU84      	71B2      	GND                 
          	               	CU86      	61B2      	P5E_CPU1_PE3_TX_DP<14>
          	               	CU88      	71B2      	GND                 
          	               	CU90      	61A3      	P5E_CPU1_PE3_RX_DN<15>
          	               	CV2       	64B3      	UPI_CPU0_CPU1_P0P1_DN<15>
          	               	CV4       	71B2      	GND                 
          	               	CV6       	64B2      	UPI_CPU1_CPU0_P1P0_DP<14>
          	               	CV8       	71B2      	GND                 
          	               	CV10      	61B3      	P5E_CPU1_PE2_RX_DP<0>
          	               	CV12      	71B2      	GND                 
          	               	CV14      	61B2      	P5E_CPU1_PE2_TX_DN<1>
          	               	CV16      	71A3      	GND                 
          	               	CV18      	45B3      	TP_H_SBLINK5_CPU1_PMDOWN
          	               	CV20      	46B4      	PWRGD_PLT_AUX_CPU1_LVT3
          	               	CV22      	46B4      	TP_JTAG_CPU1_PLD_TMS
          	               	CV24      	45B2      	CPU1_RSVD<135>      
          	               	CV26      	71A3      	GND                 
          	               	CV61      	68B3      	PVCCINFAON_CPU1     
          	               	CV63      	68B3      	PVCCINFAON_CPU1     
          	               	CV65      	68B1      	PVCCINFAON_CPU1     
          	               	CV67      	68B1      	PVCCINFAON_CPU1     
          	               	CV69      	46B4      	NC_UART_IBL_CPU1_TXD
          	               	CV71      	46B4      	NC_UART_IBL_CPU1_CTS
          	               	CV73      	66B2      	NC                  
          	               	CV75      	71A3      	GND                 
          	               	CV77      	66B2      	NC                  
          	               	CV79      	71A3      	GND                 
          	               	CV81      	66B3      	GND                 
          	               	CV83      	71A3      	GND                 
          	               	CV85      	61A2      	P5E_CPU1_PE3_TX_DN<13>
          	               	CV87      	71A3      	GND                 
          	               	CV89      	61A3      	P5E_CPU1_PE3_RX_DN<14>
          	               	CV91      	71A3      	GND                 
          	               	CW1       	71A3      	GND                 
          	               	CW3       	64B3      	UPI_CPU0_CPU1_P0P1_DP<14>
          	               	CW5       	71A3      	GND                 
          	               	CW7       	64B2      	UPI_CPU1_CPU0_P1P0_DP<13>
          	               	CW9       	71A3      	GND                 
          	               	CW11      	61B3      	P5E_CPU1_PE2_RX_DP<1>
          	               	CW13      	71A3      	GND                 
          	               	CW15      	61B2      	P5E_CPU1_PE2_TX_DP<1>
          	               	CW17      	71A3      	GND                 
          	               	CW19      	50B3      	PU_CPU1_UPI1_AC_COUPLING
          	               	CW21      	46B4      	TP_FM_IBL_SLPS5_CPU1_R_N
          	               	CW23      	45B2      	CPU1_RSVD<139>      
          	               	CW25      	45B2      	CPU1_RSVD<140>      
          	               	CW27      	44B3      	CLK_100M_DB2000_CPU1_BCLK3_DN
          	               	CW29      	44B3      	CLK_100M_DB2000_CPU1_BCLK1_DP
          	               	CW31      	44B3      	CLK_25M_NSSC_CPU1_DN
          	               	CW33      	71A3      	GND                 
          	               	CW35      	68B2      	PVCCD_HV_CPU1       
          	               	CW37      	68B2      	PVCCD_HV_CPU1       
          	               	CW39      	45B3      	H_CPU0_PMSYNC_CPU1  
          	               	CW41      	48B3      	NC_CPU1_HBM1_VIEWDIG1
          	               	CW43      	49B3      	TP_CPU1_SPARE6      
          	               	CW45      	45B3      	PWRGD_DRAMPWRGD_CPU1_GH_LVC1_R
          	               	CW48      	56A2      	M_F_CPU1_ALERT_N    
          	               	CW50      	57A2      	M_G_CPU1_ALERT_N    
          	               	CW52      	68B2      	PVCCD_HV_CPU1       
          	               	CW54      	68B2      	PVCCD_HV_CPU1       
          	               	CW56      	68B2      	PVCCD_HV_CPU1       
          	               	CW58      	48B2      	NC_CPU1_VIEWPIN_GNR1
          	               	CW60      	44B2      	PU_CPU1_SOCKET_ID0  
          	               	CW62      	68B3      	PVCCINFAON_CPU1     
          	               	CW64      	68B1      	PVCCINFAON_CPU1     
          	               	CW66      	68B1      	PVCCINFAON_CPU1     
          	               	CW68      	45B2      	CPU1_RSVD<144>      
          	               	CW70      	71A3      	GND                 
          	               	CW72      	71A3      	GND                 
          	               	CW74      	66B2      	NC                  
          	               	CW76      	66B2      	NC                  
          	               	CW78      	71A3      	GND                 
          	               	CW80      	66B3      	GND                 
          	               	CW82      	66B3      	GND                 
          	               	CW84      	71A3      	GND                 
          	               	CW86      	61B2      	P5E_CPU1_PE3_TX_DP<13>
          	               	CW88      	71A3      	GND                 
          	               	CW90      	61B3      	P5E_CPU1_PE3_RX_DP<14>
          	               	CY2       	64B3      	UPI_CPU0_CPU1_P0P1_DN<14>
          	               	CY4       	71A3      	GND                 
          	               	CY6       	64B2      	UPI_CPU1_CPU0_P1P0_DN<13>
          	               	CY8       	71A3      	GND                 
          	               	CY10      	61B3      	P5E_CPU1_PE2_RX_DN<1>
          	               	CY12      	71A3      	GND                 
          	               	CY14      	61B2      	P5E_CPU1_PE2_TX_DP<2>
          	               	CY16      	71A3      	GND                 
          	               	CY18      	71B3      	GND                 
          	               	CY20      	46B2      	FM_S3M_CPU1_CPLD_CRC_ERROR
          	               	CY22      	46B4      	PD_JTAG_CPU1_PLD_TCK
          	               	CY24      	47B4      	NC_CPU1_DDR45_VIEWDIG0
          	               	CY26      	71B3      	GND                 
          	               	CY28      	44B3      	CLK_100M_DB2000_CPU1_BCLK1_DN
          	               	CY30      	71B3      	GND                 
          	               	CY32      	44B3      	CLK_25M_NSSC_CPU1_DP
          	               	CY34      	68B2      	PVCCD_HV_CPU1       
          	               	CY36      	68B2      	PVCCD_HV_CPU1       
          	               	CY38      	47B4      	NC_CPU1_DDR45_VIEWDIG1
          	               	CY40      	45B3      	TP_H_CPU1_PMDOWN_PCH_R
          	               	CY42      	44B2      	RST_CPU1_DRAM_EF_N  
          	               	CY44      	45B3      	PWRGD_DRAMPWRGD_CPU1_EF_LVC1_R
          	               	CY47      	55A2      	M_E_CPU1_ALERT_N    
          	               	CY49      	47B4      	NC_CPU1_DDR67_VIEWDIG1
          	               	CY51      	58A2      	M_H_CPU1_ALERT_N    
          	               	CY53      	68B2      	PVCCD_HV_CPU1       
          	               	CY55      	44B2      	RST_CPU1_DRAM_GH_N  
          	               	CY57      	48B2      	NC_CPU1_VIEWPIN_GNR3
          	               	CY59      	44B2      	PU_CPU1_LEGACY_SKT  
          	               	CY61      	44B2      	PU_CPU1_SOCKET_ID1  
          	               	CY63      	71B3      	GND                 
          	               	CY65      	68B1      	PVCCINFAON_CPU1     
          	               	CY67      	68B1      	PVCCINFAON_CPU1     
          	               	CY69      	46B4      	NC_UART_IBL_CPU1_RXD
          	               	CY71      	46B4      	NC_UART_IBL_CPU1_RTS
          	               	CY73      	71B3      	GND                 
          	               	CY75      	69B3      	PVCCFA_EHV_FIVRA_CPU1
          	               	CY77      	71B3      	GND                 
          	               	CY79      	69B3      	PVCCFA_EHV_FIVRA_CPU1
          	               	CY81      	71B3      	GND                 
          	               	CY83      	71B3      	GND                 
          	               	CY85      	69B3      	PVCCFA_EHV_FIVRA_CPU1
          	               	CY87      	61A2      	P5E_CPU1_PE3_TX_DN<12>
          	               	CY89      	69B3      	PVCCFA_EHV_FIVRA_CPU1
          	               	CY91      	61B3      	P5E_CPU1_PE3_RX_DP<13>
          	               	D4        	44B3      	CPU1_RSVD<153>      
          	               	D6        	73B2      	GND                 
          	               	D8        	73B2      	GND                 
          	               	D10       	73B2      	GND                 
          	               	D12       	73B2      	GND                 
          	               	D14       	73B2      	GND                 
          	               	D16       	73B2      	GND                 
          	               	D18       	73B2      	GND                 
          	               	D20       	73B2      	GND                 
          	               	D22       	73B2      	GND                 
          	               	D24       	73B2      	GND                 
          	               	D26       	73B2      	GND                 
          	               	D28       	73B2      	GND                 
          	               	D30       	73B2      	GND                 
          	               	D32       	73B2      	GND                 
          	               	D34       	73B2      	GND                 
          	               	D36       	73B2      	GND                 
          	               	D38       	73B2      	GND                 
          	               	D40       	73B2      	GND                 
          	               	D42       	73B2      	GND                 
          	               	D44       	73B2      	GND                 
          	               	D47       	73B2      	GND                 
          	               	D49       	73B2      	GND                 
          	               	D51       	73B2      	GND                 
          	               	D53       	73B2      	GND                 
          	               	D55       	73B2      	GND                 
          	               	D57       	73B2      	GND                 
          	               	D59       	73B2      	GND                 
          	               	D61       	73B2      	GND                 
          	               	D63       	73B2      	GND                 
          	               	D65       	73B2      	GND                 
          	               	D67       	73B2      	GND                 
          	               	D69       	73B2      	GND                 
          	               	D71       	73B2      	GND                 
          	               	D73       	51B3      	M_A_CPU1_SA_DQ<18>  
          	               	D75       	51B3      	M_A_CPU1_SA_DQ<5>   
          	               	D77       	51B2      	M_A_CPU1_SA_DQS_DP<0>
          	               	D79       	73B2      	GND                 
          	               	D81       	73B2      	GND                 
          	               	D83       	73B2      	GND                 
          	               	D85       	65B2      	UPI_CPU1_CPU0_P2P2_DP<0>
          	               	D87       	65B2      	UPI_CPU1_CPU0_P2P2_DN<2>
          	               	DA1       	64B3      	UPI_CPU0_CPU1_P0P1_DP<13>
          	               	DA3       	68B1      	PVCCINFAON_CPU1     
          	               	DA5       	64B2      	UPI_CPU1_CPU0_P1P0_DN<12>
          	               	DA7       	68B1      	PVCCINFAON_CPU1     
          	               	DA9       	61B3      	P5E_CPU1_PE2_RX_DN<2>
          	               	DA11      	68B1      	PVCCINFAON_CPU1     
          	               	DA13      	61B2      	P5E_CPU1_PE2_TX_DN<2>
          	               	DA15      	68B1      	PVCCINFAON_CPU1     
          	               	DA17      	58B3      	M_H_CPU1_SB_DQ<29>  
          	               	DA19      	71B3      	GND                 
          	               	DA21      	68B3      	PVCCINFAON_CPU1     
          	               	DA23      	71B3      	GND                 
          	               	DA25      	71B3      	GND                 
          	               	DA27      	44B3      	CLK_100M_DB2000_CPU1_BCLK3_DP
          	               	DA29      	71B3      	GND                 
          	               	DA31      	71B3      	GND                 
          	               	DA33      	71B3      	GND                 
          	               	DA35      	71B3      	GND                 
          	               	DA37      	71B3      	GND                 
          	               	DA39      	45B3      	TP_H_CPU1_PMSYNC_PCH_INTRP_R
          	               	DA41      	71B3      	GND                 
          	               	DA43      	71B3      	GND                 
          	               	DA45      	47B4      	NC_CPU1_DDR67_VIEWDIG0
          	               	DA48      	71B3      	GND                 
          	               	DA50      	71B3      	GND                 
          	               	DA52      	44B2      	PD_CPU1_PROCDIS_COD_GTL_N
          	               	DA54      	71B3      	GND                 
          	               	DA56      	71B3      	GND                 
          	               	DA58      	71B3      	GND                 
          	               	DA60      	71B3      	GND                 
          	               	DA62      	71B3      	GND                 
          	               	DA64      	68B1      	PVCCINFAON_CPU1     
          	               	DA66      	71B3      	GND                 
          	               	DA68      	71B3      	GND                 
          	               	DA70      	49B3      	TP_CPU1_SPARE4      
          	               	DA72      	71B3      	GND                 
          	               	DA74      	71B3      	GND                 
          	               	DA76      	66B2      	NC                  
          	               	DA78      	66B3      	GND                 
          	               	DA80      	71B3      	GND                 
          	               	DA82      	71B3      	GND                 
          	               	DA84      	71B3      	GND                 
          	               	DA86      	61B2      	P5E_CPU1_PE3_TX_DP<12>
          	               	DA88      	71B3      	GND                 
          	               	DA90      	61A3      	P5E_CPU1_PE3_RX_DN<13>
          	               	DB2       	64B3      	UPI_CPU0_CPU1_P0P1_DN<13>
          	               	DB4       	71B3      	GND                 
          	               	DB6       	64B2      	UPI_CPU1_CPU0_P1P0_DP<12>
          	               	DB8       	71B3      	GND                 
          	               	DB10      	61B3      	P5E_CPU1_PE2_RX_DP<2>
          	               	DB12      	71B3      	GND                 
          	               	DB14      	61B2      	P5E_CPU1_PE2_TX_DN<3>
          	               	DB16      	71B3      	GND                 
          	               	DB18      	58B2      	M_H_CPU1_SB_DQS_DN<3>
          	               	DB20      	71B3      	GND                 
          	               	DB22      	71B3      	GND                 
          	               	DB24      	58B2      	M_H_CPU1_SB_DQS_DP<1>
          	               	DB26      	71B3      	GND                 
          	               	DB28      	71B3      	GND                 
          	               	DB30      	58B2      	M_H_CPU1_SB_DQS_DP<0>
          	               	DB32      	71B3      	GND                 
          	               	DB34      	71B3      	GND                 
          	               	DB36      	58B2      	M_H_CPU1_SB_DQS_DP<9>
          	               	DB38      	71B3      	GND                 
          	               	DB40      	71B3      	GND                 
          	               	DB42      	58A3      	M_H_CPU1_CLK_DP<1>  
          	               	DB44      	71B3      	GND                 
          	               	DB47      	71B3      	GND                 
          	               	DB49      	58B2      	M_H_CPU1_SA_CA<0>   
          	               	DB51      	71B3      	GND                 
          	               	DB53      	71B3      	GND                 
          	               	DB55      	58B2      	M_H_CPU1_SA_DQS_DP<4>
          	               	DB57      	71B3      	GND                 
          	               	DB59      	71B3      	GND                 
          	               	DB61      	58B2      	M_H_CPU1_SA_DQS_DP<3>
          	               	DB63      	71B3      	GND                 
          	               	DB65      	71B3      	GND                 
          	               	DB67      	58B2      	M_H_CPU1_SA_DQS_DP<2>
          	               	DB69      	71B3      	GND                 
          	               	DB71      	71B3      	GND                 
          	               	DB73      	58B2      	M_H_CPU1_SA_DQS_DN<1>
          	               	DB75      	71B3      	GND                 
          	               	DB77      	71B3      	GND                 
          	               	DB79      	66B3      	GND                 
          	               	DB81      	66B3      	GND                 
          	               	DB83      	66B3      	GND                 
          	               	DB85      	61A2      	P5E_CPU1_PE3_TX_DN<11>
          	               	DB87      	71B3      	GND                 
          	               	DB89      	61A3      	P5E_CPU1_PE3_RX_DN<12>
          	               	DB91      	71A4      	GND                 
          	               	DC1       	71A4      	GND                 
          	               	DC3       	64B3      	UPI_CPU0_CPU1_P0P1_DP<12>
          	               	DC5       	71A4      	GND                 
          	               	DC7       	64B2      	UPI_CPU1_CPU0_P1P0_DP<11>
          	               	DC9       	71A4      	GND                 
          	               	DC11      	61B3      	P5E_CPU1_PE2_RX_DP<3>
          	               	DC13      	71A4      	GND                 
          	               	DC15      	61B2      	P5E_CPU1_PE2_TX_DP<3>
          	               	DC17      	58B3      	M_H_CPU1_SB_DQ<31>  
          	               	DC19      	58B3      	M_H_CPU1_SB_DQ<25>  
          	               	DC21      	71A4      	GND                 
          	               	DC23      	58B3      	M_H_CPU1_SB_DQ<12>  
          	               	DC25      	58A3      	M_H_CPU1_SB_DQ<9>   
          	               	DC27      	71A4      	GND                 
          	               	DC29      	58A3      	M_H_CPU1_SB_DQ<4>   
          	               	DC31      	58A3      	M_H_CPU1_SB_DQ<1>   
          	               	DC33      	71A4      	GND                 
          	               	DC35      	58A3      	M_H_CPU1_SB_CB<0>   
          	               	DC37      	58A3      	M_H_CPU1_SB_CB<7>   
          	               	DC39      	71A4      	GND                 
          	               	DC41      	58B2      	M_H_CPU1_SA_CA<6>   
          	               	DC43      	55A2      	M_E_CPU1_SA_RSP<1>  
          	               	DC45      	71A4      	GND                 
          	               	DC48      	58B2      	M_H_CPU1_SA_CA<2>   
          	               	DC50      	58A2      	M_H_CPU1_SA_CS_N<3> 
          	               	DC52      	71A4      	GND                 
          	               	DC54      	58B3      	M_H_CPU1_SA_CB<4>   
          	               	DC56      	58B3      	M_H_CPU1_SA_CB<1>   
          	               	DC58      	71A4      	GND                 
          	               	DC60      	58B3      	M_H_CPU1_SA_DQ<28>  
          	               	DC62      	58B3      	M_H_CPU1_SA_DQ<25>  
          	               	DC64      	71A4      	GND                 
          	               	DC66      	58B3      	M_H_CPU1_SA_DQ<20>  
          	               	DC68      	58B3      	M_H_CPU1_SA_DQ<17>  
          	               	DC70      	71A4      	GND                 
          	               	DC72      	58B3      	M_H_CPU1_SA_DQ<12>  
          	               	DC74      	58B3      	M_H_CPU1_SA_DQ<9>   
          	               	DC76      	71A4      	GND                 
          	               	DC78      	71A4      	GND                 
          	               	DC80      	71A4      	GND                 
          	               	DC82      	66B3      	GND                 
          	               	DC84      	71A4      	GND                 
          	               	DC86      	61B2      	P5E_CPU1_PE3_TX_DP<11>
          	               	DC88      	71A4      	GND                 
          	               	DC90      	61B3      	P5E_CPU1_PE3_RX_DP<12>
          	               	DD2       	64B3      	UPI_CPU0_CPU1_P0P1_DN<12>
          	               	DD4       	71A4      	GND                 
          	               	DD6       	64B2      	UPI_CPU1_CPU0_P1P0_DN<11>
          	               	DD8       	71A4      	GND                 
          	               	DD10      	61B3      	P5E_CPU1_PE2_RX_DN<3>
          	               	DD12      	71A4      	GND                 
          	               	DD14      	61B2      	P5E_CPU1_PE2_TX_DP<4>
          	               	DD16      	71B4      	GND                 
          	               	DD18      	58B2      	M_H_CPU1_SB_DQS_DP<3>
          	               	DD20      	58B3      	M_H_CPU1_SB_DQ<24>  
          	               	DD22      	58B3      	M_H_CPU1_SB_DQ<13>  
          	               	DD24      	58B2      	M_H_CPU1_SB_DQS_DN<1>
          	               	DD26      	58A3      	M_H_CPU1_SB_DQ<8>   
          	               	DD28      	58A3      	M_H_CPU1_SB_DQ<7>   
          	               	DD30      	58B2      	M_H_CPU1_SB_DQS_DN<0>
          	               	DD32      	58A3      	M_H_CPU1_SB_DQ<0>   
          	               	DD34      	58A3      	M_H_CPU1_SB_CB<1>   
          	               	DD36      	58B2      	M_H_CPU1_SB_DQS_DN<9>
          	               	DD38      	58A3      	M_H_CPU1_SB_CB<6>   
          	               	DD40      	58B2      	M_H_CPU1_SA_PAR     
          	               	DD42      	58A3      	M_H_CPU1_CLK_DN<1>  
          	               	DD44      	55A2      	M_E_CPU1_SA_RSP<0>  
          	               	DD47      	58B2      	M_H_CPU1_SA_CA<4>   
          	               	DD49      	71B4      	GND                 
          	               	DD51      	58A2      	M_H_CPU1_SA_CS_N<2> 
          	               	DD53      	58B3      	M_H_CPU1_SA_CB<5>   
          	               	DD55      	58B2      	M_H_CPU1_SA_DQS_DN<4>
          	               	DD57      	58B3      	M_H_CPU1_SA_CB<0>   
          	               	DD59      	58B3      	M_H_CPU1_SA_DQ<29>  
          	               	DD61      	58B2      	M_H_CPU1_SA_DQS_DN<3>
          	               	DD63      	58B3      	M_H_CPU1_SA_DQ<24>  
          	               	DD65      	58B3      	M_H_CPU1_SA_DQ<21>  
          	               	DD67      	58B2      	M_H_CPU1_SA_DQS_DN<2>
          	               	DD69      	58B3      	M_H_CPU1_SA_DQ<16>  
          	               	DD71      	58B3      	M_H_CPU1_SA_DQ<13>  
          	               	DD73      	58B2      	M_H_CPU1_SA_DQS_DP<1>
          	               	DD75      	58B3      	M_H_CPU1_SA_DQ<8>   
          	               	DD77      	69B3      	PVCCFA_EHV_FIVRA_CPU1
          	               	DD79      	71B4      	GND                 
          	               	DD81      	66B3      	GND                 
          	               	DD83      	69B3      	PVCCFA_EHV_FIVRA_CPU1
          	               	DD85      	69B3      	PVCCFA_EHV_FIVRA_CPU1
          	               	DD87      	61A2      	P5E_CPU1_PE3_TX_DN<10>
          	               	DD89      	69B3      	PVCCFA_EHV_FIVRA_CPU1
          	               	DD91      	61A3      	P5E_CPU1_PE3_RX_DN<11>
          	               	DE1       	64B3      	UPI_CPU0_CPU1_P0P1_DN<11>
          	               	DE3       	68B1      	PVCCINFAON_CPU1     
          	               	DE5       	64B2      	UPI_CPU1_CPU0_P1P0_DN<10>
          	               	DE7       	68B1      	PVCCINFAON_CPU1     
          	               	DE9       	61B3      	P5E_CPU1_PE2_RX_DN<4>
          	               	DE11      	68B1      	PVCCINFAON_CPU1     
          	               	DE13      	61B2      	P5E_CPU1_PE2_TX_DN<4>
          	               	DE15      	68B1      	PVCCINFAON_CPU1     
          	               	DE17      	71B4      	GND                 
          	               	DE19      	71B4      	GND                 
          	               	DE21      	71B4      	GND                 
          	               	DE23      	71B4      	GND                 
          	               	DE25      	71B4      	GND                 
          	               	DE27      	71B4      	GND                 
          	               	DE29      	71B4      	GND                 
          	               	DE31      	71B4      	GND                 
          	               	DE33      	71B4      	GND                 
          	               	DE35      	71B4      	GND                 
          	               	DE37      	71B4      	GND                 
          	               	DE39      	71B4      	GND                 
          	               	DE41      	71B4      	GND                 
          	               	DE43      	71B4      	GND                 
          	               	DE45      	71B4      	GND                 
          	               	DE48      	71B4      	GND                 
          	               	DE50      	71B4      	GND                 
          	               	DE52      	71B4      	GND                 
          	               	DE54      	71B4      	GND                 
          	               	DE56      	71B4      	GND                 
          	               	DE58      	71B4      	GND                 
          	               	DE60      	71B4      	GND                 
          	               	DE62      	71B4      	GND                 
          	               	DE64      	71B4      	GND                 
          	               	DE66      	71B4      	GND                 
          	               	DE68      	71B4      	GND                 
          	               	DE70      	71B4      	GND                 
          	               	DE72      	71B4      	GND                 
          	               	DE74      	71B4      	GND                 
          	               	DE76      	71B4      	GND                 
          	               	DE78      	66B3      	GND                 
          	               	DE80      	66B3      	GND                 
          	               	DE82      	71B4      	GND                 
          	               	DE84      	71B4      	GND                 
          	               	DE86      	61A2      	P5E_CPU1_PE3_TX_DP<10>
          	               	DE88      	71B4      	GND                 
          	               	DE90      	61B3      	P5E_CPU1_PE3_RX_DP<11>
          	               	DF2       	64B3      	UPI_CPU0_CPU1_P0P1_DP<11>
          	               	DF4       	71B4      	GND                 
          	               	DF6       	64B2      	UPI_CPU1_CPU0_P1P0_DP<10>
          	               	DF8       	71B4      	GND                 
          	               	DF10      	61B3      	P5E_CPU1_PE2_RX_DP<4>
          	               	DF12      	71B4      	GND                 
          	               	DF14      	61B2      	P5E_CPU1_PE2_TX_DN<5>
          	               	DF16      	71B4      	GND                 
          	               	DF18      	58B2      	M_H_CPU1_SB_DQS_DN<8>
          	               	DF20      	58B3      	M_H_CPU1_SB_DQ<26>  
          	               	DF22      	58B3      	M_H_CPU1_SB_DQ<15>  
          	               	DF24      	58B2      	M_H_CPU1_SB_DQS_DP<6>
          	               	DF26      	58A3      	M_H_CPU1_SB_DQ<10>  
          	               	DF28      	58A3      	M_H_CPU1_SB_DQ<5>   
          	               	DF30      	58B2      	M_H_CPU1_SB_DQS_DP<5>
          	               	DF32      	58A3      	M_H_CPU1_SB_DQ<2>   
          	               	DF34      	58A3      	M_H_CPU1_SB_CB<3>   
          	               	DF36      	58B2      	M_H_CPU1_SB_DQS_DP<4>
          	               	DF38      	58A3      	M_H_CPU1_SB_CB<4>   
          	               	DF40      	58A2      	M_H_CPU1_SB_CA<0>   
          	               	DF42      	58A3      	M_H_CPU1_CLK_DP<0>  
          	               	DF44      	55A2      	M_E_CPU1_SB_RSP<0>  
          	               	DF47      	58B2      	M_H_CPU1_SA_CA<5>   
          	               	DF49      	71B4      	GND                 
          	               	DF51      	58A2      	M_H_CPU1_SA_CS_N<0> 
          	               	DF53      	58B3      	M_H_CPU1_SA_CB<7>   
          	               	DF55      	58B2      	M_H_CPU1_SA_DQS_DP<9>
          	               	DF57      	58B3      	M_H_CPU1_SA_CB<2>   
          	               	DF59      	58B3      	M_H_CPU1_SA_DQ<31>  
          	               	DF61      	58B2      	M_H_CPU1_SA_DQS_DP<8>
          	               	DF63      	58B3      	M_H_CPU1_SA_DQ<26>  
          	               	DF65      	58B3      	M_H_CPU1_SA_DQ<23>  
          	               	DF67      	58B2      	M_H_CPU1_SA_DQS_DP<7>
          	               	DF69      	58B3      	M_H_CPU1_SA_DQ<18>  
          	               	DF71      	58B3      	M_H_CPU1_SA_DQ<15>  
          	               	DF73      	58B2      	M_H_CPU1_SA_DQS_DP<6>
          	               	DF75      	58B3      	M_H_CPU1_SA_DQ<10>  
          	               	DF77      	66B3      	GND                 
          	               	DF79      	71B4      	GND                 
          	               	DF81      	66B3      	GND                 
          	               	DF83      	66B3      	GND                 
          	               	DF85      	61A2      	P5E_CPU1_PE3_TX_DN<9>
          	               	DF87      	71B4      	GND                 
          	               	DF89      	61A3      	P5E_CPU1_PE3_RX_DP<10>
          	               	DF91      	71B4      	GND                 
          	               	DG1       	71B4      	GND                 
          	               	DG3       	64B3      	UPI_CPU0_CPU1_P0P1_DN<10>
          	               	DG5       	71B4      	GND                 
          	               	DG7       	64B2      	UPI_CPU1_CPU0_P1P0_DP<9>
          	               	DG9       	71B4      	GND                 
          	               	DG11      	61B3      	P5E_CPU1_PE2_RX_DP<5>
          	               	DG13      	71B4      	GND                 
          	               	DG15      	61B2      	P5E_CPU1_PE2_TX_DP<5>
          	               	DG17      	58B3      	M_H_CPU1_SB_DQ<28>  
          	               	DG19      	58B3      	M_H_CPU1_SB_DQ<27>  
          	               	DG21      	71B4      	GND                 
          	               	DG23      	58B3      	M_H_CPU1_SB_DQ<14>  
          	               	DG25      	58B3      	M_H_CPU1_SB_DQ<11>  
          	               	DG27      	71B4      	GND                 
          	               	DG29      	58A3      	M_H_CPU1_SB_DQ<6>   
          	               	DG31      	58A3      	M_H_CPU1_SB_DQ<3>   
          	               	DG33      	71B4      	GND                 
          	               	DG35      	58A3      	M_H_CPU1_SB_CB<2>   
          	               	DG37      	58A3      	M_H_CPU1_SB_CB<5>   
          	               	DG39      	71B4      	GND                 
          	               	DG41      	58A2      	M_H_CPU1_SB_CA<1>   
          	               	DG43      	55A2      	M_E_CPU1_SB_RSP<1>  
          	               	DG45      	71B4      	GND                 
          	               	DG48      	58B2      	M_H_CPU1_SA_CA<3>   
          	               	DG50      	58A2      	M_H_CPU1_SA_CS_N<1> 
          	               	DG52      	71B4      	GND                 
          	               	DG54      	58B3      	M_H_CPU1_SA_CB<6>   
          	               	DG56      	58B3      	M_H_CPU1_SA_CB<3>   
          	               	DG58      	71B4      	GND                 
          	               	DG60      	58B3      	M_H_CPU1_SA_DQ<30>  
          	               	DG62      	58B3      	M_H_CPU1_SA_DQ<27>  
          	               	DG64      	71B4      	GND                 
          	               	DG66      	58B3      	M_H_CPU1_SA_DQ<22>  
          	               	DG68      	58B3      	M_H_CPU1_SA_DQ<19>  
          	               	DG70      	71B4      	GND                 
          	               	DG72      	58B3      	M_H_CPU1_SA_DQ<14>  
          	               	DG74      	58B3      	M_H_CPU1_SA_DQ<11>  
          	               	DG76      	71B4      	GND                 
          	               	DG78      	66B3      	GND                 
          	               	DG80      	71A4      	GND                 
          	               	DG82      	66B3      	GND                 
          	               	DG84      	71A4      	GND                 
          	               	DG86      	61A2      	P5E_CPU1_PE3_TX_DP<9>
          	               	DG88      	71A4      	GND                 
          	               	DG90      	61A3      	P5E_CPU1_PE3_RX_DN<10>
          	               	DH2       	64B3      	UPI_CPU0_CPU1_P0P1_DP<10>
          	               	DH4       	71A4      	GND                 
          	               	DH6       	64B2      	UPI_CPU1_CPU0_P1P0_DN<9>
          	               	DH8       	71A4      	GND                 
          	               	DH10      	61B3      	P5E_CPU1_PE2_RX_DN<5>
          	               	DH12      	71A4      	GND                 
          	               	DH14      	61B2      	P5E_CPU1_PE2_TX_DP<6>
          	               	DH16      	71A4      	GND                 
          	               	DH18      	58B2      	M_H_CPU1_SB_DQS_DP<8>
          	               	DH20      	71A4      	GND                 
          	               	DH22      	71A4      	GND                 
          	               	DH24      	58B2      	M_H_CPU1_SB_DQS_DN<6>
          	               	DH26      	71A4      	GND                 
          	               	DH28      	71A4      	GND                 
          	               	DH30      	58B2      	M_H_CPU1_SB_DQS_DN<5>
          	               	DH32      	71A4      	GND                 
          	               	DH34      	71A4      	GND                 
          	               	DH36      	58B2      	M_H_CPU1_SB_DQS_DN<4>
          	               	DH38      	71A4      	GND                 
          	               	DH40      	71A4      	GND                 
          	               	DH42      	58A3      	M_H_CPU1_CLK_DN<0>  
          	               	DH44      	71A4      	GND                 
          	               	DH47      	71A4      	GND                 
          	               	DH49      	58B2      	M_H_CPU1_SA_CA<1>   
          	               	DH51      	71A4      	GND                 
          	               	DH53      	71A4      	GND                 
          	               	DH55      	58B2      	M_H_CPU1_SA_DQS_DN<9>
          	               	DH57      	71A4      	GND                 
          	               	DH59      	71A4      	GND                 
          	               	DH61      	58B2      	M_H_CPU1_SA_DQS_DN<8>
          	               	DH63      	71A4      	GND                 
          	               	DH65      	71B4      	GND                 
          	               	DH67      	58B2      	M_H_CPU1_SA_DQS_DN<7>
          	               	DH69      	71B4      	GND                 
          	               	DH71      	71B4      	GND                 
          	               	DH73      	58B2      	M_H_CPU1_SA_DQS_DN<6>
          	               	DH75      	71B4      	GND                 
          	               	DH77      	71B4      	GND                 
          	               	DH79      	66B3      	GND                 
          	               	DH81      	66B3      	GND                 
          	               	DH83      	66B3      	GND                 
          	               	DH85      	71B4      	GND                 
          	               	DH87      	61A2      	P5E_CPU1_PE3_TX_DN<8>
          	               	DH89      	69B3      	PVCCFA_EHV_FIVRA_CPU1
          	               	DH91      	61A3      	P5E_CPU1_PE3_RX_DN<9>
          	               	DJ1       	64B3      	UPI_CPU0_CPU1_P0P1_DN<9>
          	               	DJ3       	68B1      	PVCCINFAON_CPU1     
          	               	DJ5       	64B2      	UPI_CPU1_CPU0_P1P0_DP<8>
          	               	DJ7       	68B1      	PVCCINFAON_CPU1     
          	               	DJ9       	61B3      	P5E_CPU1_PE2_RX_DN<6>
          	               	DJ11      	68B1      	PVCCINFAON_CPU1     
          	               	DJ13      	61B2      	P5E_CPU1_PE2_TX_DN<6>
          	               	DJ15      	68B1      	PVCCINFAON_CPU1     
          	               	DJ17      	58B3      	M_H_CPU1_SB_DQ<30>  
          	               	DJ19      	71B4      	GND                 
          	               	DJ21      	58B2      	M_H_CPU1_SB_DQS_DP<2>
          	               	DJ23      	71B4      	GND                 
          	               	DJ25      	71B4      	GND                 
          	               	DJ27      	57B2      	M_G_CPU1_SB_DQS_DN<1>
          	               	DJ29      	71B4      	GND                 
          	               	DJ31      	71B4      	GND                 
          	               	DJ33      	57B2      	M_G_CPU1_SB_DQS_DN<0>
          	               	DJ35      	71B4      	GND                 
          	               	DJ37      	71B4      	GND                 
          	               	DJ39      	58B2      	M_H_CPU1_SB_CA<6>   
          	               	DJ41      	71B4      	GND                 
          	               	DJ43      	71B4      	GND                 
          	               	DJ45      	57A3      	M_G_CPU1_CLK_DP<1>  
          	               	DJ48      	71B4      	GND                 
          	               	DJ50      	71B4      	GND                 
          	               	DJ52      	57B2      	M_G_CPU1_SA_CA<0>   
          	               	DJ54      	71B4      	GND                 
          	               	DJ56      	71B4      	GND                 
          	               	DJ58      	57B2      	M_G_CPU1_SA_DQS_DP<4>
          	               	DJ60      	71B4      	GND                 
          	               	DJ62      	71B4      	GND                 
          	               	DJ64      	57B2      	M_G_CPU1_SA_DQS_DP<3>
          	               	DJ66      	71B4      	GND                 
          	               	DJ68      	71B4      	GND                 
          	               	DJ70      	57B2      	M_G_CPU1_SA_DQS_DN<1>
          	               	DJ72      	71B4      	GND                 
          	               	DJ74      	71B4      	GND                 
          	               	DJ76      	58B2      	M_H_CPU1_SA_DQS_DN<0>
          	               	DJ78      	66B3      	GND                 
          	               	DJ80      	71B4      	GND                 
          	               	DJ82      	71B4      	GND                 
          	               	DJ84      	71B4      	GND                 
          	               	DJ86      	61A2      	P5E_CPU1_PE3_TX_DP<8>
          	               	DJ88      	71B4      	GND                 
          	               	DJ90      	61A3      	P5E_CPU1_PE3_RX_DP<9>
          	               	DK2       	64B3      	UPI_CPU0_CPU1_P0P1_DP<9>
          	               	DK4       	71B4      	GND                 
          	               	DK6       	64B2      	UPI_CPU1_CPU0_P1P0_DN<8>
          	               	DK8       	71B4      	GND                 
          	               	DK10      	61B3      	P5E_CPU1_PE2_RX_DP<6>
          	               	DK12      	71B4      	GND                 
          	               	DK14      	61B2      	P5E_CPU1_PE2_TX_DN<7>
          	               	DK16      	71B4      	GND                 
          	               	DK18      	71B4      	GND                 
          	               	DK20      	58B3      	M_H_CPU1_SB_DQ<20>  
          	               	DK22      	58B3      	M_H_CPU1_SB_DQ<17>  
          	               	DK24      	71B4      	GND                 
          	               	DK26      	57B3      	M_G_CPU1_SB_DQ<12>  
          	               	DK28      	57A3      	M_G_CPU1_SB_DQ<9>   
          	               	DK30      	71B4      	GND                 
          	               	DK32      	57A3      	M_G_CPU1_SB_DQ<4>   
          	               	DK34      	57A3      	M_G_CPU1_SB_DQ<1>   
          	               	DK36      	71B4      	GND                 
          	               	DK38      	58A2      	M_H_CPU1_SB_CS_N<2> 
          	               	DK40      	58B2      	M_H_CPU1_SB_CA<4>   
          	               	DK42      	71B4      	GND                 
          	               	DK44      	57B2      	M_G_CPU1_SA_CA<6>   
          	               	DK47      	56A2      	M_F_CPU1_SB_RSP<1>  
          	               	DK49      	71B4      	GND                 
          	               	DK51      	57B2      	M_G_CPU1_SA_CA<2>   
          	               	DK53      	57A2      	M_G_CPU1_SA_CS_N<3> 
          	               	DK55      	71B4      	GND                 
          	               	DK57      	57B3      	M_G_CPU1_SA_CB<4>   
          	               	DK59      	57B3      	M_G_CPU1_SA_CB<1>   
          	               	DK61      	71B4      	GND                 
          	               	DK63      	57B3      	M_G_CPU1_SA_DQ<28>  
          	               	DK65      	57B3      	M_G_CPU1_SA_DQ<25>  
          	               	DK67      	71B4      	GND                 
          	               	DK69      	57B3      	M_G_CPU1_SA_DQ<12>  
          	               	DK71      	57B3      	M_G_CPU1_SA_DQ<9>   
          	               	DK73      	71B4      	GND                 
          	               	DK75      	58B3      	M_H_CPU1_SA_DQ<4>   
          	               	DK77      	71B4      	GND                 
          	               	DK79      	71B4      	GND                 
          	               	DK81      	71B4      	GND                 
          	               	DK83      	71B4      	GND                 
          	               	DK85      	61A2      	P5E_CPU1_PE3_TX_DN<7>
          	               	DK87      	71B4      	GND                 
          	               	DK89      	61A3      	P5E_CPU1_PE3_RX_DP<8>
          	               	DK91      	71B4      	GND                 
          	               	DL1       	71B4      	GND                 
          	               	DL3       	64B3      	UPI_CPU0_CPU1_P0P1_DN<8>
          	               	DL5       	71B4      	GND                 
          	               	DL7       	64B2      	UPI_CPU1_CPU0_P1P0_DN<7>
          	               	DL9       	71B4      	GND                 
          	               	DL11      	61B3      	P5E_CPU1_PE2_RX_DP<7>
          	               	DL13      	71B4      	GND                 
          	               	DL15      	61B2      	P5E_CPU1_PE2_TX_DP<7>
          	               	DL17      	71B4      	GND                 
          	               	DL19      	58B3      	M_H_CPU1_SB_DQ<21>  
          	               	DL21      	58B2      	M_H_CPU1_SB_DQS_DN<2>
          	               	DL23      	58B3      	M_H_CPU1_SB_DQ<16>  
          	               	DL25      	57B3      	M_G_CPU1_SB_DQ<13>  
          	               	DL27      	57B2      	M_G_CPU1_SB_DQS_DP<1>
          	               	DL29      	57A3      	M_G_CPU1_SB_DQ<10>  
          	               	DL31      	57A3      	M_G_CPU1_SB_DQ<5>   
          	               	DL33      	57B2      	M_G_CPU1_SB_DQS_DP<0>
          	               	DL35      	57A3      	M_G_CPU1_SB_DQ<0>   
          	               	DL37      	58A2      	M_H_CPU1_SB_CS_N<0> 
          	               	DL39      	71B4      	GND                 
          	               	DL41      	58B2      	M_H_CPU1_SB_CA<2>   
          	               	DL43      	57B2      	M_G_CPU1_SA_PAR     
          	               	DL45      	57A3      	M_G_CPU1_CLK_DN<1>  
          	               	DL48      	56A2      	M_F_CPU1_SB_RSP<0>  
          	               	DL50      	57B2      	M_G_CPU1_SA_CA<4>   
          	               	DL52      	71B4      	GND                 
          	               	DL54      	57A2      	M_G_CPU1_SA_CS_N<2> 
          	               	DL56      	57B3      	M_G_CPU1_SA_CB<5>   
          	               	DL58      	57B2      	M_G_CPU1_SA_DQS_DN<4>
          	               	DL60      	57B3      	M_G_CPU1_SA_CB<0>   
          	               	DL62      	57B3      	M_G_CPU1_SA_DQ<29>  
          	               	DL64      	57B2      	M_G_CPU1_SA_DQS_DN<3>
          	               	DL66      	57B3      	M_G_CPU1_SA_DQ<24>  
          	               	DL68      	57B3      	M_G_CPU1_SA_DQ<13>  
          	               	DL70      	57B2      	M_G_CPU1_SA_DQS_DP<1>
          	               	DL72      	57B3      	M_G_CPU1_SA_DQ<8>   
          	               	DL74      	58B3      	M_H_CPU1_SA_DQ<5>   
          	               	DL76      	58B2      	M_H_CPU1_SA_DQS_DP<0>
          	               	DL78      	66B3      	GND                 
          	               	DL80      	66B2      	NC                  
          	               	DL82      	66B2      	NC                  
          	               	DL84      	71B4      	GND                 
          	               	DL86      	61A2      	P5E_CPU1_PE3_TX_DP<7>
          	               	DL88      	71B4      	GND                 
          	               	DL90      	61A3      	P5E_CPU1_PE3_RX_DN<8>
          	               	DM2       	64B3      	UPI_CPU0_CPU1_P0P1_DP<8>
          	               	DM4       	70A1      	GND                 
          	               	DM6       	64B2      	UPI_CPU1_CPU0_P1P0_DP<7>
          	               	DM8       	70A1      	GND                 
          	               	DM10      	61B3      	P5E_CPU1_PE2_RX_DN<7>
          	               	DM12      	70A1      	GND                 
          	               	DM14      	61B2      	P5E_CPU1_PE2_TX_DP<8>
          	               	DM16      	70A1      	GND                 
          	               	DM18      	70A1      	GND                 
          	               	DM20      	70A1      	GND                 
          	               	DM22      	70A1      	GND                 
          	               	DM24      	70A1      	GND                 
          	               	DM26      	70A1      	GND                 
          	               	DM28      	70A1      	GND                 
          	               	DM30      	70A1      	GND                 
          	               	DM32      	70A1      	GND                 
          	               	DM34      	70A1      	GND                 
          	               	DM36      	70A1      	GND                 
          	               	DM38      	70A1      	GND                 
          	               	DM40      	70A1      	GND                 
          	               	DM42      	70A1      	GND                 
          	               	DM44      	70A1      	GND                 
          	               	DM47      	70A1      	GND                 
          	               	DM49      	70A1      	GND                 
          	               	DM51      	70A1      	GND                 
          	               	DM53      	70A1      	GND                 
          	               	DM55      	70B1      	GND                 
          	               	DM57      	70B1      	GND                 
          	               	DM59      	70B1      	GND                 
          	               	DM61      	70B1      	GND                 
          	               	DM63      	70B1      	GND                 
          	               	DM65      	70B1      	GND                 
          	               	DM67      	70B1      	GND                 
          	               	DM69      	70B1      	GND                 
          	               	DM71      	70B1      	GND                 
          	               	DM73      	70B1      	GND                 
          	               	DM75      	70B1      	GND                 
          	               	DM77      	70B1      	GND                 
          	               	DM79      	70B1      	GND                 
          	               	DM81      	66B2      	NC                  
          	               	DM83      	69B3      	PVCCFA_EHV_FIVRA_CPU1
          	               	DM85      	69B3      	PVCCFA_EHV_FIVRA_CPU1
          	               	DM87      	61A2      	P5E_CPU1_PE3_TX_DN<6>
          	               	DM89      	69B3      	PVCCFA_EHV_FIVRA_CPU1
          	               	DM91      	61A3      	P5E_CPU1_PE3_RX_DP<7>
          	               	DN1       	64B3      	UPI_CPU0_CPU1_P0P1_DN<7>
          	               	DN3       	69B3      	PVCCFA_EHV_FIVRA_CPU1
          	               	DN5       	64B2      	UPI_CPU1_CPU0_P1P0_DP<6>
          	               	DN7       	69B3      	PVCCFA_EHV_FIVRA_CPU1
          	               	DN9       	61B3      	P5E_CPU1_PE2_RX_DN<8>
          	               	DN11      	69B3      	PVCCFA_EHV_FIVRA_CPU1
          	               	DN13      	61B2      	P5E_CPU1_PE2_TX_DN<8>
          	               	DN15      	69B3      	PVCCFA_EHV_FIVRA_CPU1
          	               	DN17      	70B1      	GND                 
          	               	DN19      	58B3      	M_H_CPU1_SB_DQ<23>  
          	               	DN21      	58B2      	M_H_CPU1_SB_DQS_DP<7>
          	               	DN23      	58B3      	M_H_CPU1_SB_DQ<18>  
          	               	DN25      	57B3      	M_G_CPU1_SB_DQ<15>  
          	               	DN27      	57B2      	M_G_CPU1_SB_DQS_DN<6>
          	               	DN29      	57A3      	M_G_CPU1_SB_DQ<8>   
          	               	DN31      	57A3      	M_G_CPU1_SB_DQ<7>   
          	               	DN33      	57B2      	M_G_CPU1_SB_DQS_DP<5>
          	               	DN35      	57A3      	M_G_CPU1_SB_DQ<2>   
          	               	DN37      	58A2      	M_H_CPU1_SB_CS_N<1> 
          	               	DN39      	70B1      	GND                 
          	               	DN41      	58B2      	M_H_CPU1_SB_CA<3>   
          	               	DN43      	57A2      	M_G_CPU1_SB_CA<0>   
          	               	DN45      	57A3      	M_G_CPU1_CLK_DP<0>  
          	               	DN48      	56A2      	M_F_CPU1_SA_RSP<0>  
          	               	DN50      	57B2      	M_G_CPU1_SA_CA<5>   
          	               	DN52      	70B1      	GND                 
          	               	DN54      	57A2      	M_G_CPU1_SA_CS_N<0> 
          	               	DN56      	57B3      	M_G_CPU1_SA_CB<7>   
          	               	DN58      	57B2      	M_G_CPU1_SA_DQS_DP<9>
          	               	DN60      	57B3      	M_G_CPU1_SA_CB<2>   
          	               	DN62      	57B3      	M_G_CPU1_SA_DQ<31>  
          	               	DN64      	57B2      	M_G_CPU1_SA_DQS_DP<8>
          	               	DN66      	57B3      	M_G_CPU1_SA_DQ<26>  
          	               	DN68      	57B3      	M_G_CPU1_SA_DQ<15>  
          	               	DN70      	57B2      	M_G_CPU1_SA_DQS_DP<6>
          	               	DN72      	57B3      	M_G_CPU1_SA_DQ<10>  
          	               	DN74      	58B3      	M_H_CPU1_SA_DQ<7>   
          	               	DN76      	58B2      	M_H_CPU1_SA_DQS_DP<5>
          	               	DN78      	70B1      	GND                 
          	               	DN80      	66B2      	NC                  
          	               	DN82      	66B2      	NC                  
          	               	DN84      	70B1      	GND                 
          	               	DN86      	61A2      	P5E_CPU1_PE3_TX_DP<6>
          	               	DN88      	70B1      	GND                 
          	               	DN90      	61A3      	P5E_CPU1_PE3_RX_DN<7>
          	               	DP2       	64B3      	UPI_CPU0_CPU1_P0P1_DP<7>
          	               	DP4       	70B1      	GND                 
          	               	DP6       	64B2      	UPI_CPU1_CPU0_P1P0_DN<6>
          	               	DP8       	70B1      	GND                 
          	               	DP10      	61B3      	P5E_CPU1_PE2_RX_DP<8>
          	               	DP12      	70B1      	GND                 
          	               	DP14      	61B2      	P5E_CPU1_PE2_TX_DN<9>
          	               	DP16      	70B1      	GND                 
          	               	DP18      	70B1      	GND                 
          	               	DP20      	58B3      	M_H_CPU1_SB_DQ<22>  
          	               	DP22      	58B3      	M_H_CPU1_SB_DQ<19>  
          	               	DP24      	70B1      	GND                 
          	               	DP26      	57B3      	M_G_CPU1_SB_DQ<14>  
          	               	DP28      	57B3      	M_G_CPU1_SB_DQ<11>  
          	               	DP30      	70B1      	GND                 
          	               	DP32      	57A3      	M_G_CPU1_SB_DQ<6>   
          	               	DP34      	57A3      	M_G_CPU1_SB_DQ<3>   
          	               	DP36      	70B1      	GND                 
          	               	DP38      	58A2      	M_H_CPU1_SB_CS_N<3> 
          	               	DP40      	58B2      	M_H_CPU1_SB_CA<5>   
          	               	DP42      	70B1      	GND                 
          	               	DP44      	57A2      	M_G_CPU1_SB_CA<1>   
          	               	DP47      	56A2      	M_F_CPU1_SA_RSP<1>  
          	               	DP49      	70B1      	GND                 
          	               	DP51      	57B2      	M_G_CPU1_SA_CA<3>   
          	               	DP53      	57A2      	M_G_CPU1_SA_CS_N<1> 
          	               	DP55      	70B1      	GND                 
          	               	DP57      	57B3      	M_G_CPU1_SA_CB<6>   
          	               	DP59      	57B3      	M_G_CPU1_SA_CB<3>   
          	               	DP61      	70B1      	GND                 
          	               	DP63      	57B3      	M_G_CPU1_SA_DQ<30>  
          	               	DP65      	57B3      	M_G_CPU1_SA_DQ<27>  
          	               	DP67      	70B1      	GND                 
          	               	DP69      	57B3      	M_G_CPU1_SA_DQ<14>  
          	               	DP71      	57B3      	M_G_CPU1_SA_DQ<11>  
          	               	DP73      	70B1      	GND                 
          	               	DP75      	58B3      	M_H_CPU1_SA_DQ<6>   
          	               	DP77      	58B3      	M_H_CPU1_SA_DQ<3>   
          	               	DP79      	66B2      	NC                  
          	               	DP81      	70B1      	GND                 
          	               	DP83      	66B2      	NC                  
          	               	DP85      	61A2      	P5E_CPU1_PE3_TX_DN<5>
          	               	DP87      	70B1      	GND                 
          	               	DP89      	61A3      	P5E_CPU1_PE3_RX_DN<6>
          	               	DP91      	70B1      	GND                 
          	               	DR1       	70B1      	GND                 
          	               	DR3       	64B3      	UPI_CPU0_CPU1_P0P1_DP<6>
          	               	DR5       	70B1      	GND                 
          	               	DR7       	64B2      	UPI_CPU1_CPU0_P1P0_DP<5>
          	               	DR9       	70B1      	GND                 
          	               	DR11      	61B3      	P5E_CPU1_PE2_RX_DP<9>
          	               	DR13      	70B1      	GND                 
          	               	DR15      	61B2      	P5E_CPU1_PE2_TX_DP<9>
          	               	DR17      	56B3      	M_F_CPU1_SB_DQ<31>  
          	               	DR19      	70B1      	GND                 
          	               	DR21      	58B2      	M_H_CPU1_SB_DQS_DN<7>
          	               	DR23      	70B1      	GND                 
          	               	DR25      	70B1      	GND                 
          	               	DR27      	57B2      	M_G_CPU1_SB_DQS_DP<6>
          	               	DR29      	70B1      	GND                 
          	               	DR31      	70B1      	GND                 
          	               	DR33      	57B2      	M_G_CPU1_SB_DQS_DN<5>
          	               	DR35      	70B1      	GND                 
          	               	DR37      	70B1      	GND                 
          	               	DR39      	58A2      	M_H_CPU1_SB_PAR     
          	               	DR41      	70B1      	GND                 
          	               	DR43      	70B1      	GND                 
          	               	DR45      	57A3      	M_G_CPU1_CLK_DN<0>  
          	               	DR48      	70B1      	GND                 
          	               	DR50      	70B1      	GND                 
          	               	DR52      	57B2      	M_G_CPU1_SA_CA<1>   
          	               	DR54      	70B1      	GND                 
          	               	DR56      	70B1      	GND                 
          	               	DR58      	57B2      	M_G_CPU1_SA_DQS_DN<9>
          	               	DR60      	70B1      	GND                 
          	               	DR62      	70B1      	GND                 
          	               	DR64      	57B2      	M_G_CPU1_SA_DQS_DN<8>
          	               	DR66      	70B1      	GND                 
          	               	DR68      	70B1      	GND                 
          	               	DR70      	57B2      	M_G_CPU1_SA_DQS_DN<6>
          	               	DR72      	70B1      	GND                 
          	               	DR74      	70A2      	GND                 
          	               	DR76      	58B2      	M_H_CPU1_SA_DQS_DN<5>
          	               	DR78      	70A2      	GND                 
          	               	DR80      	66B2      	NC                  
          	               	DR82      	66B2      	NC                  
          	               	DR84      	70A2      	GND                 
          	               	DR86      	61A2      	P5E_CPU1_PE3_TX_DP<5>
          	               	DR88      	70A2      	GND                 
          	               	DR90      	61A3      	P5E_CPU1_PE3_RX_DP<6>
          	               	DT2       	64B3      	UPI_CPU0_CPU1_P0P1_DN<6>
          	               	DT4       	70A2      	GND                 
          	               	DT6       	64B2      	UPI_CPU1_CPU0_P1P0_DN<5>
          	               	DT8       	70A2      	GND                 
          	               	DT10      	61B3      	P5E_CPU1_PE2_RX_DN<9>
          	               	DT12      	70A2      	GND                 
          	               	DT14      	61B2      	P5E_CPU1_PE2_TX_DP<10>
          	               	DT16      	70A2      	GND                 
          	               	DT18      	56B2      	M_F_CPU1_SB_DQS_DN<3>
          	               	DT20      	70A2      	GND                 
          	               	DT22      	70A2      	GND                 
          	               	DT24      	57B2      	M_G_CPU1_SB_DQS_DP<2>
          	               	DT26      	70A2      	GND                 
          	               	DT28      	70A2      	GND                 
          	               	DT30      	56B2      	M_F_CPU1_SB_DQS_DP<0>
          	               	DT32      	70A2      	GND                 
          	               	DT34      	70A2      	GND                 
          	               	DT36      	57B2      	M_G_CPU1_SB_DQS_DP<9>
          	               	DT38      	70A2      	GND                 
          	               	DT40      	70A2      	GND                 
          	               	DT42      	57B2      	M_G_CPU1_SB_CA<6>   
          	               	DT44      	70A2      	GND                 
          	               	DT47      	70A2      	GND                 
          	               	DT49      	56A3      	M_F_CPU1_CLK_DP<1>  
          	               	DT51      	70A2      	GND                 
          	               	DT53      	70A2      	GND                 
          	               	DT55      	56B2      	M_F_CPU1_SA_DQS_DP<3>
          	               	DT57      	70A2      	GND                 
          	               	DT59      	70A2      	GND                 
          	               	DT61      	57B2      	M_G_CPU1_SA_DQS_DN<2>
          	               	DT63      	70B2      	GND                 
          	               	DT65      	70B2      	GND                 
          	               	DT67      	56B2      	M_F_CPU1_SA_DQS_DN<1>
          	               	DT69      	70B2      	GND                 
          	               	DT71      	70B2      	GND                 
          	               	DT73      	57B2      	M_G_CPU1_SA_DQS_DP<0>
          	               	DT75      	70B2      	GND                 
          	               	DT77      	58B3      	M_H_CPU1_SA_DQ<1>   
          	               	DT79      	69B3      	PVCCFA_EHV_FIVRA_CPU1
          	               	DT81      	66B2      	NC                  
          	               	DT83      	70B2      	GND                 
          	               	DT85      	69B3      	PVCCFA_EHV_FIVRA_CPU1
          	               	DT87      	61A2      	P5E_CPU1_PE3_TX_DN<4>
          	               	DT89      	69B3      	PVCCFA_EHV_FIVRA_CPU1
          	               	DT91      	61A3      	P5E_CPU1_PE3_RX_DP<5>
          	               	DU1       	64B3      	UPI_CPU0_CPU1_P0P1_DN<5>
          	               	DU3       	69B3      	PVCCFA_EHV_FIVRA_CPU1
          	               	DU5       	64B2      	UPI_CPU1_CPU0_P1P0_DP<4>
          	               	DU7       	69B3      	PVCCFA_EHV_FIVRA_CPU1
          	               	DU9       	61B3      	P5E_CPU1_PE2_RX_DN<10>
          	               	DU11      	69B3      	PVCCFA_EHV_FIVRA_CPU1
          	               	DU13      	61B2      	P5E_CPU1_PE2_TX_DN<10>
          	               	DU15      	69B3      	PVCCFA_EHV_FIVRA_CPU1
          	               	DU17      	56B3      	M_F_CPU1_SB_DQ<29>  
          	               	DU19      	56B3      	M_F_CPU1_SB_DQ<25>  
          	               	DU21      	70B2      	GND                 
          	               	DU23      	57B3      	M_G_CPU1_SB_DQ<20>  
          	               	DU25      	57B3      	M_G_CPU1_SB_DQ<17>  
          	               	DU27      	70B2      	GND                 
          	               	DU29      	56A3      	M_F_CPU1_SB_DQ<4>   
          	               	DU31      	56A3      	M_F_CPU1_SB_DQ<1>   
          	               	DU33      	70B2      	GND                 
          	               	DU35      	57A3      	M_G_CPU1_SB_CB<0>   
          	               	DU37      	57A3      	M_G_CPU1_SB_CB<5>   
          	               	DU39      	70B2      	GND                 
          	               	DU41      	57A2      	M_G_CPU1_SB_CS_N<2> 
          	               	DU43      	57B2      	M_G_CPU1_SB_CA<4>   
          	               	DU45      	70B2      	GND                 
          	               	DU48      	57A2      	M_G_CPU1_SB_RSP<0>  
          	               	DU50      	56A2      	M_F_CPU1_SB_CA<1>   
          	               	DU52      	70B2      	GND                 
          	               	DU54      	56B3      	M_F_CPU1_SA_DQ<28>  
          	               	DU56      	56B3      	M_F_CPU1_SA_DQ<25>  
          	               	DU58      	70B2      	GND                 
          	               	DU60      	57B3      	M_G_CPU1_SA_DQ<20>  
          	               	DU62      	57B3      	M_G_CPU1_SA_DQ<17>  
          	               	DU64      	70B2      	GND                 
          	               	DU66      	56B3      	M_F_CPU1_SA_DQ<12>  
          	               	DU68      	56B3      	M_F_CPU1_SA_DQ<9>   
          	               	DU70      	70B2      	GND                 
          	               	DU72      	57B3      	M_G_CPU1_SA_DQ<4>   
          	               	DU74      	57B3      	M_G_CPU1_SA_DQ<1>   
          	               	DU76      	70B2      	GND                 
          	               	DU78      	70B2      	GND                 
          	               	DU80      	66B2      	NC                  
          	               	DU82      	66B2      	NC                  
          	               	DU84      	70B2      	GND                 
          	               	DU86      	61A2      	P5E_CPU1_PE3_TX_DP<4>
          	               	DU88      	70B2      	GND                 
          	               	DU90      	61A3      	P5E_CPU1_PE3_RX_DN<5>
          	               	DV2       	64B3      	UPI_CPU0_CPU1_P0P1_DP<5>
          	               	DV4       	70B2      	GND                 
          	               	DV6       	64B2      	UPI_CPU1_CPU0_P1P0_DN<4>
          	               	DV8       	70B2      	GND                 
          	               	DV10      	61B3      	P5E_CPU1_PE2_RX_DP<10>
          	               	DV12      	70B2      	GND                 
          	               	DV14      	61B2      	P5E_CPU1_PE2_TX_DN<11>
          	               	DV16      	70B2      	GND                 
          	               	DV18      	56B2      	M_F_CPU1_SB_DQS_DP<3>
          	               	DV20      	56B3      	M_F_CPU1_SB_DQ<24>  
          	               	DV22      	57B3      	M_G_CPU1_SB_DQ<21>  
          	               	DV24      	57B2      	M_G_CPU1_SB_DQS_DN<2>
          	               	DV26      	57B3      	M_G_CPU1_SB_DQ<16>  
          	               	DV28      	56A3      	M_F_CPU1_SB_DQ<5>   
          	               	DV30      	56B2      	M_F_CPU1_SB_DQS_DN<0>
          	               	DV32      	56A3      	M_F_CPU1_SB_DQ<0>   
          	               	DV34      	57A3      	M_G_CPU1_SB_CB<1>   
          	               	DV36      	57B2      	M_G_CPU1_SB_DQS_DN<9>
          	               	DV38      	57A3      	M_G_CPU1_SB_CB<4>   
          	               	DV40      	57A2      	M_G_CPU1_SB_CS_N<3> 
          	               	DV42      	70B2      	GND                 
          	               	DV44      	57B2      	M_G_CPU1_SB_CA<2>   
          	               	DV47      	57A2      	M_G_CPU1_SB_RSP<1>  
          	               	DV49      	56A3      	M_F_CPU1_CLK_DN<1>  
          	               	DV51      	56A2      	M_F_CPU1_SB_CA<0>   
          	               	DV53      	56B3      	M_F_CPU1_SA_DQ<29>  
          	               	DV55      	56B2      	M_F_CPU1_SA_DQS_DN<3>
          	               	DV57      	56B3      	M_F_CPU1_SA_DQ<24>  
          	               	DV59      	57B3      	M_G_CPU1_SA_DQ<21>  
          	               	DV61      	57B2      	M_G_CPU1_SA_DQS_DP<2>
          	               	DV63      	57B3      	M_G_CPU1_SA_DQ<16>  
          	               	DV65      	56B3      	M_F_CPU1_SA_DQ<13>  
          	               	DV67      	56B2      	M_F_CPU1_SA_DQS_DP<1>
          	               	DV69      	56B3      	M_F_CPU1_SA_DQ<8>   
          	               	DV71      	57B3      	M_G_CPU1_SA_DQ<5>   
          	               	DV73      	57B2      	M_G_CPU1_SA_DQS_DN<0>
          	               	DV75      	57B3      	M_G_CPU1_SA_DQ<0>   
          	               	DV77      	70B2      	GND                 
          	               	DV79      	70B2      	GND                 
          	               	DV81      	70B2      	GND                 
          	               	DV83      	70B2      	GND                 
          	               	DV85      	61A2      	P5E_CPU1_PE3_TX_DN<3>
          	               	DV87      	70B2      	GND                 
          	               	DV89      	61A3      	P5E_CPU1_PE3_RX_DN<4>
          	               	DV91      	70B2      	GND                 
          	               	DW1       	70B2      	GND                 
          	               	DW3       	64B3      	UPI_CPU0_CPU1_P0P1_DP<4>
          	               	DW5       	70B2      	GND                 
          	               	DW7       	64B2      	UPI_CPU1_CPU0_P1P0_DP<3>
          	               	DW9       	70B2      	GND                 
          	               	DW11      	61B3      	P5E_CPU1_PE2_RX_DP<11>
          	               	DW13      	70B2      	GND                 
          	               	DW15      	61B2      	P5E_CPU1_PE2_TX_DP<11>
          	               	DW17      	70B2      	GND                 
          	               	DW19      	70B2      	GND                 
          	               	DW21      	70B2      	GND                 
          	               	DW23      	70B2      	GND                 
          	               	DW25      	70B2      	GND                 
          	               	DW27      	70B2      	GND                 
          	               	DW29      	70B2      	GND                 
          	               	DW31      	70B2      	GND                 
          	               	DW33      	70B2      	GND                 
          	               	DW35      	70B2      	GND                 
          	               	DW37      	70B2      	GND                 
          	               	DW39      	70B2      	GND                 
          	               	DW41      	70B2      	GND                 
          	               	DW43      	70B2      	GND                 
          	               	DW45      	70B2      	GND                 
          	               	DW48      	70B2      	GND                 
          	               	DW50      	70B2      	GND                 
          	               	DW52      	70B2      	GND                 
          	               	DW54      	70B2      	GND                 
          	               	DW56      	70B2      	GND                 
          	               	DW58      	70B2      	GND                 
          	               	DW60      	70B2      	GND                 
          	               	DW62      	70B2      	GND                 
          	               	DW64      	70B2      	GND                 
          	               	DW66      	70A2      	GND                 
          	               	DW68      	70A2      	GND                 
          	               	DW70      	70A2      	GND                 
          	               	DW72      	70A2      	GND                 
          	               	DW74      	70A2      	GND                 
          	               	DW76      	70A2      	GND                 
          	               	DW78      	58B3      	M_H_CPU1_SA_DQ<2>   
          	               	DW80      	70A2      	GND                 
          	               	DW82      	70A2      	GND                 
          	               	DW84      	70A2      	GND                 
          	               	DW86      	61A2      	P5E_CPU1_PE3_TX_DP<3>
          	               	DW88      	70A2      	GND                 
          	               	DW90      	61A3      	P5E_CPU1_PE3_RX_DP<4>
          	               	DY2       	64B3      	UPI_CPU0_CPU1_P0P1_DN<4>
          	               	DY4       	70A2      	GND                 
          	               	DY6       	64B2      	UPI_CPU1_CPU0_P1P0_DN<3>
          	               	DY8       	70A2      	GND                 
          	               	DY10      	61B3      	P5E_CPU1_PE2_RX_DN<11>
          	               	DY12      	70A2      	GND                 
          	               	DY14      	61B2      	P5E_CPU1_PE2_TX_DP<12>
          	               	DY16      	70A2      	GND                 
          	               	DY18      	56B2      	M_F_CPU1_SB_DQS_DN<8>
          	               	DY20      	56B3      	M_F_CPU1_SB_DQ<26>  
          	               	DY22      	57B3      	M_G_CPU1_SB_DQ<23>  
          	               	DY24      	57B2      	M_G_CPU1_SB_DQS_DP<7>
          	               	DY26      	57B3      	M_G_CPU1_SB_DQ<18>  
          	               	DY28      	56A3      	M_F_CPU1_SB_DQ<7>   
          	               	DY30      	56B2      	M_F_CPU1_SB_DQS_DP<5>
          	               	DY32      	56A3      	M_F_CPU1_SB_DQ<2>   
          	               	DY34      	57A3      	M_G_CPU1_SB_CB<3>   
          	               	DY36      	57B2      	M_G_CPU1_SB_DQS_DP<4>
          	               	DY38      	57A3      	M_G_CPU1_SB_CB<6>   
          	               	DY40      	57A2      	M_G_CPU1_SB_CS_N<1> 
          	               	DY42      	70A2      	GND                 
          	               	DY44      	57B2      	M_G_CPU1_SB_CA<3>   
          	               	DY47      	57A2      	M_G_CPU1_SA_RSP<1>  
          	               	DY49      	56A3      	M_F_CPU1_CLK_DN<0>  
          	               	DY51      	56B2      	M_F_CPU1_SA_CA<6>   
          	               	DY53      	56B3      	M_F_CPU1_SA_DQ<31>  
          	               	DY55      	56B2      	M_F_CPU1_SA_DQS_DP<8>
          	               	DY57      	56B3      	M_F_CPU1_SA_DQ<26>  
          	               	DY59      	57B3      	M_G_CPU1_SA_DQ<23>  
          	               	DY61      	57B2      	M_G_CPU1_SA_DQS_DP<7>
          	               	DY63      	57B3      	M_G_CPU1_SA_DQ<18>  
          	               	DY65      	56B3      	M_F_CPU1_SA_DQ<15>  
          	               	DY67      	56B2      	M_F_CPU1_SA_DQS_DP<6>
          	               	DY69      	56B3      	M_F_CPU1_SA_DQ<10>  
          	               	DY71      	57B3      	M_G_CPU1_SA_DQ<7>   
          	               	DY73      	57B2      	M_G_CPU1_SA_DQS_DP<5>
          	               	DY75      	57B3      	M_G_CPU1_SA_DQ<2>   
          	               	DY77      	70A2      	GND                 
          	               	DY79      	58B3      	M_H_CPU1_SA_DQ<0>   
          	               	DY81      	66B3      	GND                 
          	               	DY83      	66B3      	GND                 
          	               	DY85      	69B3      	PVCCFA_EHV_FIVRA_CPU1
          	               	DY87      	61A2      	P5E_CPU1_PE3_TX_DN<2>
          	               	DY89      	69B3      	PVCCFA_EHV_FIVRA_CPU1
          	               	DY91      	61A3      	P5E_CPU1_PE3_RX_DN<3>
          	               	E5        	73B2      	GND                 
          	               	E7        	51B3      	M_A_CPU1_SB_DQ<31>  
          	               	E9        	51B2      	M_A_CPU1_SB_DQS_DP<8>
          	               	E11       	51B3      	M_A_CPU1_SB_DQ<26>  
          	               	E13       	52B3      	M_B_CPU1_SB_DQ<29>  
          	               	E15       	52B2      	M_B_CPU1_SB_DQS_DN<8>
          	               	E17       	52B3      	M_B_CPU1_SB_DQ<26>  
          	               	E19       	51B3      	M_A_CPU1_SB_DQ<23>  
          	               	E21       	51B2      	M_A_CPU1_SB_DQS_DP<7>
          	               	E23       	51B3      	M_A_CPU1_SB_DQ<18>  
          	               	E25       	51B3      	M_A_CPU1_SB_DQ<15>  
          	               	E27       	51B2      	M_A_CPU1_SB_DQS_DP<6>
          	               	E29       	51A3      	M_A_CPU1_SB_DQ<10>  
          	               	E31       	51A3      	M_A_CPU1_SB_CB<3>   
          	               	E33       	51B2      	M_A_CPU1_SB_DQS_DP<4>
          	               	E35       	51A3      	M_A_CPU1_SB_CB<6>   
          	               	E37       	51A2      	M_A_CPU1_SB_CS_N<3> 
          	               	E39       	73B2      	GND                 
          	               	E41       	51B2      	M_A_CPU1_SB_CA<3>   
          	               	E43       	51A2      	M_A_CPU1_SB_CA<0>   
          	               	E45       	51A3      	M_A_CPU1_CLK_DP<1>  
          	               	E48       	51B2      	M_A_CPU1_SA_PAR     
          	               	E50       	51B2      	M_A_CPU1_SA_CA<5>   
          	               	E52       	73A2      	GND                 
          	               	E54       	51A2      	M_A_CPU1_SA_CS_N<2> 
          	               	E56       	51B3      	M_A_CPU1_SA_CB<7>   
          	               	E58       	51B2      	M_A_CPU1_SA_DQS_DP<9>
          	               	E60       	51B3      	M_A_CPU1_SA_CB<2>   
          	               	E62       	51B3      	M_A_CPU1_SA_DQ<31>  
          	               	E64       	51B2      	M_A_CPU1_SA_DQS_DP<8>
          	               	E66       	51B3      	M_A_CPU1_SA_DQ<26>  
          	               	E68       	51B3      	M_A_CPU1_SA_DQ<23>  
          	               	E70       	51B2      	M_A_CPU1_SA_DQS_DP<7>
          	               	E72       	51B3      	M_A_CPU1_SA_DQ<17>  
          	               	E74       	73A2      	GND                 
          	               	E76       	73A2      	GND                 
          	               	E78       	73A2      	GND                 
          	               	E80       	65B3      	UPI_CPU0_CPU1_P2P2_DN<0>
          	               	E82       	65B3      	UPI_CPU0_CPU1_P2P2_DP<1>
          	               	E84       	65B2      	UPI_CPU1_CPU0_P2P2_DN<1>
          	               	E86       	73A2      	GND                 
          	               	E88       	65B2      	UPI_CPU1_CPU0_P2P2_DP<2>
          	               	EA1       	64B3      	UPI_CPU0_CPU1_P0P1_DN<3>
          	               	EA3       	69B3      	PVCCFA_EHV_FIVRA_CPU1
          	               	EA5       	64B2      	UPI_CPU1_CPU0_P1P0_DP<2>
          	               	EA7       	69B3      	PVCCFA_EHV_FIVRA_CPU1
          	               	EA9       	61B3      	P5E_CPU1_PE2_RX_DN<12>
          	               	EA11      	69B3      	PVCCFA_EHV_FIVRA_CPU1
          	               	EA13      	61B2      	P5E_CPU1_PE2_TX_DN<12>
          	               	EA15      	69B3      	PVCCFA_EHV_FIVRA_CPU1
          	               	EA17      	56B3      	M_F_CPU1_SB_DQ<28>  
          	               	EA19      	56B3      	M_F_CPU1_SB_DQ<27>  
          	               	EA21      	70A2      	GND                 
          	               	EA23      	57B3      	M_G_CPU1_SB_DQ<22>  
          	               	EA25      	57B3      	M_G_CPU1_SB_DQ<19>  
          	               	EA27      	70A2      	GND                 
          	               	EA29      	56A3      	M_F_CPU1_SB_DQ<6>   
          	               	EA31      	56A3      	M_F_CPU1_SB_DQ<3>   
          	               	EA33      	70A2      	GND                 
          	               	EA35      	57A3      	M_G_CPU1_SB_CB<2>   
          	               	EA37      	57A3      	M_G_CPU1_SB_CB<7>   
          	               	EA39      	70A2      	GND                 
          	               	EA41      	57A2      	M_G_CPU1_SB_CS_N<0> 
          	               	EA43      	57B2      	M_G_CPU1_SB_CA<5>   
          	               	EA45      	70A2      	GND                 
          	               	EA48      	57A2      	M_G_CPU1_SA_RSP<0>  
          	               	EA50      	56B2      	M_F_CPU1_SA_PAR     
          	               	EA52      	70A2      	GND                 
          	               	EA54      	56B3      	M_F_CPU1_SA_DQ<30>  
          	               	EA56      	56B3      	M_F_CPU1_SA_DQ<27>  
          	               	EA58      	70B2      	GND                 
          	               	EA60      	57B3      	M_G_CPU1_SA_DQ<22>  
          	               	EA62      	57B3      	M_G_CPU1_SA_DQ<19>  
          	               	EA64      	70B2      	GND                 
          	               	EA66      	56B3      	M_F_CPU1_SA_DQ<14>  
          	               	EA68      	56B3      	M_F_CPU1_SA_DQ<11>  
          	               	EA70      	70B2      	GND                 
          	               	EA72      	57B3      	M_G_CPU1_SA_DQ<6>   
          	               	EA74      	57B3      	M_G_CPU1_SA_DQ<3>   
          	               	EA76      	70B2      	GND                 
          	               	EA78      	70B2      	GND                 
          	               	EA80      	70B2      	GND                 
          	               	EA82      	66B3      	GND                 
          	               	EA84      	70B2      	GND                 
          	               	EA86      	61A2      	P5E_CPU1_PE3_TX_DP<2>
          	               	EA88      	70B2      	GND                 
          	               	EA90      	61A3      	P5E_CPU1_PE3_RX_DP<3>
          	               	EB2       	64B3      	UPI_CPU0_CPU1_P0P1_DP<3>
          	               	EB4       	70B2      	GND                 
          	               	EB6       	64B2      	UPI_CPU1_CPU0_P1P0_DN<2>
          	               	EB8       	70B2      	GND                 
          	               	EB10      	61B3      	P5E_CPU1_PE2_RX_DP<12>
          	               	EB12      	70B2      	GND                 
          	               	EB14      	61B2      	P5E_CPU1_PE2_TX_DN<13>
          	               	EB16      	70B2      	GND                 
          	               	EB18      	56B2      	M_F_CPU1_SB_DQS_DP<8>
          	               	EB20      	70B2      	GND                 
          	               	EB22      	70B2      	GND                 
          	               	EB24      	57B2      	M_G_CPU1_SB_DQS_DN<7>
          	               	EB26      	70B2      	GND                 
          	               	EB28      	70B2      	GND                 
          	               	EB30      	56B2      	M_F_CPU1_SB_DQS_DN<5>
          	               	EB32      	70B2      	GND                 
          	               	EB34      	70B2      	GND                 
          	               	EB36      	57B2      	M_G_CPU1_SB_DQS_DN<4>
          	               	EB38      	70B2      	GND                 
          	               	EB40      	70B2      	GND                 
          	               	EB42      	57A2      	M_G_CPU1_SB_PAR     
          	               	EB44      	70B2      	GND                 
          	               	EB47      	70B2      	GND                 
          	               	EB49      	56A3      	M_F_CPU1_CLK_DP<0>  
          	               	EB51      	70B2      	GND                 
          	               	EB53      	70B2      	GND                 
          	               	EB55      	56B2      	M_F_CPU1_SA_DQS_DN<8>
          	               	EB57      	70B2      	GND                 
          	               	EB59      	70B2      	GND                 
          	               	EB61      	57B2      	M_G_CPU1_SA_DQS_DN<7>
          	               	EB63      	70B2      	GND                 
          	               	EB65      	70B2      	GND                 
          	               	EB67      	56B2      	M_F_CPU1_SA_DQS_DN<6>
          	               	EB69      	70B2      	GND                 
          	               	EB71      	70B2      	GND                 
          	               	EB73      	57B2      	M_G_CPU1_SA_DQS_DN<5>
          	               	EB75      	70B2      	GND                 
          	               	EB77      	56B3      	M_F_CPU1_SA_DQ<0>   
          	               	EB79      	70B2      	GND                 
          	               	EB81      	66B3      	GND                 
          	               	EB83      	70B2      	GND                 
          	               	EB85      	61A2      	P5E_CPU1_PE3_TX_DN<1>
          	               	EB87      	70B2      	GND                 
          	               	EB89      	61A3      	P5E_CPU1_PE3_RX_DP<2>
          	               	EB91      	70B2      	GND                 
          	               	EC1       	70B2      	GND                 
          	               	EC3       	64B3      	UPI_CPU0_CPU1_P0P1_DP<2>
          	               	EC5       	70B2      	GND                 
          	               	EC7       	64B2      	UPI_CPU1_CPU0_P1P0_DN<1>
          	               	EC9       	70B2      	GND                 
          	               	EC11      	61B3      	P5E_CPU1_PE2_RX_DP<13>
          	               	EC13      	70B2      	GND                 
          	               	EC15      	61B2      	P5E_CPU1_PE2_TX_DP<13>
          	               	EC17      	56B3      	M_F_CPU1_SB_DQ<30>  
          	               	EC19      	70B2      	GND                 
          	               	EC21      	56B2      	M_F_CPU1_SB_DQS_DP<1>
          	               	EC23      	70B2      	GND                 
          	               	EC25      	70B2      	GND                 
          	               	EC27      	55B2      	M_E_CPU1_SB_DQS_DP<0>
          	               	EC29      	70B2      	GND                 
          	               	EC31      	70B2      	GND                 
          	               	EC33      	56B2      	M_F_CPU1_SB_DQS_DP<9>
          	               	EC35      	70B2      	GND                 
          	               	EC37      	70B2      	GND                 
          	               	EC39      	56B2      	M_F_CPU1_SB_CA<6>   
          	               	EC41      	70B2      	GND                 
          	               	EC43      	70B2      	GND                 
          	               	EC45      	55A3      	M_E_CPU1_CLK_DP<1>  
          	               	EC48      	70B2      	GND                 
          	               	EC50      	70B2      	GND                 
          	               	EC52      	56B2      	M_F_CPU1_SA_CA<0>   
          	               	EC54      	70B2      	GND                 
          	               	EC56      	70B2      	GND                 
          	               	EC58      	56B2      	M_F_CPU1_SA_DQS_DP<4>
          	               	EC60      	70B2      	GND                 
          	               	EC62      	70B2      	GND                 
          	               	EC64      	56B2      	M_F_CPU1_SA_DQS_DN<2>
          	               	EC66      	70B2      	GND                 
          	               	EC68      	70B2      	GND                 
          	               	EC70      	55B2      	M_E_CPU1_SA_DQS_DN<1>
          	               	EC72      	70B2      	GND                 
          	               	EC74      	70B2      	GND                 
          	               	EC76      	56B2      	M_F_CPU1_SA_DQS_DP<0>
          	               	EC78      	69B3      	PVCCFA_EHV_FIVRA_CPU1
          	               	EC80      	66B3      	GND                 
          	               	EC82      	70A3      	GND                 
          	               	EC84      	70A3      	GND                 
          	               	EC86      	61A2      	P5E_CPU1_PE3_TX_DP<1>
          	               	EC88      	70A3      	GND                 
          	               	EC90      	61A3      	P5E_CPU1_PE3_RX_DN<2>
          	               	ED2       	64B3      	UPI_CPU0_CPU1_P0P1_DN<2>
          	               	ED4       	70A3      	GND                 
          	               	ED6       	64B2      	UPI_CPU1_CPU0_P1P0_DP<1>
          	               	ED8       	70A3      	GND                 
          	               	ED10      	61B3      	P5E_CPU1_PE2_RX_DN<13>
          	               	ED12      	70A3      	GND                 
          	               	ED14      	61B2      	P5E_CPU1_PE2_TX_DP<14>
          	               	ED16      	70A3      	GND                 
          	               	ED18      	70A3      	GND                 
          	               	ED20      	56B3      	M_F_CPU1_SB_DQ<12>  
          	               	ED22      	56A3      	M_F_CPU1_SB_DQ<9>   
          	               	ED24      	70A3      	GND                 
          	               	ED26      	55A3      	M_E_CPU1_SB_DQ<4>   
          	               	ED28      	55A3      	M_E_CPU1_SB_DQ<1>   
          	               	ED30      	70A3      	GND                 
          	               	ED32      	56A3      	M_F_CPU1_SB_CB<0>   
          	               	ED34      	56A3      	M_F_CPU1_SB_CB<5>   
          	               	ED36      	70A3      	GND                 
          	               	ED38      	56A2      	M_F_CPU1_SB_CS_N<2> 
          	               	ED40      	56B2      	M_F_CPU1_SB_CA<4>   
          	               	ED42      	70A3      	GND                 
          	               	ED44      	55B2      	M_E_CPU1_SA_CA<6>   
          	               	ED47      	58A2      	M_H_CPU1_SB_RSP<1>  
          	               	ED49      	70A3      	GND                 
          	               	ED51      	56B2      	M_F_CPU1_SA_CA<2>   
          	               	ED53      	56A2      	M_F_CPU1_SA_CS_N<3> 
          	               	ED55      	70A3      	GND                 
          	               	ED57      	56B3      	M_F_CPU1_SA_CB<4>   
          	               	ED59      	56B3      	M_F_CPU1_SA_CB<1>   
          	               	ED61      	70A3      	GND                 
          	               	ED63      	56B3      	M_F_CPU1_SA_DQ<20>  
          	               	ED65      	56B3      	M_F_CPU1_SA_DQ<17>  
          	               	ED67      	70A3      	GND                 
          	               	ED69      	55B3      	M_E_CPU1_SA_DQ<12>  
          	               	ED71      	55B3      	M_E_CPU1_SA_DQ<9>   
          	               	ED73      	70A3      	GND                 
          	               	ED75      	56B3      	M_F_CPU1_SA_DQ<4>   
          	               	ED77      	56B3      	M_F_CPU1_SA_DQ<2>   
          	               	ED79      	69B3      	PVCCFA_EHV_FIVRA_CPU1
          	               	ED81      	66B3      	GND                 
          	               	ED83      	66B3      	GND                 
          	               	ED85      	69B3      	PVCCFA_EHV_FIVRA_CPU1
          	               	ED87      	61A2      	P5E_CPU1_PE3_TX_DP<0>
          	               	ED89      	69B3      	PVCCFA_EHV_FIVRA_CPU1
          	               	ED91      	61A3      	P5E_CPU1_PE3_RX_DN<1>
          	               	EE3       	64B3      	UPI_CPU0_CPU1_P0P1_DN<1>
          	               	EE5       	64B2      	UPI_CPU1_CPU0_P1P0_DP<0>
          	               	EE7       	69B3      	PVCCFA_EHV_FIVRA_CPU1
          	               	EE9       	61B3      	P5E_CPU1_PE2_RX_DN<14>
          	               	EE11      	69B3      	PVCCFA_EHV_FIVRA_CPU1
          	               	EE13      	61B2      	P5E_CPU1_PE2_TX_DN<14>
          	               	EE15      	69B3      	PVCCFA_EHV_FIVRA_CPU1
          	               	EE17      	70A3      	GND                 
          	               	EE19      	56B3      	M_F_CPU1_SB_DQ<13>  
          	               	EE21      	56B2      	M_F_CPU1_SB_DQS_DN<1>
          	               	EE23      	56A3      	M_F_CPU1_SB_DQ<8>   
          	               	EE25      	55A3      	M_E_CPU1_SB_DQ<5>   
          	               	EE27      	55B2      	M_E_CPU1_SB_DQS_DN<0>
          	               	EE29      	55A3      	M_E_CPU1_SB_DQ<0>   
          	               	EE31      	56A3      	M_F_CPU1_SB_CB<1>   
          	               	EE33      	56B2      	M_F_CPU1_SB_DQS_DN<9>
          	               	EE35      	56A3      	M_F_CPU1_SB_CB<4>   
          	               	EE37      	56A2      	M_F_CPU1_SB_CS_N<3> 
          	               	EE39      	70A3      	GND                 
          	               	EE41      	56B2      	M_F_CPU1_SB_CA<2>   
          	               	EE43      	55B2      	M_E_CPU1_SA_PAR     
          	               	EE45      	55A3      	M_E_CPU1_CLK_DN<1>  
          	               	EE48      	58A2      	M_H_CPU1_SB_RSP<0>  
          	               	EE50      	56B2      	M_F_CPU1_SA_CA<4>   
          	               	EE52      	70A3      	GND                 
          	               	EE54      	56A2      	M_F_CPU1_SA_CS_N<2> 
          	               	EE56      	56B3      	M_F_CPU1_SA_CB<5>   
          	               	EE58      	56B2      	M_F_CPU1_SA_DQS_DN<4>
          	               	EE60      	56B3      	M_F_CPU1_SA_CB<0>   
          	               	EE62      	56B3      	M_F_CPU1_SA_DQ<21>  
          	               	EE64      	56B2      	M_F_CPU1_SA_DQS_DP<2>
          	               	EE66      	56B3      	M_F_CPU1_SA_DQ<16>  
          	               	EE68      	55B3      	M_E_CPU1_SA_DQ<13>  
          	               	EE70      	55B2      	M_E_CPU1_SA_DQS_DP<1>
          	               	EE72      	55B3      	M_E_CPU1_SA_DQ<8>   
          	               	EE74      	56B3      	M_F_CPU1_SA_DQ<5>   
          	               	EE76      	56B2      	M_F_CPU1_SA_DQS_DN<0>
          	               	EE78      	70A3      	GND                 
          	               	EE80      	70A3      	GND                 
          	               	EE82      	66B3      	GND                 
          	               	EE84      	69B3      	PVCCFA_EHV_FIVRA_CPU1
          	               	EE86      	61A2      	P5E_CPU1_PE3_TX_DN<0>
          	               	EE88      	70B3      	GND                 
          	               	EE90      	61A3      	P5E_CPU1_PE3_RX_DP<1>
          	               	EF2       	70B3      	GND                 
          	               	EF4       	70B3      	GND                 
          	               	EF6       	64B2      	UPI_CPU1_CPU0_P1P0_DN<0>
          	               	EF8       	70B3      	GND                 
          	               	EF10      	61B3      	P5E_CPU1_PE2_RX_DP<14>
          	               	EF12      	70B3      	GND                 
          	               	EF14      	61B2      	P5E_CPU1_PE2_TX_DN<15>
          	               	EF16      	70B3      	GND                 
          	               	EF18      	70B3      	GND                 
          	               	EF20      	70B3      	GND                 
          	               	EF22      	70B3      	GND                 
          	               	EF24      	70B3      	GND                 
          	               	EF26      	70B3      	GND                 
          	               	EF28      	70B3      	GND                 
          	               	EF30      	70B3      	GND                 
          	               	EF32      	70B3      	GND                 
          	               	EF34      	70B3      	GND                 
          	               	EF36      	70B3      	GND                 
          	               	EF38      	70B3      	GND                 
          	               	EF40      	70B3      	GND                 
          	               	EF42      	70B3      	GND                 
          	               	EF44      	70B3      	GND                 
          	               	EF47      	70B3      	GND                 
          	               	EF49      	70B3      	GND                 
          	               	EF51      	70B3      	GND                 
          	               	EF53      	70B3      	GND                 
          	               	EF55      	70B3      	GND                 
          	               	EF57      	70B3      	GND                 
          	               	EF59      	70B3      	GND                 
          	               	EF61      	70B3      	GND                 
          	               	EF63      	70B3      	GND                 
          	               	EF65      	70B3      	GND                 
          	               	EF67      	70B3      	GND                 
          	               	EF69      	70B3      	GND                 
          	               	EF71      	70B3      	GND                 
          	               	EF73      	70B3      	GND                 
          	               	EF75      	70B3      	GND                 
          	               	EF77      	70B3      	GND                 
          	               	EF79      	69B3      	PVCCFA_EHV_FIVRA_CPU1
          	               	EF81      	66B3      	GND                 
          	               	EF83      	66B3      	GND                 
          	               	EF85      	70B3      	GND                 
          	               	EF87      	70B3      	GND                 
          	               	EF89      	70B3      	GND                 
          	               	EG3       	64B3      	UPI_CPU0_CPU1_P0P1_DP<1>
          	               	EG5       	70B3      	GND                 
          	               	EG7       	70B3      	GND                 
          	               	EG9       	70B3      	GND                 
          	               	EG11      	61B3      	P5E_CPU1_PE2_RX_DP<15>
          	               	EG13      	70B3      	GND                 
          	               	EG15      	61B2      	P5E_CPU1_PE2_TX_DP<15>
          	               	EG17      	48B3      	NC_CPU1_HBM0_VIEWDIG1
          	               	EG19      	56B3      	M_F_CPU1_SB_DQ<15>  
          	               	EG21      	56B2      	M_F_CPU1_SB_DQS_DP<6>
          	               	EG23      	56A3      	M_F_CPU1_SB_DQ<10>  
          	               	EG25      	55A3      	M_E_CPU1_SB_DQ<7>   
          	               	EG27      	55B2      	M_E_CPU1_SB_DQS_DP<5>
          	               	EG29      	55A3      	M_E_CPU1_SB_DQ<2>   
          	               	EG31      	56A3      	M_F_CPU1_SB_CB<3>   
          	               	EG33      	56B2      	M_F_CPU1_SB_DQS_DP<4>
          	               	EG35      	56A3      	M_F_CPU1_SB_CB<6>   
          	               	EG37      	56A2      	M_F_CPU1_SB_CS_N<1> 
          	               	EG39      	70B3      	GND                 
          	               	EG41      	56B2      	M_F_CPU1_SB_CA<3>   
          	               	EG43      	55A2      	M_E_CPU1_SB_CA<0>   
          	               	EG45      	55A3      	M_E_CPU1_CLK_DP<0>  
          	               	EG48      	58A2      	M_H_CPU1_SA_RSP<0>  
          	               	EG50      	56B2      	M_F_CPU1_SA_CA<5>   
          	               	EG52      	70B3      	GND                 
          	               	EG54      	56A2      	M_F_CPU1_SA_CS_N<0> 
          	               	EG56      	56B3      	M_F_CPU1_SA_CB<7>   
          	               	EG58      	56B2      	M_F_CPU1_SA_DQS_DP<9>
          	               	EG60      	56B3      	M_F_CPU1_SA_CB<2>   
          	               	EG62      	56B3      	M_F_CPU1_SA_DQ<23>  
          	               	EG64      	56B2      	M_F_CPU1_SA_DQS_DP<7>
          	               	EG66      	56B3      	M_F_CPU1_SA_DQ<18>  
          	               	EG68      	55B3      	M_E_CPU1_SA_DQ<15>  
          	               	EG70      	55B2      	M_E_CPU1_SA_DQS_DP<6>
          	               	EG72      	55B3      	M_E_CPU1_SA_DQ<10>  
          	               	EG74      	56B3      	M_F_CPU1_SA_DQ<7>   
          	               	EG76      	56B2      	M_F_CPU1_SA_DQS_DP<5>
          	               	EG78      	56B3      	M_F_CPU1_SA_DQ<3>   
          	               	EG80      	69B3      	PVCCFA_EHV_FIVRA_CPU1
          	               	EG82      	70B3      	GND                 
          	               	EG84      	70B3      	GND                 
          	               	EG86      	70B3      	GND                 
          	               	EG88      	70B3      	GND                 
          	               	EG90      	70B3      	GND                 
          	               	EH2       	64B3      	UPI_CPU0_CPU1_P0P1_DN<0>
          	               	EH4       	70B3      	GND                 
          	               	EH6       	70B3      	GND                 
          	               	EH8       	57B3      	M_G_CPU1_SB_DQ<25>  
          	               	EH10      	61B3      	P5E_CPU1_PE2_RX_DN<15>
          	               	EH12      	70B3      	GND                 
          	               	EH14      	70B3      	GND                 
          	               	EH16      	70B3      	GND                 
          	               	EH18      	70B3      	GND                 
          	               	EH20      	56B3      	M_F_CPU1_SB_DQ<14>  
          	               	EH22      	56B3      	M_F_CPU1_SB_DQ<11>  
          	               	EH24      	70B3      	GND                 
          	               	EH26      	55A3      	M_E_CPU1_SB_DQ<6>   
          	               	EH28      	55A3      	M_E_CPU1_SB_DQ<3>   
          	               	EH30      	70B3      	GND                 
          	               	EH32      	56A3      	M_F_CPU1_SB_CB<2>   
          	               	EH34      	56A3      	M_F_CPU1_SB_CB<7>   
          	               	EH36      	70A4      	GND                 
          	               	EH38      	56A2      	M_F_CPU1_SB_CS_N<0> 
          	               	EH40      	56B2      	M_F_CPU1_SB_CA<5>   
          	               	EH42      	70A4      	GND                 
          	               	EH44      	55A2      	M_E_CPU1_SB_CA<1>   
          	               	EH47      	58A2      	M_H_CPU1_SA_RSP<1>  
          	               	EH49      	70A4      	GND                 
          	               	EH51      	56B2      	M_F_CPU1_SA_CA<3>   
          	               	EH53      	56A2      	M_F_CPU1_SA_CS_N<1> 
          	               	EH55      	70A4      	GND                 
          	               	EH57      	56B3      	M_F_CPU1_SA_CB<6>   
          	               	EH59      	56B3      	M_F_CPU1_SA_CB<3>   
          	               	EH61      	70A4      	GND                 
          	               	EH63      	56B3      	M_F_CPU1_SA_DQ<22>  
          	               	EH65      	56B3      	M_F_CPU1_SA_DQ<19>  
          	               	EH67      	70A4      	GND                 
          	               	EH69      	55B3      	M_E_CPU1_SA_DQ<14>  
          	               	EH71      	55B3      	M_E_CPU1_SA_DQ<11>  
          	               	EH73      	70A4      	GND                 
          	               	EH75      	56B3      	M_F_CPU1_SA_DQ<6>   
          	               	EH77      	56B3      	M_F_CPU1_SA_DQ<1>   
          	               	EH79      	70A4      	GND                 
          	               	EH81      	70A4      	GND                 
          	               	EH83      	70A4      	GND                 
          	               	EH85      	66B2      	NC                  
          	               	EH87      	66B2      	NC                  
          	               	EH89      	61A3      	P5E_CPU1_PE3_RX_DN<0>
          	               	EJ3       	64B3      	UPI_CPU0_CPU1_P0P1_DP<0>
          	               	EJ5       	57B3      	M_G_CPU1_SB_DQ<29>  
          	               	EJ7       	70A4      	GND                 
          	               	EJ9       	70A4      	GND                 
          	               	EJ11      	70A4      	GND                 
          	               	EJ13      	70A4      	GND                 
          	               	EJ15      	69B3      	PVCCFA_EHV_FIVRA_CPU1
          	               	EJ17      	70A4      	GND                 
          	               	EJ19      	70A4      	GND                 
          	               	EJ21      	56B2      	M_F_CPU1_SB_DQS_DN<6>
          	               	EJ23      	70A4      	GND                 
          	               	EJ25      	70A4      	GND                 
          	               	EJ27      	55B2      	M_E_CPU1_SB_DQS_DN<5>
          	               	EJ29      	70A4      	GND                 
          	               	EJ31      	70A4      	GND                 
          	               	EJ33      	56B2      	M_F_CPU1_SB_DQS_DN<4>
          	               	EJ35      	70A4      	GND                 
          	               	EJ37      	70A4      	GND                 
          	               	EJ39      	56A2      	M_F_CPU1_SB_PAR     
          	               	EJ41      	70B4      	GND                 
          	               	EJ43      	70B4      	GND                 
          	               	EJ45      	55A3      	M_E_CPU1_CLK_DN<0>  
          	               	EJ48      	70B4      	GND                 
          	               	EJ50      	70B4      	GND                 
          	               	EJ52      	56B2      	M_F_CPU1_SA_CA<1>   
          	               	EJ54      	70B4      	GND                 
          	               	EJ56      	70B4      	GND                 
          	               	EJ58      	56B2      	M_F_CPU1_SA_DQS_DN<9>
          	               	EJ60      	70B4      	GND                 
          	               	EJ62      	70B4      	GND                 
          	               	EJ64      	56B2      	M_F_CPU1_SA_DQS_DN<7>
          	               	EJ66      	70B4      	GND                 
          	               	EJ68      	70B4      	GND                 
          	               	EJ70      	55B2      	M_E_CPU1_SA_DQS_DN<6>
          	               	EJ72      	70B4      	GND                 
          	               	EJ74      	70B4      	GND                 
          	               	EJ76      	56B2      	M_F_CPU1_SA_DQS_DN<5>
          	               	EJ78      	70B4      	GND                 
          	               	EJ80      	66B3      	GND                 
          	               	EJ82      	66B3      	GND                 
          	               	EJ84      	69B3      	PVCCFA_EHV_FIVRA_CPU1
          	               	EJ86      	66B2      	NC                  
          	               	EJ88      	70B4      	GND                 
          	               	EJ90      	61A3      	P5E_CPU1_PE3_RX_DP<0>
          	               	EK2       	70B4      	GND                 
          	               	EK4       	70B4      	GND                 
          	               	EK6       	57B3      	M_G_CPU1_SB_DQ<28>  
          	               	EK8       	57B3      	M_G_CPU1_SB_DQ<24>  
          	               	EK10      	70B4      	GND                 
          	               	EK12      	56B2      	M_F_CPU1_SB_DQS_DP<2>
          	               	EK14      	70B4      	GND                 
          	               	EK16      	70B4      	GND                 
          	               	EK18      	55B2      	M_E_CPU1_SB_DQS_DN<3>
          	               	EK20      	70B4      	GND                 
          	               	EK22      	70B4      	GND                 
          	               	EK24      	55B2      	M_E_CPU1_SB_DQS_DN<2>
          	               	EK26      	70B4      	GND                 
          	               	EK28      	70B4      	GND                 
          	               	EK30      	55B2      	M_E_CPU1_SB_DQS_DN<1>
          	               	EK32      	70B4      	GND                 
          	               	EK34      	70B4      	GND                 
          	               	EK36      	55B2      	M_E_CPU1_SB_DQS_DN<9>
          	               	EK38      	70B4      	GND                 
          	               	EK40      	70B4      	GND                 
          	               	EK42      	55B2      	M_E_CPU1_SB_CA<6>   
          	               	EK44      	70B4      	GND                 
          	               	EK47      	70B4      	GND                 
          	               	EK49      	55B2      	M_E_CPU1_SA_CA<2>   
          	               	EK51      	70B4      	GND                 
          	               	EK53      	70B4      	GND                 
          	               	EK55      	55B2      	M_E_CPU1_SA_DQS_DP<4>
          	               	EK57      	70B4      	GND                 
          	               	EK59      	70B4      	GND                 
          	               	EK61      	55B2      	M_E_CPU1_SA_DQS_DN<3>
          	               	EK63      	70B4      	GND                 
          	               	EK65      	70B4      	GND                 
          	               	EK67      	55B2      	M_E_CPU1_SA_DQS_DN<2>
          	               	EK69      	70B4      	GND                 
          	               	EK71      	70B4      	GND                 
          	               	EK73      	55B3      	M_E_CPU1_SA_DQ<5>   
          	               	EK75      	70B4      	GND                 
          	               	EK77      	70B4      	GND                 
          	               	EK79      	70B4      	GND                 
          	               	EK81      	66B3      	GND                 
          	               	EK83      	70B4      	GND                 
          	               	EK85      	66B2      	NC                  
          	               	EK87      	66B2      	NC                  
          	               	EK89      	70B4      	GND                 
          	               	EL3       	70B4      	GND                 
          	               	EL5       	70B4      	GND                 
          	               	EL7       	70B4      	GND                 
          	               	EL9       	70B4      	GND                 
          	               	EL11      	56B3      	M_F_CPU1_SB_DQ<20>  
          	               	EL13      	56B3      	M_F_CPU1_SB_DQ<17>  
          	               	EL15      	70B4      	GND                 
          	               	EL17      	55B3      	M_E_CPU1_SB_DQ<28>  
          	               	EL19      	55B3      	M_E_CPU1_SB_DQ<25>  
          	               	EL21      	70B4      	GND                 
          	               	EL23      	55B3      	M_E_CPU1_SB_DQ<20>  
          	               	EL25      	55B3      	M_E_CPU1_SB_DQ<17>  
          	               	EL27      	70B4      	GND                 
          	               	EL29      	55B3      	M_E_CPU1_SB_DQ<12>  
          	               	EL31      	55A3      	M_E_CPU1_SB_DQ<9>   
          	               	EL33      	70B4      	GND                 
          	               	EL35      	55A3      	M_E_CPU1_SB_CB<0>   
          	               	EL37      	55A3      	M_E_CPU1_SB_CB<5>   
          	               	EL39      	70B4      	GND                 
          	               	EL41      	55A2      	M_E_CPU1_SB_CS_N<3> 
          	               	EL43      	55B2      	M_E_CPU1_SB_CA<4>   
          	               	EL45      	70B4      	GND                 
          	               	EL48      	55B2      	M_E_CPU1_SA_CA<3>   
          	               	EL50      	55A2      	M_E_CPU1_SA_CS_N<3> 
          	               	EL52      	70B4      	GND                 
          	               	EL54      	55B3      	M_E_CPU1_SA_CB<4>   
          	               	EL56      	55B3      	M_E_CPU1_SA_CB<1>   
          	               	EL58      	70B4      	GND                 
          	               	EL60      	55B3      	M_E_CPU1_SA_DQ<28>  
          	               	EL62      	55B3      	M_E_CPU1_SA_DQ<25>  
          	               	EL64      	70B4      	GND                 
          	               	EL66      	55B3      	M_E_CPU1_SA_DQ<22>  
          	               	EL68      	55B2      	M_E_CPU1_SA_DQS_DP<2>
          	               	EL70      	70B4      	GND                 
          	               	EL72      	70B4      	GND                 
          	               	EL74      	55B3      	M_E_CPU1_SA_DQ<4>   
          	               	EL76      	70B4      	GND                 
          	               	EL78      	55B3      	M_E_CPU1_SA_DQ<0>   
          	               	EL80      	66B3      	GND                 
          	               	EL82      	66B3      	GND                 
          	               	EL84      	66B2      	NC                  
          	               	EL86      	70A4      	GND                 
          	               	EL88      	66B2      	NC                  
          	               	EM4       	57B3      	M_G_CPU1_SB_DQ<31>  
          	               	EM6       	57B2      	M_G_CPU1_SB_DQS_DN<8>
          	               	EM8       	70A4      	GND                 
          	               	EM10      	56B3      	M_F_CPU1_SB_DQ<21>  
          	               	EM12      	56B2      	M_F_CPU1_SB_DQS_DN<2>
          	               	EM14      	56B3      	M_F_CPU1_SB_DQ<16>  
          	               	EM16      	55B3      	M_E_CPU1_SB_DQ<29>  
          	               	EM18      	55B2      	M_E_CPU1_SB_DQS_DP<3>
          	               	EM20      	55B3      	M_E_CPU1_SB_DQ<24>  
          	               	EM22      	55B3      	M_E_CPU1_SB_DQ<21>  
          	               	EM24      	55B2      	M_E_CPU1_SB_DQS_DP<2>
          	               	EM26      	55B3      	M_E_CPU1_SB_DQ<16>  
          	               	EM28      	55B3      	M_E_CPU1_SB_DQ<13>  
          	               	EM30      	55B2      	M_E_CPU1_SB_DQS_DP<1>
          	               	EM32      	55A3      	M_E_CPU1_SB_DQ<8>   
          	               	EM34      	55A3      	M_E_CPU1_SB_CB<1>   
          	               	EM36      	55B2      	M_E_CPU1_SB_DQS_DP<9>
          	               	EM38      	55A3      	M_E_CPU1_SB_CB<4>   
          	               	EM40      	55A2      	M_E_CPU1_SB_CS_N<2> 
          	               	EM42      	70A4      	GND                 
          	               	EM44      	55B2      	M_E_CPU1_SB_CA<2>   
          	               	EM47      	55B2      	M_E_CPU1_SA_CA<4>   
          	               	EM49      	70A4      	GND                 
          	               	EM51      	55A2      	M_E_CPU1_SA_CS_N<2> 
          	               	EM53      	55B3      	M_E_CPU1_SA_CB<5>   
          	               	EM55      	55B2      	M_E_CPU1_SA_DQS_DN<4>
          	               	EM57      	55B3      	M_E_CPU1_SA_CB<0>   
          	               	EM59      	55B3      	M_E_CPU1_SA_DQ<29>  
          	               	EM61      	55B2      	M_E_CPU1_SA_DQS_DP<3>
          	               	EM63      	55B3      	M_E_CPU1_SA_DQ<24>  
          	               	EM65      	55B3      	M_E_CPU1_SA_DQ<21>  
          	               	EM67      	55B2      	M_E_CPU1_SA_DQS_DP<7>
          	               	EM69      	55B3      	M_E_CPU1_SA_DQ<17>  
          	               	EM71      	55B3      	M_E_CPU1_SA_DQ<16>  
          	               	EM73      	70A4      	GND                 
          	               	EM75      	55B2      	M_E_CPU1_SA_DQS_DN<5>
          	               	EM77      	55B3      	M_E_CPU1_SA_DQ<1>   
          	               	EM79      	70A4      	GND                 
          	               	EM81      	70A4      	GND                 
          	               	EM83      	70A4      	GND                 
          	               	EM85      	66B2      	NC                  
          	               	EM87      	66B2      	NC                  
          	               	EN5       	57B2      	M_G_CPU1_SB_DQS_DP<8>
          	               	EN7       	57B2      	M_G_CPU1_SB_DQS_DP<3>
          	               	EN9       	70A4      	GND                 
          	               	EN11      	70A4      	GND                 
          	               	EN13      	70A4      	GND                 
          	               	EN15      	70A4      	GND                 
          	               	EN17      	70A4      	GND                 
          	               	EN19      	70A4      	GND                 
          	               	EN21      	70A4      	GND                 
          	               	EN23      	70A4      	GND                 
          	               	EN25      	70A4      	GND                 
          	               	EN27      	70A4      	GND                 
          	               	EN29      	70A4      	GND                 
          	               	EN31      	70A4      	GND                 
          	               	EN33      	70A4      	GND                 
          	               	EN35      	70A4      	GND                 
          	               	EN37      	70B4      	GND                 
          	               	EN39      	70B4      	GND                 
          	               	EN41      	70B4      	GND                 
          	               	EN43      	70B4      	GND                 
          	               	EN45      	70B4      	GND                 
          	               	EN48      	70B4      	GND                 
          	               	EN50      	70B4      	GND                 
          	               	EN52      	70B4      	GND                 
          	               	EN54      	70B4      	GND                 
          	               	EN56      	70B4      	GND                 
          	               	EN58      	70B4      	GND                 
          	               	EN60      	70B4      	GND                 
          	               	EN62      	70B4      	GND                 
          	               	EN64      	70B4      	GND                 
          	               	EN66      	70B4      	GND                 
          	               	EN68      	55B2      	M_E_CPU1_SA_DQS_DN<7>
          	               	EN70      	55B3      	M_E_CPU1_SA_DQ<18>  
          	               	EN72      	70B4      	GND                 
          	               	EN74      	55B2      	M_E_CPU1_SA_DQS_DP<5>
          	               	EN76      	55B2      	M_E_CPU1_SA_DQS_DP<0>
          	               	EN78      	70B4      	GND                 
          	               	EN80      	70B4      	GND                 
          	               	EN82      	66B3      	GND                 
          	               	EN84      	69B3      	PVCCFA_EHV_FIVRA_CPU1
          	               	EN86      	66B2      	NC                  
          	               	EN88      	70B4      	GND                 
          	               	EP4       	57B3      	M_G_CPU1_SB_DQ<30>  
          	               	EP6       	57B2      	M_G_CPU1_SB_DQS_DN<3>
          	               	EP8       	57B3      	M_G_CPU1_SB_DQ<26>  
          	               	EP10      	56B3      	M_F_CPU1_SB_DQ<23>  
          	               	EP12      	56B2      	M_F_CPU1_SB_DQS_DP<7>
          	               	EP14      	56B3      	M_F_CPU1_SB_DQ<18>  
          	               	EP16      	55B3      	M_E_CPU1_SB_DQ<31>  
          	               	EP18      	55B2      	M_E_CPU1_SB_DQS_DP<8>
          	               	EP20      	55B3      	M_E_CPU1_SB_DQ<26>  
          	               	EP22      	55B3      	M_E_CPU1_SB_DQ<23>  
          	               	EP24      	55B2      	M_E_CPU1_SB_DQS_DP<7>
          	               	EP26      	55B3      	M_E_CPU1_SB_DQ<18>  
          	               	EP28      	55B3      	M_E_CPU1_SB_DQ<15>  
          	               	EP30      	55B2      	M_E_CPU1_SB_DQS_DP<6>
          	               	EP32      	55A3      	M_E_CPU1_SB_DQ<10>  
          	               	EP34      	55A3      	M_E_CPU1_SB_CB<3>   
          	               	EP36      	55B2      	M_E_CPU1_SB_DQS_DP<4>
          	               	EP38      	55A3      	M_E_CPU1_SB_CB<6>   
          	               	EP40      	55A2      	M_E_CPU1_SB_CS_N<0> 
          	               	EP42      	55A2      	M_E_CPU1_SB_PAR     
          	               	EP44      	55B2      	M_E_CPU1_SB_CA<3>   
          	               	EP47      	55B2      	M_E_CPU1_SA_CA<5>   
          	               	EP49      	55B2      	M_E_CPU1_SA_CA<0>   
          	               	EP51      	55A2      	M_E_CPU1_SA_CS_N<0> 
          	               	EP53      	55B3      	M_E_CPU1_SA_CB<7>   
          	               	EP55      	55B2      	M_E_CPU1_SA_DQS_DP<9>
          	               	EP57      	55B3      	M_E_CPU1_SA_CB<2>   
          	               	EP59      	55B3      	M_E_CPU1_SA_DQ<31>  
          	               	EP61      	55B2      	M_E_CPU1_SA_DQS_DP<8>
          	               	EP63      	55B3      	M_E_CPU1_SA_DQ<26>  
          	               	EP65      	55B3      	M_E_CPU1_SA_DQ<23>  
          	               	EP67      	70B4      	GND                 
          	               	EP69      	70B4      	GND                 
          	               	EP71      	70B4      	GND                 
          	               	EP73      	55B3      	M_E_CPU1_SA_DQ<6>   
          	               	EP75      	55B2      	M_E_CPU1_SA_DQS_DN<0>
          	               	EP77      	70B4      	GND                 
          	               	EP79      	55B3      	M_E_CPU1_SA_DQ<2>   
          	               	EP81      	66B3      	GND                 
          	               	EP83      	70B4      	GND                 
          	               	EP85      	66B2      	NC                  
          	               	EP87      	66B2      	NC                  
          	               	ER5       	70B4      	GND                 
          	               	ER7       	70B4      	GND                 
          	               	ER9       	70B4      	GND                 
          	               	ER11      	56B3      	M_F_CPU1_SB_DQ<22>  
          	               	ER13      	56B3      	M_F_CPU1_SB_DQ<19>  
          	               	ER15      	70B4      	GND                 
          	               	ER17      	55B3      	M_E_CPU1_SB_DQ<30>  
          	               	ER19      	55B3      	M_E_CPU1_SB_DQ<27>  
          	               	ER21      	70B4      	GND                 
          	               	ER23      	55B3      	M_E_CPU1_SB_DQ<22>  
          	               	ER25      	55B3      	M_E_CPU1_SB_DQ<19>  
          	               	ER27      	70B4      	GND                 
          	               	ER29      	55B3      	M_E_CPU1_SB_DQ<14>  
          	               	ER31      	55B3      	M_E_CPU1_SB_DQ<11>  
          	               	ER33      	70B4      	GND                 
          	               	ER35      	55A3      	M_E_CPU1_SB_CB<2>   
          	               	ER37      	55A3      	M_E_CPU1_SB_CB<7>   
          	               	ER39      	70B4      	GND                 
          	               	ER41      	70B4      	GND                 
          	               	ER43      	70B4      	GND                 
          	               	ER48      	70B4      	GND                 
          	               	ER50      	70B4      	GND                 
          	               	ER52      	70B4      	GND                 
          	               	ER54      	55B3      	M_E_CPU1_SA_CB<6>   
          	               	ER56      	55B3      	M_E_CPU1_SA_CB<3>   
          	               	ER58      	70B4      	GND                 
          	               	ER60      	55B3      	M_E_CPU1_SA_DQ<30>  
          	               	ER62      	55B3      	M_E_CPU1_SA_DQ<27>  
          	               	ER64      	70B4      	GND                 
          	               	ER66      	55B3      	M_E_CPU1_SA_DQ<20>  
          	               	ER68      	55B3      	M_E_CPU1_SA_DQ<19>  
          	               	ER70      	70B4      	GND                 
          	               	ER72      	55B3      	M_E_CPU1_SA_DQ<7>   
          	               	ER74      	70B4      	GND                 
          	               	ER76      	55B3      	M_E_CPU1_SA_DQ<3>   
          	               	ER78      	70B4      	GND                 
          	               	ER80      	70B4      	GND                 
          	               	ER82      	66B3      	GND                 
          	               	ER84      	70B4      	GND                 
          	               	ER86      	70B4      	GND                 
          	               	ET8       	57B3      	M_G_CPU1_SB_DQ<27>  
          	               	ET10      	70B4      	GND                 
          	               	ET12      	56B2      	M_F_CPU1_SB_DQS_DN<7>
          	               	ET14      	70B4      	GND                 
          	               	ET16      	70B4      	GND                 
          	               	ET18      	55B2      	M_E_CPU1_SB_DQS_DN<8>
          	               	ET20      	70B4      	GND                 
          	               	ET22      	70B4      	GND                 
          	               	ET24      	55B2      	M_E_CPU1_SB_DQS_DN<7>
          	               	ET26      	70B4      	GND                 
          	               	ET28      	70B4      	GND                 
          	               	ET30      	55B2      	M_E_CPU1_SB_DQS_DN<6>
          	               	ET32      	70B4      	GND                 
          	               	ET34      	70B4      	GND                 
          	               	ET36      	55B2      	M_E_CPU1_SB_DQS_DN<4>
          	               	ET38      	70B4      	GND                 
          	               	ET40      	55A2      	M_E_CPU1_SB_CS_N<1> 
          	               	ET42      	55B2      	M_E_CPU1_SB_CA<5>   
          	               	ET49      	55B2      	M_E_CPU1_SA_CA<1>   
          	               	ET51      	55A2      	M_E_CPU1_SA_CS_N<1> 
          	               	ET53      	70B4      	GND                 
          	               	ET55      	55B2      	M_E_CPU1_SA_DQS_DN<9>
          	               	ET57      	70B4      	GND                 
          	               	ET59      	70B4      	GND                 
          	               	ET61      	55B2      	M_E_CPU1_SA_DQS_DN<8>
          	               	F4        	73A2      	GND                 
          	               	F6        	73A2      	GND                 
          	               	F8        	51B3      	M_A_CPU1_SB_DQ<30>  
          	               	F10       	51B3      	M_A_CPU1_SB_DQ<27>  
          	               	F12       	73A2      	GND                 
          	               	F14       	52B3      	M_B_CPU1_SB_DQ<31>  
          	               	F16       	52B3      	M_B_CPU1_SB_DQ<27>  
          	               	F18       	73A2      	GND                 
          	               	F20       	51B3      	M_A_CPU1_SB_DQ<22>  
          	               	F22       	51B3      	M_A_CPU1_SB_DQ<19>  
          	               	F24       	73A2      	GND                 
          	               	F26       	51B3      	M_A_CPU1_SB_DQ<14>  
          	               	F28       	51B3      	M_A_CPU1_SB_DQ<11>  
          	               	F30       	73A2      	GND                 
          	               	F32       	51A3      	M_A_CPU1_SB_CB<2>   
          	               	F34       	51A3      	M_A_CPU1_SB_CB<7>   
          	               	F36       	73A2      	GND                 
          	               	F38       	51A2      	M_A_CPU1_SB_CS_N<2> 
          	               	F40       	51B2      	M_A_CPU1_SB_CA<5>   
          	               	F42       	73A2      	GND                 
          	               	F44       	51A2      	M_A_CPU1_SB_CA<1>   
          	               	F47       	45B3      	PWRGD_DRAMPWRGD_CPU1_CD_LVC1_R
          	               	F49       	73A2      	GND                 
          	               	F51       	51B2      	M_A_CPU1_SA_CA<3>   
          	               	F53       	51A2      	M_A_CPU1_SA_CS_N<3> 
          	               	F55       	73A2      	GND                 
          	               	F57       	51B3      	M_A_CPU1_SA_CB<6>   
          	               	F59       	51B3      	M_A_CPU1_SA_CB<3>   
          	               	F61       	73A2      	GND                 
          	               	F63       	51B3      	M_A_CPU1_SA_DQ<30>  
          	               	F65       	51B3      	M_A_CPU1_SA_DQ<27>  
          	               	F67       	73A2      	GND                 
          	               	F69       	51B3      	M_A_CPU1_SA_DQ<22>  
          	               	F71       	51B3      	M_A_CPU1_SA_DQ<19>  
          	               	F73       	73A2      	GND                 
          	               	F75       	51B3      	M_A_CPU1_SA_DQ<7>   
          	               	F77       	51B2      	M_A_CPU1_SA_DQS_DP<5>
          	               	F79       	73B2      	GND                 
          	               	F81       	65B3      	UPI_CPU0_CPU1_P2P2_DN<1>
          	               	F83       	73B2      	GND                 
          	               	F85       	65B2      	UPI_CPU1_CPU0_P2P2_DP<1>
          	               	F87       	65B2      	UPI_CPU1_CPU0_P2P2_DN<3>
          	               	F89       	73B2      	GND                 
          	               	G3        	73B2      	GND                 
          	               	G5        	44B3      	CPU1_RSVD<157>      
          	               	G7        	73B2      	GND                 
          	               	G9        	51B2      	M_A_CPU1_SB_DQS_DN<8>
          	               	G11       	73B2      	GND                 
          	               	G13       	73B2      	GND                 
          	               	G15       	52B2      	M_B_CPU1_SB_DQS_DP<8>
          	               	G17       	73B2      	GND                 
          	               	G19       	73B2      	GND                 
          	               	G21       	51B2      	M_A_CPU1_SB_DQS_DN<7>
          	               	G23       	73B2      	GND                 
          	               	G25       	73B2      	GND                 
          	               	G27       	51B2      	M_A_CPU1_SB_DQS_DN<6>
          	               	G29       	73B2      	GND                 
          	               	G31       	73B2      	GND                 
          	               	G33       	51B2      	M_A_CPU1_SB_DQS_DN<4>
          	               	G35       	73B2      	GND                 
          	               	G37       	73B2      	GND                 
          	               	G39       	51A2      	M_A_CPU1_SB_PAR     
          	               	G41       	73B2      	GND                 
          	               	G43       	73B2      	GND                 
          	               	G45       	51A3      	M_A_CPU1_CLK_DN<1>  
          	               	G48       	73B2      	GND                 
          	               	G50       	73B2      	GND                 
          	               	G52       	51B2      	M_A_CPU1_SA_CA<1>   
          	               	G54       	73B2      	GND                 
          	               	G56       	73B2      	GND                 
          	               	G58       	51B2      	M_A_CPU1_SA_DQS_DN<9>
          	               	G60       	73B2      	GND                 
          	               	G62       	73B2      	GND                 
          	               	G64       	51B2      	M_A_CPU1_SA_DQS_DN<8>
          	               	G66       	73B2      	GND                 
          	               	G68       	73B2      	GND                 
          	               	G70       	51B2      	M_A_CPU1_SA_DQS_DN<7>
          	               	G72       	73B2      	GND                 
          	               	G74       	73B2      	GND                 
          	               	G76       	51B3      	M_A_CPU1_SA_DQ<6>   
          	               	G78       	51B3      	M_A_CPU1_SA_DQ<3>   
          	               	G80       	65B3      	UPI_CPU0_CPU1_P2P2_DP<0>
          	               	G82       	65B3      	UPI_CPU0_CPU1_P2P2_DN<2>
          	               	G84       	73B2      	GND                 
          	               	G86       	65B2      	UPI_CPU1_CPU0_P2P2_DP<4>
          	               	G88       	73B2      	GND                 
          	               	G90       	73B2      	GND                 
          	               	H2        	73B2      	GND                 
          	               	H4        	73B2      	GND                 
          	               	H6        	73B2      	GND                 
          	               	H8        	73B2      	GND                 
          	               	H10       	73B2      	GND                 
          	               	H12       	47B3      	TP_CPU1_A0_DEBUG_EN 
          	               	H14       	73B2      	GND                 
          	               	H16       	73B2      	GND                 
          	               	H18       	52B2      	M_B_CPU1_SB_DQS_DN<2>
          	               	H20       	73B2      	GND                 
          	               	H22       	73B2      	GND                 
          	               	H24       	52B2      	M_B_CPU1_SB_DQS_DN<1>
          	               	H26       	73B2      	GND                 
          	               	H28       	73B2      	GND                 
          	               	H30       	51B2      	M_A_CPU1_SB_DQS_DN<0>
          	               	H32       	73B2      	GND                 
          	               	H34       	73B2      	GND                 
          	               	H36       	52B2      	M_B_CPU1_SB_DQS_DP<9>
          	               	H38       	73B2      	GND                 
          	               	H40       	73B2      	GND                 
          	               	H42       	52B2      	M_B_CPU1_SB_CA<6>   
          	               	H44       	73B2      	GND                 
          	               	H47       	73B2      	GND                 
          	               	H49       	52B2      	M_B_CPU1_SA_CA<0>   
          	               	H51       	73B2      	GND                 
          	               	H53       	73B2      	GND                 
          	               	H55       	52B2      	M_B_CPU1_SA_DQS_DN<4>
          	               	H57       	73B2      	GND                 
          	               	H59       	73B2      	GND                 
          	               	H61       	52B2      	M_B_CPU1_SA_DQS_DN<2>
          	               	H63       	73B2      	GND                 
          	               	H65       	73B2      	GND                 
          	               	H67       	51B2      	M_A_CPU1_SA_DQS_DN<1>
          	               	H69       	73B2      	GND                 
          	               	H71       	73B2      	GND                 
          	               	H73       	52B2      	M_B_CPU1_SA_DQS_DN<0>
          	               	H75       	73B2      	GND                 
          	               	H77       	51B2      	M_A_CPU1_SA_DQS_DN<5>
          	               	H79       	73B2      	GND                 
          	               	H81       	73B2      	GND                 
          	               	H83       	65B3      	UPI_CPU0_CPU1_P2P2_DP<2>
          	               	H85       	65B2      	UPI_CPU1_CPU0_P2P2_DN<4>
          	               	H87       	65B2      	UPI_CPU1_CPU0_P2P2_DP<3>
          	               	H89       	69A2      	PVCCFA_EHV_FIVRA_CPU1
          	               	J3        	63B2      	UPI_CPU1_CPU0_P0P1_DP<0>
          	               	J5        	73A3      	GND                 
          	               	J7        	69A2      	PVCCFA_EHV_FIVRA_CPU1
          	               	J9        	73A3      	GND                 
          	               	J11       	69A2      	PVCCFA_EHV_FIVRA_CPU1
          	               	J13       	49B3      	TP_CPU1_PPD         
          	               	J15       	73A3      	GND                 
          	               	J17       	52B3      	M_B_CPU1_SB_DQ<20>  
          	               	J19       	52B3      	M_B_CPU1_SB_DQ<17>  
          	               	J21       	73A3      	GND                 
          	               	J23       	52B3      	M_B_CPU1_SB_DQ<12>  
          	               	J25       	52A3      	M_B_CPU1_SB_DQ<9>   
          	               	J27       	73A3      	GND                 
          	               	J29       	51A3      	M_A_CPU1_SB_DQ<4>   
          	               	J31       	51A3      	M_A_CPU1_SB_DQ<1>   
          	               	J33       	73A3      	GND                 
          	               	J35       	52A3      	M_B_CPU1_SB_CB<0>   
          	               	J37       	52A3      	M_B_CPU1_SB_CB<5>   
          	               	J39       	73A3      	GND                 
          	               	J41       	52A2      	M_B_CPU1_SB_CS_N<0> 
          	               	J43       	52B2      	M_B_CPU1_SB_CA<4>   
          	               	J45       	73A3      	GND                 
          	               	J48       	52B2      	M_B_CPU1_SA_CA<2>   
          	               	J50       	52A2      	M_B_CPU1_SA_CS_N<1> 
          	               	J52       	73A3      	GND                 
          	               	J54       	52B3      	M_B_CPU1_SA_CB<4>   
          	               	J56       	52B3      	M_B_CPU1_SA_CB<1>   
          	               	J58       	73A3      	GND                 
          	               	J60       	52B3      	M_B_CPU1_SA_DQ<20>  
          	               	J62       	52B3      	M_B_CPU1_SA_DQ<17>  
          	               	J64       	73A3      	GND                 
          	               	J66       	51B3      	M_A_CPU1_SA_DQ<12>  
          	               	J68       	51B3      	M_A_CPU1_SA_DQ<9>   
          	               	J70       	73A3      	GND                 
          	               	J72       	52B3      	M_B_CPU1_SA_DQ<4>   
          	               	J74       	52B3      	M_B_CPU1_SA_DQ<1>   
          	               	J76       	73A3      	GND                 
          	               	J78       	73A3      	GND                 
          	               	J80       	69A2      	PVCCFA_EHV_FIVRA_CPU1
          	               	J82       	65B3      	UPI_CPU0_CPU1_P2P2_DN<4>
          	               	J84       	73A3      	GND                 
          	               	J86       	73A3      	GND                 
          	               	J88       	73A3      	GND                 
          	               	J90       	62B3      	P5E_CPU1_PE4_RX_DN<0>
          	               	K2        	73A3      	GND                 
          	               	K4        	63B2      	UPI_CPU1_CPU0_P0P1_DN<0>
          	               	K6        	63B3      	UPI_CPU0_CPU1_P1P0_DN<0>
          	               	K8        	73A3      	GND                 
          	               	K10       	60B3      	P5E_CPU1_PE0_RX_DN<0>
          	               	K12       	73A3      	GND                 
          	               	K14       	73A3      	GND                 
          	               	K16       	52B3      	M_B_CPU1_SB_DQ<21>  
          	               	K18       	52B2      	M_B_CPU1_SB_DQS_DP<2>
          	               	K20       	52B3      	M_B_CPU1_SB_DQ<16>  
          	               	K22       	52B3      	M_B_CPU1_SB_DQ<13>  
          	               	K24       	52B2      	M_B_CPU1_SB_DQS_DP<1>
          	               	K26       	52A3      	M_B_CPU1_SB_DQ<8>   
          	               	K28       	51A3      	M_A_CPU1_SB_DQ<5>   
          	               	K30       	51B2      	M_A_CPU1_SB_DQS_DP<0>
          	               	K32       	51A3      	M_A_CPU1_SB_DQ<0>   
          	               	K34       	52A3      	M_B_CPU1_SB_CB<1>   
          	               	K36       	52B2      	M_B_CPU1_SB_DQS_DN<9>
          	               	K38       	52A3      	M_B_CPU1_SB_CB<4>   
          	               	K40       	52A2      	M_B_CPU1_SB_CS_N<1> 
          	               	K42       	73A3      	GND                 
          	               	K44       	52B2      	M_B_CPU1_SB_CA<2>   
          	               	K47       	52B2      	M_B_CPU1_SA_CA<4>   
          	               	K49       	73B3      	GND                 
          	               	K51       	52A2      	M_B_CPU1_SA_CS_N<0> 
          	               	K53       	52B3      	M_B_CPU1_SA_CB<5>   
          	               	K55       	52B2      	M_B_CPU1_SA_DQS_DP<4>
          	               	K57       	52B3      	M_B_CPU1_SA_CB<0>   
          	               	K59       	52B3      	M_B_CPU1_SA_DQ<21>  
          	               	K61       	52B2      	M_B_CPU1_SA_DQS_DP<2>
          	               	K63       	52B3      	M_B_CPU1_SA_DQ<16>  
          	               	K65       	51B3      	M_A_CPU1_SA_DQ<13>  
          	               	K67       	51B2      	M_A_CPU1_SA_DQS_DP<1>
          	               	K69       	51B3      	M_A_CPU1_SA_DQ<8>   
          	               	K71       	52B3      	M_B_CPU1_SA_DQ<5>   
          	               	K73       	52B2      	M_B_CPU1_SA_DQS_DP<0>
          	               	K75       	52B3      	M_B_CPU1_SA_DQ<0>   
          	               	K77       	73B3      	GND                 
          	               	K79       	65B3      	UPI_CPU0_CPU1_P2P2_DN<3>
          	               	K81       	65B3      	UPI_CPU0_CPU1_P2P2_DP<5>
          	               	K83       	73B3      	GND                 
          	               	K85       	73B3      	GND                 
          	               	K87       	69B2      	PVCCFA_EHV_FIVRA_CPU1
          	               	K89       	62B3      	P5E_CPU1_PE4_RX_DP<0>
          	               	L3        	63B2      	UPI_CPU1_CPU0_P0P1_DP<1>
          	               	L5        	73B3      	GND                 
          	               	L7        	63B3      	UPI_CPU0_CPU1_P1P0_DP<0>
          	               	L9        	73B3      	GND                 
          	               	L11       	60B3      	P5E_CPU1_PE0_RX_DP<0>
          	               	L13       	73B3      	GND                 
          	               	L15       	73B3      	GND                 
          	               	L17       	73B3      	GND                 
          	               	L19       	73B3      	GND                 
          	               	L21       	73B3      	GND                 
          	               	L23       	73B3      	GND                 
          	               	L25       	73B3      	GND                 
          	               	L27       	73B3      	GND                 
          	               	L29       	73B3      	GND                 
          	               	L31       	73B3      	GND                 
          	               	L33       	73B3      	GND                 
          	               	L35       	73B3      	GND                 
          	               	L37       	73B3      	GND                 
          	               	L39       	73B3      	GND                 
          	               	L41       	73B3      	GND                 
          	               	L43       	73B3      	GND                 
          	               	L45       	73B3      	GND                 
          	               	L48       	73B3      	GND                 
          	               	L50       	73B3      	GND                 
          	               	L52       	73B3      	GND                 
          	               	L54       	73B3      	GND                 
          	               	L56       	73B3      	GND                 
          	               	L58       	73B3      	GND                 
          	               	L60       	73B3      	GND                 
          	               	L62       	73B3      	GND                 
          	               	L64       	73B3      	GND                 
          	               	L66       	73B3      	GND                 
          	               	L68       	73B3      	GND                 
          	               	L70       	73B3      	GND                 
          	               	L72       	73B3      	GND                 
          	               	L74       	73B3      	GND                 
          	               	L76       	73B3      	GND                 
          	               	L78       	73B3      	GND                 
          	               	L80       	65B3      	UPI_CPU0_CPU1_P2P2_DN<5>
          	               	L82       	65B3      	UPI_CPU0_CPU1_P2P2_DP<4>
          	               	L84       	69B2      	PVCCFA_EHV_FIVRA_CPU1
          	               	L86       	62B2      	P5E_CPU1_PE4_TX_DN<0>
          	               	L88       	73B3      	GND                 
          	               	L90       	73B3      	GND                 
          	               	M2        	63B2      	UPI_CPU1_CPU0_P0P1_DN<1>
          	               	M4        	73B3      	GND                 
          	               	M6        	63B3      	UPI_CPU0_CPU1_P1P0_DP<1>
          	               	M8        	73B3      	GND                 
          	               	M10       	60B3      	P5E_CPU1_PE0_RX_DN<1>
          	               	M12       	73B3      	GND                 
          	               	M14       	60B2      	P5E_CPU1_PE0_TX_DP<0>
          	               	M16       	52B3      	M_B_CPU1_SB_DQ<23>  
          	               	M18       	52B2      	M_B_CPU1_SB_DQS_DN<7>
          	               	M20       	52B3      	M_B_CPU1_SB_DQ<18>  
          	               	M22       	52B3      	M_B_CPU1_SB_DQ<15>  
          	               	M24       	52B2      	M_B_CPU1_SB_DQS_DN<6>
          	               	M26       	52A3      	M_B_CPU1_SB_DQ<10>  
          	               	M28       	51A3      	M_A_CPU1_SB_DQ<7>   
          	               	M30       	51B2      	M_A_CPU1_SB_DQS_DN<5>
          	               	M32       	51A3      	M_A_CPU1_SB_DQ<2>   
          	               	M34       	52A3      	M_B_CPU1_SB_CB<3>   
          	               	M36       	52B2      	M_B_CPU1_SB_DQS_DP<4>
          	               	M38       	52A3      	M_B_CPU1_SB_CB<6>   
          	               	M40       	52A2      	M_B_CPU1_SB_CS_N<3> 
          	               	M42       	73B3      	GND                 
          	               	M44       	52B2      	M_B_CPU1_SB_CA<3>   
          	               	M47       	52B2      	M_B_CPU1_SA_CA<5>   
          	               	M49       	73B3      	GND                 
          	               	M51       	52A2      	M_B_CPU1_SA_CS_N<2> 
          	               	M53       	52B3      	M_B_CPU1_SA_CB<7>   
          	               	M55       	52B2      	M_B_CPU1_SA_DQS_DN<9>
          	               	M57       	52B3      	M_B_CPU1_SA_CB<2>   
          	               	M59       	52B3      	M_B_CPU1_SA_DQ<23>  
          	               	M61       	52B2      	M_B_CPU1_SA_DQS_DN<7>
          	               	M63       	52B3      	M_B_CPU1_SA_DQ<18>  
          	               	M65       	51B3      	M_A_CPU1_SA_DQ<15>  
          	               	M67       	51B2      	M_A_CPU1_SA_DQS_DP<6>
          	               	M69       	51B3      	M_A_CPU1_SA_DQ<10>  
          	               	M71       	52B3      	M_B_CPU1_SA_DQ<7>   
          	               	M73       	52B2      	M_B_CPU1_SA_DQS_DN<5>
          	               	M75       	52B3      	M_B_CPU1_SA_DQ<2>   
          	               	M77       	51B3      	M_A_CPU1_SA_DQ<2>   
          	               	M79       	65B3      	UPI_CPU0_CPU1_P2P2_DP<3>
          	               	M81       	73B3      	GND                 
          	               	M83       	73B3      	GND                 
          	               	M85       	69B2      	PVCCFA_EHV_FIVRA_CPU1
          	               	M87       	62B2      	P5E_CPU1_PE4_TX_DP<0>
          	               	M89       	69B2      	PVCCFA_EHV_FIVRA_CPU1
          	               	N1        	63B2      	UPI_CPU1_CPU0_P0P1_DN<2>
          	               	N3        	68A1      	PVCCFA_EHV_CPU1     
          	               	N5        	63B3      	UPI_CPU0_CPU1_P1P0_DN<1>
          	               	N7        	69B2      	PVCCFA_EHV_FIVRA_CPU1
          	               	N9        	60B3      	P5E_CPU1_PE0_RX_DP<1>
          	               	N11       	69B2      	PVCCFA_EHV_FIVRA_CPU1
          	               	N13       	60B2      	P5E_CPU1_PE0_TX_DN<0>
          	               	N15       	73B3      	GND                 
          	               	N17       	52B3      	M_B_CPU1_SB_DQ<22>  
          	               	N19       	52B3      	M_B_CPU1_SB_DQ<19>  
          	               	N21       	73B3      	GND                 
          	               	N23       	52B3      	M_B_CPU1_SB_DQ<14>  
          	               	N25       	52B3      	M_B_CPU1_SB_DQ<11>  
          	               	N27       	73B3      	GND                 
          	               	N29       	51A3      	M_A_CPU1_SB_DQ<6>   
          	               	N31       	51A3      	M_A_CPU1_SB_DQ<3>   
          	               	N33       	73B3      	GND                 
          	               	N35       	52A3      	M_B_CPU1_SB_CB<2>   
          	               	N37       	52A3      	M_B_CPU1_SB_CB<7>   
          	               	N39       	73B3      	GND                 
          	               	N41       	52A2      	M_B_CPU1_SB_CS_N<2> 
          	               	N43       	52B2      	M_B_CPU1_SB_CA<5>   
          	               	N45       	73B3      	GND                 
          	               	N48       	52B2      	M_B_CPU1_SA_CA<3>   
          	               	N50       	52A2      	M_B_CPU1_SA_CS_N<3> 
          	               	N52       	73B3      	GND                 
          	               	N54       	52B3      	M_B_CPU1_SA_CB<6>   
          	               	N56       	52B3      	M_B_CPU1_SA_CB<3>   
          	               	N58       	73B3      	GND                 
          	               	N60       	52B3      	M_B_CPU1_SA_DQ<22>  
          	               	N62       	52B3      	M_B_CPU1_SA_DQ<19>  
          	               	N64       	73B3      	GND                 
          	               	N66       	51B3      	M_A_CPU1_SA_DQ<14>  
          	               	N68       	51B3      	M_A_CPU1_SA_DQ<11>  
          	               	N70       	73B3      	GND                 
          	               	N72       	52B3      	M_B_CPU1_SA_DQ<6>   
          	               	N74       	52B3      	M_B_CPU1_SA_DQ<3>   
          	               	N76       	73A4      	GND                 
          	               	N78       	73A4      	GND                 
          	               	N80       	73A4      	GND                 
          	               	N82       	73A4      	GND                 
          	               	N84       	73A4      	GND                 
          	               	N86       	62B2      	P5E_CPU1_PE4_TX_DP<1>
          	               	N88       	73A4      	GND                 
          	               	N90       	62B3      	P5E_CPU1_PE4_RX_DP<1>
          	               	P2        	63B2      	UPI_CPU1_CPU0_P0P1_DP<2>
          	               	P4        	73A4      	GND                 
          	               	P6        	63B3      	UPI_CPU0_CPU1_P1P0_DN<2>
          	               	P8        	73A4      	GND                 
          	               	P10       	60B3      	P5E_CPU1_PE0_RX_DN<2>
          	               	P12       	73A4      	GND                 
          	               	P14       	60B2      	P5E_CPU1_PE0_TX_DN<1>
          	               	P16       	73A4      	GND                 
          	               	P18       	52B2      	M_B_CPU1_SB_DQS_DP<7>
          	               	P20       	73A4      	GND                 
          	               	P22       	73A4      	GND                 
          	               	P24       	52B2      	M_B_CPU1_SB_DQS_DP<6>
          	               	P26       	73A4      	GND                 
          	               	P28       	73A4      	GND                 
          	               	P30       	51B2      	M_A_CPU1_SB_DQS_DP<5>
          	               	P32       	73A4      	GND                 
          	               	P34       	73A4      	GND                 
          	               	P36       	52B2      	M_B_CPU1_SB_DQS_DN<4>
          	               	P38       	73A4      	GND                 
          	               	P40       	73A4      	GND                 
          	               	P42       	52A2      	M_B_CPU1_SB_PAR     
          	               	P44       	73A4      	GND                 
          	               	P47       	73A4      	GND                 
          	               	P49       	52B2      	M_B_CPU1_SA_CA<1>   
          	               	P51       	73A4      	GND                 
          	               	P53       	73A4      	GND                 
          	               	P55       	52B2      	M_B_CPU1_SA_DQS_DP<9>
          	               	P57       	73B4      	GND                 
          	               	P59       	73B4      	GND                 
          	               	P61       	52B2      	M_B_CPU1_SA_DQS_DP<7>
          	               	P63       	73B4      	GND                 
          	               	P65       	73B4      	GND                 
          	               	P67       	51B2      	M_A_CPU1_SA_DQS_DN<6>
          	               	P69       	73B4      	GND                 
          	               	P71       	73B4      	GND                 
          	               	P73       	52B2      	M_B_CPU1_SA_DQS_DP<5>
          	               	P75       	73B4      	GND                 
          	               	P77       	73B4      	GND                 
          	               	P79       	69B2      	PVCCFA_EHV_FIVRA_CPU1
          	               	P81       	65B2      	UPI_CPU1_CPU0_P2P2_DN<5>
          	               	P83       	65B2      	UPI_CPU1_CPU0_P2P2_DP<6>
          	               	P85       	62B2      	P5E_CPU1_PE4_TX_DN<1>
          	               	P87       	73B4      	GND                 
          	               	P89       	62B3      	P5E_CPU1_PE4_RX_DN<1>
          	               	P91       	73B4      	GND                 
          	               	R1        	73B4      	GND                 
          	               	R3        	63B2      	UPI_CPU1_CPU0_P0P1_DP<3>
          	               	R5        	73B4      	GND                 
          	               	R7        	63B3      	UPI_CPU0_CPU1_P1P0_DP<2>
          	               	R9        	73B4      	GND                 
          	               	R11       	60B3      	P5E_CPU1_PE0_RX_DP<2>
          	               	R13       	73B4      	GND                 
          	               	R15       	60B2      	P5E_CPU1_PE0_TX_DP<1>
          	               	R17       	73B4      	GND                 
          	               	R19       	73B4      	GND                 
          	               	R21       	53B2      	M_C_CPU1_SB_DQS_DN<2>
          	               	R23       	73B4      	GND                 
          	               	R25       	73B4      	GND                 
          	               	R27       	52B2      	M_B_CPU1_SB_DQS_DN<0>
          	               	R29       	73B4      	GND                 
          	               	R31       	73B4      	GND                 
          	               	R33       	53B2      	M_C_CPU1_SB_DQS_DN<9>
          	               	R35       	73B4      	GND                 
          	               	R37       	73B4      	GND                 
          	               	R39       	53B2      	M_C_CPU1_SB_CA<6>   
          	               	R41       	73B4      	GND                 
          	               	R43       	73B4      	GND                 
          	               	R45       	52A3      	M_B_CPU1_CLK_DN<0>  
          	               	R48       	73B4      	GND                 
          	               	R50       	73B4      	GND                 
          	               	R52       	53B2      	M_C_CPU1_SA_CA<0>   
          	               	R54       	73B4      	GND                 
          	               	R56       	73B4      	GND                 
          	               	R58       	52B2      	M_B_CPU1_SA_DQS_DN<3>
          	               	R60       	73B4      	GND                 
          	               	R62       	73B4      	GND                 
          	               	R64       	53B2      	M_C_CPU1_SA_DQS_DN<2>
          	               	R66       	73B4      	GND                 
          	               	R68       	73B4      	GND                 
          	               	R70       	52B2      	M_B_CPU1_SA_DQS_DN<1>
          	               	R72       	73B4      	GND                 
          	               	R74       	73B4      	GND                 
          	               	R76       	53B2      	M_C_CPU1_SA_DQS_DN<0>
          	               	R78       	73B4      	GND                 
          	               	R80       	69B2      	PVCCFA_EHV_FIVRA_CPU1
          	               	R82       	65B2      	UPI_CPU1_CPU0_P2P2_DN<6>
          	               	R84       	73B4      	GND                 
          	               	R86       	62B2      	P5E_CPU1_PE4_TX_DN<2>
          	               	R88       	73B4      	GND                 
          	               	R90       	62B3      	P5E_CPU1_PE4_RX_DP<2>
          	               	T2        	63B2      	UPI_CPU1_CPU0_P0P1_DN<3>
          	               	T4        	73B4      	GND                 
          	               	T6        	63B3      	UPI_CPU0_CPU1_P1P0_DP<3>
          	               	T8        	73B4      	GND                 
          	               	T10       	60B3      	P5E_CPU1_PE0_RX_DN<3>
          	               	T12       	73B4      	GND                 
          	               	T14       	60B2      	P5E_CPU1_PE0_TX_DP<2>
          	               	T16       	73B4      	GND                 
          	               	T18       	73B4      	GND                 
          	               	T20       	53B3      	M_C_CPU1_SB_DQ<20>  
          	               	T22       	53B3      	M_C_CPU1_SB_DQ<17>  
          	               	T24       	73B4      	GND                 
          	               	T26       	52A3      	M_B_CPU1_SB_DQ<4>   
          	               	T28       	52A3      	M_B_CPU1_SB_DQ<1>   
          	               	T30       	73B4      	GND                 
          	               	T32       	53A3      	M_C_CPU1_SB_CB<0>   
          	               	T34       	53A3      	M_C_CPU1_SB_CB<5>   
          	               	T36       	73B4      	GND                 
          	               	T38       	53A2      	M_C_CPU1_SB_CS_N<0> 
          	               	T40       	53B2      	M_C_CPU1_SB_CA<4>   
          	               	T42       	73B4      	GND                 
          	               	T44       	52A2      	M_B_CPU1_SB_CA<0>   
          	               	T47       	53B2      	M_C_CPU1_SA_PAR     
          	               	T49       	73B4      	GND                 
          	               	T51       	53B2      	M_C_CPU1_SA_CA<2>   
          	               	T53       	53A2      	M_C_CPU1_SA_CS_N<1> 
          	               	T55       	73B4      	GND                 
          	               	T57       	52B3      	M_B_CPU1_SA_DQ<28>  
          	               	T59       	52B3      	M_B_CPU1_SA_DQ<25>  
          	               	T61       	73B4      	GND                 
          	               	T63       	53B3      	M_C_CPU1_SA_DQ<20>  
          	               	T65       	53B3      	M_C_CPU1_SA_DQ<17>  
          	               	T67       	73B4      	GND                 
          	               	T69       	52B3      	M_B_CPU1_SA_DQ<12>  
          	               	T71       	52B3      	M_B_CPU1_SA_DQ<9>   
          	               	T73       	73B4      	GND                 
          	               	T75       	53B3      	M_C_CPU1_SA_DQ<4>   
          	               	T77       	53B3      	M_C_CPU1_SA_DQ<1>   
          	               	T79       	73B4      	GND                 
          	               	T81       	65B2      	UPI_CPU1_CPU0_P2P2_DP<5>
          	               	T83       	73B4      	GND                 
          	               	T85       	69B2      	PVCCFA_EHV_FIVRA_CPU1
          	               	T87       	62B2      	P5E_CPU1_PE4_TX_DP<2>
          	               	T89       	69B2      	PVCCFA_EHV_FIVRA_CPU1
          	               	T91       	62B3      	P5E_CPU1_PE4_RX_DN<2>
          	               	U1        	63B2      	UPI_CPU1_CPU0_P0P1_DN<4>
          	               	U3        	68A1      	PVCCFA_EHV_CPU1     
          	               	U5        	63B3      	UPI_CPU0_CPU1_P1P0_DN<3>
          	               	U7        	69B2      	PVCCFA_EHV_FIVRA_CPU1
          	               	U9        	60B3      	P5E_CPU1_PE0_RX_DP<3>
          	               	U11       	69B2      	PVCCFA_EHV_FIVRA_CPU1
          	               	U13       	60B2      	P5E_CPU1_PE0_TX_DN<2>
          	               	U15       	69B2      	PVCCFA_EHV_FIVRA_CPU1
          	               	U17       	48B3      	NC_CPU1_HBM0_VIEWDIG0
          	               	U19       	53B3      	M_C_CPU1_SB_DQ<21>  
          	               	U21       	53B2      	M_C_CPU1_SB_DQS_DP<2>
          	               	U23       	53B3      	M_C_CPU1_SB_DQ<16>  
          	               	U25       	52A3      	M_B_CPU1_SB_DQ<5>   
          	               	U27       	52B2      	M_B_CPU1_SB_DQS_DP<0>
          	               	U29       	52A3      	M_B_CPU1_SB_DQ<0>   
          	               	U31       	53A3      	M_C_CPU1_SB_CB<1>   
          	               	U33       	53B2      	M_C_CPU1_SB_DQS_DP<9>
          	               	U35       	53A3      	M_C_CPU1_SB_CB<4>   
          	               	U37       	53A2      	M_C_CPU1_SB_CS_N<1> 
          	               	U39       	73B4      	GND                 
          	               	U41       	53B2      	M_C_CPU1_SB_CA<2>   
          	               	U43       	52A2      	M_B_CPU1_SB_CA<1>   
          	               	U45       	52A3      	M_B_CPU1_CLK_DP<0>  
          	               	U48       	53B2      	M_C_CPU1_SA_CA<6>   
          	               	U50       	53B2      	M_C_CPU1_SA_CA<4>   
          	               	U52       	73B4      	GND                 
          	               	U54       	53A2      	M_C_CPU1_SA_CS_N<0> 
          	               	U56       	52B3      	M_B_CPU1_SA_DQ<29>  
          	               	U58       	52B2      	M_B_CPU1_SA_DQS_DP<3>
          	               	U60       	52B3      	M_B_CPU1_SA_DQ<24>  
          	               	U62       	53B3      	M_C_CPU1_SA_DQ<21>  
          	               	U64       	53B2      	M_C_CPU1_SA_DQS_DP<2>
          	               	U66       	53B3      	M_C_CPU1_SA_DQ<16>  
          	               	U68       	52B3      	M_B_CPU1_SA_DQ<13>  
          	               	U70       	52B2      	M_B_CPU1_SA_DQS_DP<1>
          	               	U72       	52B3      	M_B_CPU1_SA_DQ<8>   
          	               	U74       	53B3      	M_C_CPU1_SA_DQ<5>   
          	               	U76       	53B2      	M_C_CPU1_SA_DQS_DP<0>
          	               	U78       	53B3      	M_C_CPU1_SA_DQ<0>   
          	               	U80       	65B2      	UPI_CPU1_CPU0_P2P2_DN<7>
          	               	U82       	73B4      	GND                 
          	               	U84       	73B4      	GND                 
          	               	U86       	62B2      	P5E_CPU1_PE4_TX_DN<3>
          	               	U88       	73B4      	GND                 
          	               	U90       	62B3      	P5E_CPU1_PE4_RX_DP<3>
          	               	V2        	63B2      	UPI_CPU1_CPU0_P0P1_DP<4>
          	               	V4        	73A4      	GND                 
          	               	V6        	63B3      	UPI_CPU0_CPU1_P1P0_DN<4>
          	               	V8        	73A4      	GND                 
          	               	V10       	60B3      	P5E_CPU1_PE0_RX_DN<4>
          	               	V12       	73A4      	GND                 
          	               	V14       	60B2      	P5E_CPU1_PE0_TX_DN<3>
          	               	V16       	73A4      	GND                 
          	               	V18       	73A4      	GND                 
          	               	V20       	73A4      	GND                 
          	               	V22       	73A4      	GND                 
          	               	V24       	73A4      	GND                 
          	               	V26       	73A4      	GND                 
          	               	V28       	73A4      	GND                 
          	               	V30       	73A4      	GND                 
          	               	V32       	73A4      	GND                 
          	               	V34       	73A4      	GND                 
          	               	V36       	73A4      	GND                 
          	               	V38       	73A4      	GND                 
          	               	V40       	73A4      	GND                 
          	               	V42       	73A4      	GND                 
          	               	V44       	73A4      	GND                 
          	               	V47       	73A4      	GND                 
          	               	V49       	73A4      	GND                 
          	               	V51       	73A4      	GND                 
          	               	V53       	73A4      	GND                 
          	               	V55       	73B4      	GND                 
          	               	V57       	73B4      	GND                 
          	               	V59       	73B4      	GND                 
          	               	V61       	73B4      	GND                 
          	               	V63       	73B4      	GND                 
          	               	V65       	73B4      	GND                 
          	               	V67       	73B4      	GND                 
          	               	V69       	73B4      	GND                 
          	               	V71       	73B4      	GND                 
          	               	V73       	73B4      	GND                 
          	               	V75       	73B4      	GND                 
          	               	V77       	73B4      	GND                 
          	               	V79       	73B4      	GND                 
          	               	V81       	65B2      	UPI_CPU1_CPU0_P2P2_DP<7>
          	               	V83       	65B2      	UPI_CPU1_CPU0_P2P2_DN<8>
          	               	V85       	62B2      	P5E_CPU1_PE4_TX_DP<3>
          	               	V87       	73B4      	GND                 
          	               	V89       	62B3      	P5E_CPU1_PE4_RX_DN<3>
          	               	V91       	73B4      	GND                 
          	               	W1        	73B4      	GND                 
          	               	W3        	63B2      	UPI_CPU1_CPU0_P0P1_DP<5>
          	               	W5        	73B4      	GND                 
          	               	W7        	63B3      	UPI_CPU0_CPU1_P1P0_DP<4>
          	               	W9        	73B4      	GND                 
          	               	W11       	60B3      	P5E_CPU1_PE0_RX_DP<4>
          	               	W13       	73B4      	GND                 
          	               	W15       	60B2      	P5E_CPU1_PE0_TX_DP<3>
          	               	W17       	48B3      	NC_CPU1_HBM1_VIEWDIG0
          	               	W19       	53B3      	M_C_CPU1_SB_DQ<23>  
          	               	W21       	53B2      	M_C_CPU1_SB_DQS_DN<7>
          	               	W23       	53B3      	M_C_CPU1_SB_DQ<18>  
          	               	W25       	52A3      	M_B_CPU1_SB_DQ<7>   
          	               	W27       	52B2      	M_B_CPU1_SB_DQS_DN<5>
          	               	W29       	52A3      	M_B_CPU1_SB_DQ<2>   
          	               	W31       	53A3      	M_C_CPU1_SB_CB<3>   
          	               	W33       	53B2      	M_C_CPU1_SB_DQS_DN<4>
          	               	W35       	53A3      	M_C_CPU1_SB_CB<6>   
          	               	W37       	53A2      	M_C_CPU1_SB_CS_N<3> 
          	               	W39       	73B4      	GND                 
          	               	W41       	53B2      	M_C_CPU1_SB_CA<3>   
          	               	W43       	52B2      	M_B_CPU1_SA_PAR     
          	               	W45       	52A3      	M_B_CPU1_CLK_DN<1>  
          	               	W48       	53A2      	M_C_CPU1_SB_CA<0>   
          	               	W50       	53B2      	M_C_CPU1_SA_CA<5>   
          	               	W52       	73B4      	GND                 
          	               	W54       	53A2      	M_C_CPU1_SA_CS_N<2> 
          	               	W56       	52B3      	M_B_CPU1_SA_DQ<31>  
          	               	W58       	52B2      	M_B_CPU1_SA_DQS_DP<8>
          	               	W60       	52B3      	M_B_CPU1_SA_DQ<26>  
          	               	W62       	53B3      	M_C_CPU1_SA_DQ<23>  
          	               	W64       	53B2      	M_C_CPU1_SA_DQS_DP<7>
          	               	W66       	53B3      	M_C_CPU1_SA_DQ<18>  
          	               	W68       	52B3      	M_B_CPU1_SA_DQ<15>  
          	               	W70       	52B2      	M_B_CPU1_SA_DQS_DP<6>
          	               	W72       	52B3      	M_B_CPU1_SA_DQ<10>  
          	               	W74       	53B3      	M_C_CPU1_SA_DQ<7>   
          	               	W76       	53B2      	M_C_CPU1_SA_DQS_DN<5>
          	               	W78       	53B3      	M_C_CPU1_SA_DQ<2>   
          	               	W80       	69B2      	PVCCFA_EHV_FIVRA_CPU1
          	               	W82       	65B2      	UPI_CPU1_CPU0_P2P2_DP<9>
          	               	W84       	73B4      	GND                 
          	               	W86       	62B2      	P5E_CPU1_PE4_TX_DN<4>
          	               	W88       	73B4      	GND                 
          	               	W90       	62B3      	P5E_CPU1_PE4_RX_DP<4>
          	               	Y2        	63B2      	UPI_CPU1_CPU0_P0P1_DN<5>
          	               	Y4        	73B4      	GND                 
          	               	Y6        	63B3      	UPI_CPU0_CPU1_P1P0_DP<5>
          	               	Y8        	73B4      	GND                 
          	               	Y10       	60B3      	P5E_CPU1_PE0_RX_DP<5>
          	               	Y12       	73B4      	GND                 
          	               	Y14       	60B2      	P5E_CPU1_PE0_TX_DP<4>
          	               	Y16       	73B4      	GND                 
          	               	Y18       	73B4      	GND                 
          	               	Y20       	53B3      	M_C_CPU1_SB_DQ<22>  
          	               	Y22       	53B3      	M_C_CPU1_SB_DQ<19>  
          	               	Y24       	73B4      	GND                 
          	               	Y26       	52A3      	M_B_CPU1_SB_DQ<6>   
          	               	Y28       	52A3      	M_B_CPU1_SB_DQ<3>   
          	               	Y30       	73B4      	GND                 
          	               	Y32       	53A3      	M_C_CPU1_SB_CB<2>   
          	               	Y34       	53A3      	M_C_CPU1_SB_CB<7>   
          	               	Y36       	73B4      	GND                 
          	               	Y38       	53A2      	M_C_CPU1_SB_CS_N<2> 
          	               	Y40       	53B2      	M_C_CPU1_SB_CA<5>   
          	               	Y42       	73B4      	GND                 
          	               	Y44       	52B2      	M_B_CPU1_SA_CA<6>   
          	               	Y47       	53A2      	M_C_CPU1_SB_CA<1>   
          	               	Y49       	73B4      	GND                 
          	               	Y51       	53B2      	M_C_CPU1_SA_CA<3>   
          	               	Y53       	53A2      	M_C_CPU1_SA_CS_N<3> 
          	               	Y55       	73B4      	GND                 
          	               	Y57       	52B3      	M_B_CPU1_SA_DQ<30>  
          	               	Y59       	52B3      	M_B_CPU1_SA_DQ<27>  
          	               	Y61       	73B4      	GND                 
          	               	Y63       	53B3      	M_C_CPU1_SA_DQ<22>  
          	               	Y65       	53B3      	M_C_CPU1_SA_DQ<19>  
          	               	Y67       	73B4      	GND                 
          	               	Y69       	52B3      	M_B_CPU1_SA_DQ<14>  
          	               	Y71       	52B3      	M_B_CPU1_SA_DQ<11>  
          	               	Y73       	73B4      	GND                 
          	               	Y75       	53B3      	M_C_CPU1_SA_DQ<6>   
          	               	Y77       	53B3      	M_C_CPU1_SA_DQ<3>   
          	               	Y79       	69B2      	PVCCFA_EHV_FIVRA_CPU1
          	               	Y81       	65B2      	UPI_CPU1_CPU0_P2P2_DN<9>
          	               	Y83       	65B2      	UPI_CPU1_CPU0_P2P2_DP<8>
          	               	Y85       	69B2      	PVCCFA_EHV_FIVRA_CPU1
          	               	Y87       	62B2      	P5E_CPU1_PE4_TX_DP<4>
          	               	Y89       	69B2      	PVCCFA_EHV_FIVRA_CPU1
          	               	Y91       	62B3      	P5E_CPU1_PE4_RX_DN<4>

U1_BL     	TP_TP_BOM ONLY 	          	          	                    
          	               	1         	311A4     	NC                  

U1_BP     	TP_TP_BOM ONLY 	          	          	                    
          	               	1         	311A4     	NC                  

U1_DC     	TP_TP_BOM ONLY 	          	          	                    
          	               	1         	311A3     	NC                  

U2        	SOCKET4677_AZIF0045P001C01CS	          	          	                    
          	               	A9        	20B2      	M_A_CPU0_SB_DQS_DN<3>
          	               	A11       	42A2      	GND                 
          	               	A13       	42A2      	GND                 
          	               	A15       	21B2      	M_B_CPU0_SB_DQS_DN<3>
          	               	A17       	42A2      	GND                 
          	               	A19       	42A2      	GND                 
          	               	A21       	20B2      	M_A_CPU0_SB_DQS_DN<2>
          	               	A23       	42A2      	GND                 
          	               	A25       	42A2      	GND                 
          	               	A27       	20B2      	M_A_CPU0_SB_DQS_DN<1>
          	               	A29       	42A2      	GND                 
          	               	A31       	42A2      	GND                 
          	               	A33       	20B2      	M_A_CPU0_SB_DQS_DN<9>
          	               	A35       	42A2      	GND                 
          	               	A37       	42A2      	GND                 
          	               	A39       	20B2      	M_A_CPU0_SB_CA<6>   
          	               	A41       	42A2      	GND                 
          	               	A43       	14B3      	PWRGD_DRAMPWRGD_CPU0_AB_LVC1_R
          	               	A50       	42A2      	GND                 
          	               	A52       	20B2      	M_A_CPU0_SA_CA<0>   
          	               	A54       	42A2      	GND                 
          	               	A56       	42A2      	GND                 
          	               	A58       	20B2      	M_A_CPU0_SA_DQS_DN<4>
          	               	A60       	42A2      	GND                 
          	               	A62       	42A2      	GND                 
          	               	A64       	20B2      	M_A_CPU0_SA_DQS_DN<3>
          	               	AA1       	32B2      	UPI_CPU0_CPU1_P0P1_DN<6>
          	               	AA3       	37A1      	PVCCFA_EHV_CPU0     
          	               	AA5       	32B3      	UPI_CPU1_CPU0_P1P0_DP<5>
          	               	AA7       	38B2      	PVCCFA_EHV_FIVRA_CPU0
          	               	AA9       	29B3      	P5E_CPU0_PE0_RX_DN<5>
          	               	AA11      	38B2      	PVCCFA_EHV_FIVRA_CPU0
          	               	AA13      	29B2      	P5E_CPU0_PE0_TX_DN<4>
          	               	AA15      	38B2      	PVCCFA_EHV_FIVRA_CPU0
          	               	AA17      	22B3      	M_C_CPU0_SB_DQ<28>  
          	               	AA19      	42B4      	GND                 
          	               	AA21      	22B2      	M_C_CPU0_SB_DQS_DP<7>
          	               	AA23      	42B4      	GND                 
          	               	AA25      	42B4      	GND                 
          	               	AA27      	21B2      	M_B_CPU0_SB_DQS_DP<5>
          	               	AA29      	42B4      	GND                 
          	               	AA31      	42B4      	GND                 
          	               	AA33      	22B2      	M_C_CPU0_SB_DQS_DP<4>
          	               	AA35      	42B4      	GND                 
          	               	AA37      	42B4      	GND                 
          	               	AA39      	22A2      	M_C_CPU0_SB_PAR     
          	               	AA41      	42B4      	GND                 
          	               	AA43      	42B4      	GND                 
          	               	AA45      	21A3      	M_B_CPU0_CLK_DP<1>  
          	               	AA48      	42B4      	GND                 
          	               	AA50      	42B4      	GND                 
          	               	AA52      	22B2      	M_C_CPU0_SA_CA<1>   
          	               	AA54      	42B4      	GND                 
          	               	AA56      	42B4      	GND                 
          	               	AA58      	21B2      	M_B_CPU0_SA_DQS_DN<8>
          	               	AA60      	42B4      	GND                 
          	               	AA62      	42B4      	GND                 
          	               	AA64      	22B2      	M_C_CPU0_SA_DQS_DN<7>
          	               	AA66      	42B4      	GND                 
          	               	AA68      	42B4      	GND                 
          	               	AA70      	21B2      	M_B_CPU0_SA_DQS_DN<6>
          	               	AA72      	42B4      	GND                 
          	               	AA74      	42B4      	GND                 
          	               	AA76      	22B2      	M_C_CPU0_SA_DQS_DP<5>
          	               	AA78      	42B4      	GND                 
          	               	AA80      	42B4      	GND                 
          	               	AA82      	41A1      	GND                 
          	               	AA84      	41A1      	GND                 
          	               	AA86      	31B2      	P5E_CPU0_PE4_TX_DN<5>
          	               	AA88      	41A1      	GND                 
          	               	AA90      	31B3      	P5E_CPU0_PE4_RX_DP<5>
          	               	AB2       	32B2      	UPI_CPU0_CPU1_P0P1_DP<6>
          	               	AB4       	41A1      	GND                 
          	               	AB6       	32B3      	UPI_CPU1_CPU0_P1P0_DN<6>
          	               	AB8       	41A1      	GND                 
          	               	AB10      	29B3      	P5E_CPU0_PE0_RX_DN<6>
          	               	AB12      	41A1      	GND                 
          	               	AB14      	29B2      	P5E_CPU0_PE0_TX_DN<5>
          	               	AB16      	41A1      	GND                 
          	               	AB18      	22B2      	M_C_CPU0_SB_DQS_DN<3>
          	               	AB20      	41A1      	GND                 
          	               	AB22      	41A1      	GND                 
          	               	AB24      	23B2      	M_D_CPU0_SB_DQS_DN<2>
          	               	AB26      	41A1      	GND                 
          	               	AB28      	41A1      	GND                 
          	               	AB30      	22B2      	M_C_CPU0_SB_DQS_DN<1>
          	               	AB32      	41A1      	GND                 
          	               	AB34      	41A1      	GND                 
          	               	AB36      	22B2      	M_C_CPU0_SB_DQS_DN<0>
          	               	AB38      	41A1      	GND                 
          	               	AB40      	41A1      	GND                 
          	               	AB42      	23B2      	M_D_CPU0_SB_CA<6>   
          	               	AB44      	41A1      	GND                 
          	               	AB47      	41A1      	GND                 
          	               	AB49      	22A3      	M_C_CPU0_CLK_DN<0>  
          	               	AB51      	41A1      	GND                 
          	               	AB53      	41A1      	GND                 
          	               	AB55      	22B2      	M_C_CPU0_SA_DQS_DP<4>
          	               	AB57      	41A1      	GND                 
          	               	AB59      	41A1      	GND                 
          	               	AB61      	22B2      	M_C_CPU0_SA_DQS_DN<3>
          	               	AB63      	41A1      	GND                 
          	               	AB65      	41B1      	GND                 
          	               	AB67      	22B2      	M_C_CPU0_SA_DQS_DN<1>
          	               	AB69      	41B1      	GND                 
          	               	AB71      	41B1      	GND                 
          	               	AB73      	23B2      	M_D_CPU0_SA_DQS_DN<0>
          	               	AB75      	41B1      	GND                 
          	               	AB77      	41B1      	GND                 
          	               	AB79      	41B1      	GND                 
          	               	AB81      	41B1      	GND                 
          	               	AB83      	41B1      	GND                 
          	               	AB85      	31B2      	P5E_CPU0_PE4_TX_DP<5>
          	               	AB87      	41B1      	GND                 
          	               	AB89      	31B3      	P5E_CPU0_PE4_RX_DN<5>
          	               	AB91      	41B1      	GND                 
          	               	AC1       	41B1      	GND                 
          	               	AC3       	32B2      	UPI_CPU0_CPU1_P0P1_DP<7>
          	               	AC5       	41B1      	GND                 
          	               	AC7       	32B3      	UPI_CPU1_CPU0_P1P0_DP<6>
          	               	AC9       	41B1      	GND                 
          	               	AC11      	29B3      	P5E_CPU0_PE0_RX_DP<6>
          	               	AC13      	41B1      	GND                 
          	               	AC15      	29B2      	P5E_CPU0_PE0_TX_DP<5>
          	               	AC17      	22B3      	M_C_CPU0_SB_DQ<30>  
          	               	AC19      	22B3      	M_C_CPU0_SB_DQ<25>  
          	               	AC21      	41B1      	GND                 
          	               	AC23      	23B3      	M_D_CPU0_SB_DQ<20>  
          	               	AC25      	23B3      	M_D_CPU0_SB_DQ<17>  
          	               	AC27      	41B1      	GND                 
          	               	AC29      	22B3      	M_C_CPU0_SB_DQ<12>  
          	               	AC31      	22A3      	M_C_CPU0_SB_DQ<9>   
          	               	AC33      	41B1      	GND                 
          	               	AC35      	22A3      	M_C_CPU0_SB_DQ<4>   
          	               	AC37      	22A3      	M_C_CPU0_SB_DQ<1>   
          	               	AC39      	41B1      	GND                 
          	               	AC41      	23A2      	M_D_CPU0_SB_CS_N<0> 
          	               	AC43      	23B2      	M_D_CPU0_SB_CA<4>   
          	               	AC45      	41B1      	GND                 
          	               	AC48      	22A2      	M_C_CPU0_SA_RSP<0>  
          	               	AC50      	23A2      	M_D_CPU0_SA_RSP<1>  
          	               	AC52      	41B1      	GND                 
          	               	AC54      	22B3      	M_C_CPU0_SA_CB<4>   
          	               	AC56      	22B3      	M_C_CPU0_SA_CB<1>   
          	               	AC58      	41B1      	GND                 
          	               	AC60      	22B3      	M_C_CPU0_SA_DQ<28>  
          	               	AC62      	22B3      	M_C_CPU0_SA_DQ<25>  
          	               	AC64      	41B1      	GND                 
          	               	AC66      	22B3      	M_C_CPU0_SA_DQ<12>  
          	               	AC68      	22B3      	M_C_CPU0_SA_DQ<9>   
          	               	AC70      	41B1      	GND                 
          	               	AC72      	23B3      	M_D_CPU0_SA_DQ<4>   
          	               	AC74      	23B3      	M_D_CPU0_SA_DQ<1>   
          	               	AC76      	41B1      	GND                 
          	               	AC78      	17B3      	NC_CPU0_HBM2_VIEWDIG0
          	               	AC80      	34B3      	UPI_CPU1_CPU0_P2P2_DN<17>
          	               	AC82      	34B3      	UPI_CPU1_CPU0_P2P2_DN<16>
          	               	AC84      	41B1      	GND                 
          	               	AC86      	31B2      	P5E_CPU0_PE4_TX_DN<6>
          	               	AC88      	41B1      	GND                 
          	               	AC90      	31B3      	P5E_CPU0_PE4_RX_DP<6>
          	               	AD2       	32B2      	UPI_CPU0_CPU1_P0P1_DN<7>
          	               	AD4       	41B1      	GND                 
          	               	AD6       	32B3      	UPI_CPU1_CPU0_P1P0_DP<7>
          	               	AD8       	41B1      	GND                 
          	               	AD10      	29B3      	P5E_CPU0_PE0_RX_DP<7>
          	               	AD12      	41B1      	GND                 
          	               	AD14      	29B2      	P5E_CPU0_PE0_TX_DP<6>
          	               	AD16      	41B1      	GND                 
          	               	AD18      	22B2      	M_C_CPU0_SB_DQS_DP<3>
          	               	AD20      	22B3      	M_C_CPU0_SB_DQ<24>  
          	               	AD22      	23B3      	M_D_CPU0_SB_DQ<21>  
          	               	AD24      	23B2      	M_D_CPU0_SB_DQS_DP<2>
          	               	AD26      	23B3      	M_D_CPU0_SB_DQ<16>  
          	               	AD28      	22B3      	M_C_CPU0_SB_DQ<13>  
          	               	AD30      	22B2      	M_C_CPU0_SB_DQS_DP<1>
          	               	AD32      	22A3      	M_C_CPU0_SB_DQ<8>   
          	               	AD34      	22A3      	M_C_CPU0_SB_DQ<5>   
          	               	AD36      	22B2      	M_C_CPU0_SB_DQS_DP<0>
          	               	AD38      	22A3      	M_C_CPU0_SB_DQ<0>   
          	               	AD40      	23A2      	M_D_CPU0_SB_CS_N<3> 
          	               	AD42      	41B1      	GND                 
          	               	AD44      	23B2      	M_D_CPU0_SB_CA<2>   
          	               	AD47      	22A2      	M_C_CPU0_SA_RSP<1>  
          	               	AD49      	22A3      	M_C_CPU0_CLK_DP<0>  
          	               	AD51      	23A2      	M_D_CPU0_SA_RSP<0>  
          	               	AD53      	22B3      	M_C_CPU0_SA_CB<5>   
          	               	AD55      	22B2      	M_C_CPU0_SA_DQS_DN<4>
          	               	AD57      	22B3      	M_C_CPU0_SA_CB<0>   
          	               	AD59      	22B3      	M_C_CPU0_SA_DQ<29>  
          	               	AD61      	22B2      	M_C_CPU0_SA_DQS_DP<3>
          	               	AD63      	22B3      	M_C_CPU0_SA_DQ<24>  
          	               	AD65      	22B3      	M_C_CPU0_SA_DQ<13>  
          	               	AD67      	22B2      	M_C_CPU0_SA_DQS_DP<1>
          	               	AD69      	22B3      	M_C_CPU0_SA_DQ<8>   
          	               	AD71      	23B3      	M_D_CPU0_SA_DQ<5>   
          	               	AD73      	23B2      	M_D_CPU0_SA_DQS_DP<0>
          	               	AD75      	23B3      	M_D_CPU0_SA_DQ<0>   
          	               	AD77      	17B3      	NC_CPU0_HBM2_VIEWDIG1
          	               	AD79      	41B1      	GND                 
          	               	AD81      	34B3      	UPI_CPU1_CPU0_P2P2_DP<16>
          	               	AD83      	41B1      	GND                 
          	               	AD85      	38B2      	PVCCFA_EHV_FIVRA_CPU0
          	               	AD87      	31B2      	P5E_CPU0_PE4_TX_DP<6>
          	               	AD89      	38B2      	PVCCFA_EHV_FIVRA_CPU0
          	               	AD91      	31B3      	P5E_CPU0_PE4_RX_DN<6>
          	               	AE1       	32B2      	UPI_CPU0_CPU1_P0P1_DP<8>
          	               	AE3       	37A1      	PVCCFA_EHV_CPU0     
          	               	AE5       	32B3      	UPI_CPU1_CPU0_P1P0_DN<7>
          	               	AE7       	38B2      	PVCCFA_EHV_FIVRA_CPU0
          	               	AE9       	29B3      	P5E_CPU0_PE0_RX_DN<7>
          	               	AE11      	38B2      	PVCCFA_EHV_FIVRA_CPU0
          	               	AE13      	29B2      	P5E_CPU0_PE0_TX_DN<6>
          	               	AE15      	38B2      	PVCCFA_EHV_FIVRA_CPU0
          	               	AE17      	41B1      	GND                 
          	               	AE19      	41B1      	GND                 
          	               	AE21      	41B1      	GND                 
          	               	AE23      	41B1      	GND                 
          	               	AE25      	41B1      	GND                 
          	               	AE27      	41B1      	GND                 
          	               	AE29      	41B1      	GND                 
          	               	AE31      	41B1      	GND                 
          	               	AE33      	41B1      	GND                 
          	               	AE35      	41B1      	GND                 
          	               	AE37      	41B1      	GND                 
          	               	AE39      	41B1      	GND                 
          	               	AE41      	41B1      	GND                 
          	               	AE43      	41B1      	GND                 
          	               	AE45      	41B1      	GND                 
          	               	AE48      	41B1      	GND                 
          	               	AE50      	41B1      	GND                 
          	               	AE52      	41B1      	GND                 
          	               	AE54      	41B1      	GND                 
          	               	AE56      	41B1      	GND                 
          	               	AE58      	41B1      	GND                 
          	               	AE60      	41B1      	GND                 
          	               	AE62      	41B1      	GND                 
          	               	AE64      	41B1      	GND                 
          	               	AE66      	41B1      	GND                 
          	               	AE68      	41A2      	GND                 
          	               	AE70      	41A2      	GND                 
          	               	AE72      	41A2      	GND                 
          	               	AE74      	41A2      	GND                 
          	               	AE76      	41A2      	GND                 
          	               	AE78      	41A2      	GND                 
          	               	AE80      	34B3      	UPI_CPU1_CPU0_P2P2_DP<17>
          	               	AE82      	34B3      	UPI_CPU1_CPU0_P2P2_DP<14>
          	               	AE84      	41A2      	GND                 
          	               	AE86      	31B2      	P5E_CPU0_PE4_TX_DN<7>
          	               	AE88      	41A2      	GND                 
          	               	AE90      	31B3      	P5E_CPU0_PE4_RX_DP<7>
          	               	AF2       	32B2      	UPI_CPU0_CPU1_P0P1_DN<8>
          	               	AF4       	41A2      	GND                 
          	               	AF6       	32B3      	UPI_CPU1_CPU0_P1P0_DN<8>
          	               	AF8       	41A2      	GND                 
          	               	AF10      	29B3      	P5E_CPU0_PE0_RX_DN<8>
          	               	AF12      	41A2      	GND                 
          	               	AF14      	29B2      	P5E_CPU0_PE0_TX_DN<7>
          	               	AF16      	41A2      	GND                 
          	               	AF18      	22B2      	M_C_CPU0_SB_DQS_DN<8>
          	               	AF20      	22B3      	M_C_CPU0_SB_DQ<26>  
          	               	AF22      	23B3      	M_D_CPU0_SB_DQ<23>  
          	               	AF24      	23B2      	M_D_CPU0_SB_DQS_DN<7>
          	               	AF26      	23B3      	M_D_CPU0_SB_DQ<18>  
          	               	AF28      	22B3      	M_C_CPU0_SB_DQ<15>  
          	               	AF30      	22B2      	M_C_CPU0_SB_DQS_DN<6>
          	               	AF32      	22A3      	M_C_CPU0_SB_DQ<10>  
          	               	AF34      	22A3      	M_C_CPU0_SB_DQ<7>   
          	               	AF36      	22B2      	M_C_CPU0_SB_DQS_DN<5>
          	               	AF38      	22A3      	M_C_CPU0_SB_DQ<2>   
          	               	AF40      	23A2      	M_D_CPU0_SB_CS_N<2> 
          	               	AF42      	41A2      	GND                 
          	               	AF44      	23B2      	M_D_CPU0_SB_CA<3>   
          	               	AF47      	22A2      	M_C_CPU0_SB_RSP<1>  
          	               	AF49      	22A3      	M_C_CPU0_CLK_DN<1>  
          	               	AF51      	23A2      	M_D_CPU0_SB_RSP<0>  
          	               	AF53      	22B3      	M_C_CPU0_SA_CB<7>   
          	               	AF55      	22B2      	M_C_CPU0_SA_DQS_DP<9>
          	               	AF57      	22B3      	M_C_CPU0_SA_CB<2>   
          	               	AF59      	22B3      	M_C_CPU0_SA_DQ<31>  
          	               	AF61      	22B2      	M_C_CPU0_SA_DQS_DN<8>
          	               	AF63      	22B3      	M_C_CPU0_SA_DQ<26>  
          	               	AF65      	22B3      	M_C_CPU0_SA_DQ<15>  
          	               	AF67      	22B2      	M_C_CPU0_SA_DQS_DP<6>
          	               	AF69      	22B3      	M_C_CPU0_SA_DQ<10>  
          	               	AF71      	23B3      	M_D_CPU0_SA_DQ<7>   
          	               	AF73      	23B2      	M_D_CPU0_SA_DQS_DP<5>
          	               	AF75      	23B3      	M_D_CPU0_SA_DQ<2>   
          	               	AF77      	38B2      	PVCCFA_EHV_FIVRA_CPU0
          	               	AF79      	34B3      	UPI_CPU1_CPU0_P2P2_DP<15>
          	               	AF81      	41A2      	GND                 
          	               	AF83      	34B3      	UPI_CPU1_CPU0_P2P2_DN<14>
          	               	AF85      	31B2      	P5E_CPU0_PE4_TX_DP<7>
          	               	AF87      	41A2      	GND                 
          	               	AF89      	31B3      	P5E_CPU0_PE4_RX_DN<7>
          	               	AF91      	41A2      	GND                 
          	               	AG1       	41A2      	GND                 
          	               	AG3       	32B2      	UPI_CPU0_CPU1_P0P1_DP<9>
          	               	AG5       	41A2      	GND                 
          	               	AG7       	32B3      	UPI_CPU1_CPU0_P1P0_DP<8>
          	               	AG9       	41A2      	GND                 
          	               	AG11      	29B3      	P5E_CPU0_PE0_RX_DP<8>
          	               	AG13      	41A2      	GND                 
          	               	AG15      	29B2      	P5E_CPU0_PE0_TX_DP<7>
          	               	AG17      	22B3      	M_C_CPU0_SB_DQ<29>  
          	               	AG19      	22B3      	M_C_CPU0_SB_DQ<27>  
          	               	AG21      	41A2      	GND                 
          	               	AG23      	23B3      	M_D_CPU0_SB_DQ<22>  
          	               	AG25      	23B3      	M_D_CPU0_SB_DQ<19>  
          	               	AG27      	41A2      	GND                 
          	               	AG29      	22B3      	M_C_CPU0_SB_DQ<14>  
          	               	AG31      	22B3      	M_C_CPU0_SB_DQ<11>  
          	               	AG33      	41B2      	GND                 
          	               	AG35      	22A3      	M_C_CPU0_SB_DQ<6>   
          	               	AG37      	22A3      	M_C_CPU0_SB_DQ<3>   
          	               	AG39      	41B2      	GND                 
          	               	AG41      	23A2      	M_D_CPU0_SB_CS_N<1> 
          	               	AG43      	23B2      	M_D_CPU0_SB_CA<5>   
          	               	AG45      	41B2      	GND                 
          	               	AG48      	22A2      	M_C_CPU0_SB_RSP<0>  
          	               	AG50      	23A2      	M_D_CPU0_SB_RSP<1>  
          	               	AG52      	41B2      	GND                 
          	               	AG54      	22B3      	M_C_CPU0_SA_CB<6>   
          	               	AG56      	22B3      	M_C_CPU0_SA_CB<3>   
          	               	AG58      	41B2      	GND                 
          	               	AG60      	22B3      	M_C_CPU0_SA_DQ<30>  
          	               	AG62      	22B3      	M_C_CPU0_SA_DQ<27>  
          	               	AG64      	41B2      	GND                 
          	               	AG66      	22B3      	M_C_CPU0_SA_DQ<14>  
          	               	AG68      	22B3      	M_C_CPU0_SA_DQ<11>  
          	               	AG70      	41B2      	GND                 
          	               	AG72      	23B3      	M_D_CPU0_SA_DQ<6>   
          	               	AG74      	23B3      	M_D_CPU0_SA_DQ<3>   
          	               	AG76      	41B2      	GND                 
          	               	AG78      	38B2      	PVCCFA_EHV_FIVRA_CPU0
          	               	AG80      	34B3      	UPI_CPU1_CPU0_P2P2_DN<15>
          	               	AG82      	34B3      	UPI_CPU1_CPU0_P2P2_DP<12>
          	               	AG84      	41B2      	GND                 
          	               	AG86      	31B2      	P5E_CPU0_PE4_TX_DN<8>
          	               	AG88      	41B2      	GND                 
          	               	AG90      	31B3      	P5E_CPU0_PE4_RX_DP<8>
          	               	AH2       	32B2      	UPI_CPU0_CPU1_P0P1_DN<9>
          	               	AH4       	41B2      	GND                 
          	               	AH6       	32B3      	UPI_CPU1_CPU0_P1P0_DN<9>
          	               	AH8       	41B2      	GND                 
          	               	AH10      	29B3      	P5E_CPU0_PE0_RX_DP<9>
          	               	AH12      	41B2      	GND                 
          	               	AH14      	29B2      	P5E_CPU0_PE0_TX_DP<8>
          	               	AH16      	41B2      	GND                 
          	               	AH18      	22B2      	M_C_CPU0_SB_DQS_DP<8>
          	               	AH20      	41B2      	GND                 
          	               	AH22      	41B2      	GND                 
          	               	AH24      	23B2      	M_D_CPU0_SB_DQS_DP<7>
          	               	AH26      	41B2      	GND                 
          	               	AH28      	41B2      	GND                 
          	               	AH30      	22B2      	M_C_CPU0_SB_DQS_DP<6>
          	               	AH32      	41B2      	GND                 
          	               	AH34      	41B2      	GND                 
          	               	AH36      	22B2      	M_C_CPU0_SB_DQS_DP<5>
          	               	AH38      	41B2      	GND                 
          	               	AH40      	41B2      	GND                 
          	               	AH42      	23A2      	M_D_CPU0_SB_PAR     
          	               	AH44      	41B2      	GND                 
          	               	AH47      	41B2      	GND                 
          	               	AH49      	22A3      	M_C_CPU0_CLK_DP<1>  
          	               	AH51      	41B2      	GND                 
          	               	AH53      	41B2      	GND                 
          	               	AH55      	22B2      	M_C_CPU0_SA_DQS_DN<9>
          	               	AH57      	41B2      	GND                 
          	               	AH59      	41B2      	GND                 
          	               	AH61      	22B2      	M_C_CPU0_SA_DQS_DP<8>
          	               	AH63      	41B2      	GND                 
          	               	AH65      	41B2      	GND                 
          	               	AH67      	22B2      	M_C_CPU0_SA_DQS_DN<6>
          	               	AH69      	41B2      	GND                 
          	               	AH71      	41B2      	GND                 
          	               	AH73      	23B2      	M_D_CPU0_SA_DQS_DN<5>
          	               	AH75      	41B2      	GND                 
          	               	AH77      	41B2      	GND                 
          	               	AH79      	41B2      	GND                 
          	               	AH81      	34B3      	UPI_CPU1_CPU0_P2P2_DP<13>
          	               	AH83      	41B2      	GND                 
          	               	AH85      	38B2      	PVCCFA_EHV_FIVRA_CPU0
          	               	AH87      	31B2      	P5E_CPU0_PE4_TX_DP<8>
          	               	AH89      	38B2      	PVCCFA_EHV_FIVRA_CPU0
          	               	AH91      	31B3      	P5E_CPU0_PE4_RX_DN<8>
          	               	AJ1       	32B2      	UPI_CPU0_CPU1_P0P1_DP<10>
          	               	AJ3       	37A1      	PVCCFA_EHV_CPU0     
          	               	AJ5       	32B3      	UPI_CPU1_CPU0_P1P0_DP<9>
          	               	AJ7       	38B2      	PVCCFA_EHV_FIVRA_CPU0
          	               	AJ9       	29B3      	P5E_CPU0_PE0_RX_DN<9>
          	               	AJ11      	38B2      	PVCCFA_EHV_FIVRA_CPU0
          	               	AJ13      	29B2      	P5E_CPU0_PE0_TX_DN<8>
          	               	AJ15      	38B2      	PVCCFA_EHV_FIVRA_CPU0
          	               	AJ17      	22B3      	M_C_CPU0_SB_DQ<31>  
          	               	AJ19      	41B2      	GND                 
          	               	AJ21      	23B2      	M_D_CPU0_SB_DQS_DN<3>
          	               	AJ23      	41B2      	GND                 
          	               	AJ25      	41B2      	GND                 
          	               	AJ27      	23B2      	M_D_CPU0_SB_DQS_DN<1>
          	               	AJ29      	41B2      	GND                 
          	               	AJ31      	41B2      	GND                 
          	               	AJ33      	23B2      	M_D_CPU0_SB_DQS_DN<0>
          	               	AJ35      	41B2      	GND                 
          	               	AJ37      	41B2      	GND                 
          	               	AJ39      	23B2      	M_D_CPU0_SB_DQS_DN<9>
          	               	AJ41      	41B2      	GND                 
          	               	AJ43      	41B2      	GND                 
          	               	AJ45      	23A3      	M_D_CPU0_CLK_DN<0>  
          	               	AJ48      	41B2      	GND                 
          	               	AJ50      	41B2      	GND                 
          	               	AJ52      	23B2      	M_D_CPU0_SA_CA<0>   
          	               	AJ54      	41B2      	GND                 
          	               	AJ56      	41B2      	GND                 
          	               	AJ58      	23B2      	M_D_CPU0_SA_DQS_DN<4>
          	               	AJ60      	41B2      	GND                 
          	               	AJ62      	41B2      	GND                 
          	               	AJ64      	23B2      	M_D_CPU0_SA_DQS_DN<3>
          	               	AJ66      	41B2      	GND                 
          	               	AJ68      	41B2      	GND                 
          	               	AJ70      	23B2      	M_D_CPU0_SA_DQS_DN<2>
          	               	AJ72      	41B2      	GND                 
          	               	AJ74      	41B2      	GND                 
          	               	AJ76      	23B2      	M_D_CPU0_SA_DQS_DN<1>
          	               	AJ78      	41B2      	GND                 
          	               	AJ80      	34B3      	UPI_CPU1_CPU0_P2P2_DN<13>
          	               	AJ82      	34B3      	UPI_CPU1_CPU0_P2P2_DN<12>
          	               	AJ84      	41B2      	GND                 
          	               	AJ86      	31B2      	P5E_CPU0_PE4_TX_DN<9>
          	               	AJ88      	41B2      	GND                 
          	               	AJ90      	31B3      	P5E_CPU0_PE4_RX_DP<9>
          	               	AK2       	32B2      	UPI_CPU0_CPU1_P0P1_DN<10>
          	               	AK4       	41A2      	GND                 
          	               	AK6       	32B3      	UPI_CPU1_CPU0_P1P0_DP<10>
          	               	AK8       	41A2      	GND                 
          	               	AK10      	29B3      	P5E_CPU0_PE0_RX_DN<10>
          	               	AK12      	41A2      	GND                 
          	               	AK14      	29B2      	P5E_CPU0_PE0_TX_DN<9>
          	               	AK16      	41A2      	GND                 
          	               	AK18      	41A2      	GND                 
          	               	AK20      	23B3      	M_D_CPU0_SB_DQ<28>  
          	               	AK22      	23B3      	M_D_CPU0_SB_DQ<25>  
          	               	AK24      	41A2      	GND                 
          	               	AK26      	23B3      	M_D_CPU0_SB_DQ<12>  
          	               	AK28      	23A3      	M_D_CPU0_SB_DQ<9>   
          	               	AK30      	41A2      	GND                 
          	               	AK32      	23A3      	M_D_CPU0_SB_DQ<4>   
          	               	AK34      	23A3      	M_D_CPU0_SB_DQ<1>   
          	               	AK36      	41A2      	GND                 
          	               	AK38      	23A3      	M_D_CPU0_SB_CB<0>   
          	               	AK40      	23A3      	M_D_CPU0_SB_CB<5>   
          	               	AK42      	41A2      	GND                 
          	               	AK44      	23A2      	M_D_CPU0_SB_CA<0>   
          	               	AK47      	21A2      	M_B_CPU0_SA_RSP<1>  
          	               	AK49      	41A2      	GND                 
          	               	AK51      	23B2      	M_D_CPU0_SA_CA<2>   
          	               	AK53      	23A2      	M_D_CPU0_SA_CS_N<1> 
          	               	AK55      	41A2      	GND                 
          	               	AK57      	23B3      	M_D_CPU0_SA_CB<4>   
          	               	AK59      	23B3      	M_D_CPU0_SA_CB<1>   
          	               	AK61      	41A2      	GND                 
          	               	AK63      	23B3      	M_D_CPU0_SA_DQ<28>  
          	               	AK65      	23B3      	M_D_CPU0_SA_DQ<25>  
          	               	AK67      	41A2      	GND                 
          	               	AK69      	23B3      	M_D_CPU0_SA_DQ<20>  
          	               	AK71      	23B3      	M_D_CPU0_SA_DQ<17>  
          	               	AK73      	41A2      	GND                 
          	               	AK75      	23B3      	M_D_CPU0_SA_DQ<12>  
          	               	AK77      	23B3      	M_D_CPU0_SA_DQ<9>   
          	               	AK79      	41A2      	GND                 
          	               	AK81      	41A2      	GND                 
          	               	AK83      	41A2      	GND                 
          	               	AK85      	31B2      	P5E_CPU0_PE4_TX_DP<9>
          	               	AK87      	41A2      	GND                 
          	               	AK89      	31B3      	P5E_CPU0_PE4_RX_DN<9>
          	               	AK91      	41A2      	GND                 
          	               	AL1       	41A2      	GND                 
          	               	AL3       	32B2      	UPI_CPU0_CPU1_P0P1_DP<11>
          	               	AL5       	41A2      	GND                 
          	               	AL7       	32B3      	UPI_CPU1_CPU0_P1P0_DN<10>
          	               	AL9       	41A2      	GND                 
          	               	AL11      	29B3      	P5E_CPU0_PE0_RX_DP<10>
          	               	AL13      	41B2      	GND                 
          	               	AL15      	29B2      	P5E_CPU0_PE0_TX_DP<9>
          	               	AL17      	41B2      	GND                 
          	               	AL19      	23B3      	M_D_CPU0_SB_DQ<29>  
          	               	AL21      	23B2      	M_D_CPU0_SB_DQS_DP<3>
          	               	AL23      	23B3      	M_D_CPU0_SB_DQ<24>  
          	               	AL25      	23B3      	M_D_CPU0_SB_DQ<13>  
          	               	AL27      	23B2      	M_D_CPU0_SB_DQS_DP<1>
          	               	AL29      	23A3      	M_D_CPU0_SB_DQ<8>   
          	               	AL31      	23A3      	M_D_CPU0_SB_DQ<5>   
          	               	AL33      	23B2      	M_D_CPU0_SB_DQS_DP<0>
          	               	AL35      	23A3      	M_D_CPU0_SB_DQ<0>   
          	               	AL37      	23A3      	M_D_CPU0_SB_CB<1>   
          	               	AL39      	23B2      	M_D_CPU0_SB_DQS_DP<9>
          	               	AL41      	23A3      	M_D_CPU0_SB_CB<4>   
          	               	AL43      	23A2      	M_D_CPU0_SB_CA<1>   
          	               	AL45      	23A3      	M_D_CPU0_CLK_DP<0>  
          	               	AL48      	21A2      	M_B_CPU0_SA_RSP<0>  
          	               	AL50      	23B2      	M_D_CPU0_SA_CA<4>   
          	               	AL52      	41B2      	GND                 
          	               	AL54      	23A2      	M_D_CPU0_SA_CS_N<0> 
          	               	AL56      	23B3      	M_D_CPU0_SA_CB<5>   
          	               	AL58      	23B2      	M_D_CPU0_SA_DQS_DP<4>
          	               	AL60      	23B3      	M_D_CPU0_SA_CB<0>   
          	               	AL62      	23B3      	M_D_CPU0_SA_DQ<29>  
          	               	AL64      	23B2      	M_D_CPU0_SA_DQS_DP<3>
          	               	AL66      	23B3      	M_D_CPU0_SA_DQ<24>  
          	               	AL68      	23B3      	M_D_CPU0_SA_DQ<21>  
          	               	AL70      	23B2      	M_D_CPU0_SA_DQS_DP<2>
          	               	AL72      	23B3      	M_D_CPU0_SA_DQ<16>  
          	               	AL74      	23B3      	M_D_CPU0_SA_DQ<13>  
          	               	AL76      	23B2      	M_D_CPU0_SA_DQS_DP<1>
          	               	AL78      	23B3      	M_D_CPU0_SA_DQ<8>   
          	               	AL80      	41B2      	GND                 
          	               	AL82      	41B2      	GND                 
          	               	AL84      	41B2      	GND                 
          	               	AL86      	31B2      	P5E_CPU0_PE4_TX_DN<10>
          	               	AL88      	41B2      	GND                 
          	               	AL90      	31B3      	P5E_CPU0_PE4_RX_DP<10>
          	               	AM2       	32B2      	UPI_CPU0_CPU1_P0P1_DN<11>
          	               	AM4       	41B2      	GND                 
          	               	AM6       	32B3      	UPI_CPU1_CPU0_P1P0_DN<11>
          	               	AM8       	41B2      	GND                 
          	               	AM10      	29B3      	P5E_CPU0_PE0_RX_DN<11>
          	               	AM12      	41B2      	GND                 
          	               	AM14      	29B2      	P5E_CPU0_PE0_TX_DP<10>
          	               	AM16      	41B2      	GND                 
          	               	AM18      	41B2      	GND                 
          	               	AM20      	41B2      	GND                 
          	               	AM22      	41B2      	GND                 
          	               	AM24      	41B2      	GND                 
          	               	AM26      	41B2      	GND                 
          	               	AM28      	41B2      	GND                 
          	               	AM30      	41B2      	GND                 
          	               	AM32      	41B2      	GND                 
          	               	AM34      	41B2      	GND                 
          	               	AM36      	41B2      	GND                 
          	               	AM38      	41B2      	GND                 
          	               	AM40      	41B2      	GND                 
          	               	AM42      	41B2      	GND                 
          	               	AM44      	41B2      	GND                 
          	               	AM47      	41B2      	GND                 
          	               	AM49      	41B2      	GND                 
          	               	AM51      	41B2      	GND                 
          	               	AM53      	41B2      	GND                 
          	               	AM55      	41B2      	GND                 
          	               	AM57      	41B2      	GND                 
          	               	AM59      	41B2      	GND                 
          	               	AM61      	41B2      	GND                 
          	               	AM63      	41B2      	GND                 
          	               	AM65      	41B2      	GND                 
          	               	AM67      	41B2      	GND                 
          	               	AM69      	41B2      	GND                 
          	               	AM71      	41B2      	GND                 
          	               	AM73      	41B2      	GND                 
          	               	AM75      	41B2      	GND                 
          	               	AM77      	41B2      	GND                 
          	               	AM79      	38B2      	PVCCFA_EHV_FIVRA_CPU0
          	               	AM81      	34B2      	UPI_CPU0_CPU1_P2P2_DN<11>
          	               	AM83      	34B2      	UPI_CPU0_CPU1_P2P2_DP<10>
          	               	AM85      	38B2      	PVCCFA_EHV_FIVRA_CPU0
          	               	AM87      	31B2      	P5E_CPU0_PE4_TX_DP<10>
          	               	AM89      	38B2      	PVCCFA_EHV_FIVRA_CPU0
          	               	AM91      	31B3      	P5E_CPU0_PE4_RX_DN<10>
          	               	AN1       	32B2      	UPI_CPU0_CPU1_P0P1_DN<12>
          	               	AN3       	37A1      	PVCCFA_EHV_CPU0     
          	               	AN5       	32B3      	UPI_CPU1_CPU0_P1P0_DP<11>
          	               	AN7       	38B2      	PVCCFA_EHV_FIVRA_CPU0
          	               	AN9       	29B3      	P5E_CPU0_PE0_RX_DP<11>
          	               	AN11      	38B2      	PVCCFA_EHV_FIVRA_CPU0
          	               	AN13      	29B2      	P5E_CPU0_PE0_TX_DN<10>
          	               	AN15      	38B2      	PVCCFA_EHV_FIVRA_CPU0
          	               	AN17      	19B3      	NC_CPU0_UPI0_APROBE<0>
          	               	AN19      	23B3      	M_D_CPU0_SB_DQ<31>  
          	               	AN21      	23B2      	M_D_CPU0_SB_DQS_DN<8>
          	               	AN23      	23B3      	M_D_CPU0_SB_DQ<26>  
          	               	AN25      	23B3      	M_D_CPU0_SB_DQ<15>  
          	               	AN27      	23B2      	M_D_CPU0_SB_DQS_DN<6>
          	               	AN29      	23A3      	M_D_CPU0_SB_DQ<10>  
          	               	AN31      	23A3      	M_D_CPU0_SB_DQ<7>   
          	               	AN33      	23B2      	M_D_CPU0_SB_DQS_DN<5>
          	               	AN35      	23A3      	M_D_CPU0_SB_DQ<2>   
          	               	AN37      	23A3      	M_D_CPU0_SB_CB<3>   
          	               	AN39      	23B2      	M_D_CPU0_SB_DQS_DP<4>
          	               	AN41      	23A3      	M_D_CPU0_SB_CB<6>   
          	               	AN43      	23B2      	M_D_CPU0_SA_CA<6>   
          	               	AN45      	23A3      	M_D_CPU0_CLK_DN<1>  
          	               	AN48      	21A2      	M_B_CPU0_SB_RSP<0>  
          	               	AN50      	23B2      	M_D_CPU0_SA_CA<5>   
          	               	AN52      	41B2      	GND                 
          	               	AN54      	23A2      	M_D_CPU0_SA_CS_N<2> 
          	               	AN56      	23B3      	M_D_CPU0_SA_CB<7>   
          	               	AN58      	23B2      	M_D_CPU0_SA_DQS_DN<9>
          	               	AN60      	23B3      	M_D_CPU0_SA_CB<2>   
          	               	AN62      	23B3      	M_D_CPU0_SA_DQ<31>  
          	               	AN64      	23B2      	M_D_CPU0_SA_DQS_DN<8>
          	               	AN66      	23B3      	M_D_CPU0_SA_DQ<26>  
          	               	AN68      	23B3      	M_D_CPU0_SA_DQ<23>  
          	               	AN70      	23B2      	M_D_CPU0_SA_DQS_DN<7>
          	               	AN72      	23B3      	M_D_CPU0_SA_DQ<18>  
          	               	AN74      	23B3      	M_D_CPU0_SA_DQ<15>  
          	               	AN76      	23B2      	M_D_CPU0_SA_DQS_DN<6>
          	               	AN78      	23B3      	M_D_CPU0_SA_DQ<10>  
          	               	AN80      	38B2      	PVCCFA_EHV_FIVRA_CPU0
          	               	AN82      	34B2      	UPI_CPU0_CPU1_P2P2_DN<10>
          	               	AN84      	41B2      	GND                 
          	               	AN86      	31B2      	P5E_CPU0_PE4_TX_DP<11>
          	               	AN88      	41B2      	GND                 
          	               	AN90      	31B3      	P5E_CPU0_PE4_RX_DP<11>
          	               	AP2       	32B2      	UPI_CPU0_CPU1_P0P1_DP<12>
          	               	AP4       	41B2      	GND                 
          	               	AP6       	32B3      	UPI_CPU1_CPU0_P1P0_DP<12>
          	               	AP8       	41B2      	GND                 
          	               	AP10      	29B3      	P5E_CPU0_PE0_RX_DN<12>
          	               	AP12      	41B2      	GND                 
          	               	AP14      	29B2      	P5E_CPU0_PE0_TX_DN<11>
          	               	AP16      	41B2      	GND                 
          	               	AP18      	41B2      	GND                 
          	               	AP20      	23B3      	M_D_CPU0_SB_DQ<30>  
          	               	AP22      	23B3      	M_D_CPU0_SB_DQ<27>  
          	               	AP24      	41B2      	GND                 
          	               	AP26      	23B3      	M_D_CPU0_SB_DQ<14>  
          	               	AP28      	23B3      	M_D_CPU0_SB_DQ<11>  
          	               	AP30      	41B2      	GND                 
          	               	AP32      	23A3      	M_D_CPU0_SB_DQ<6>   
          	               	AP34      	23A3      	M_D_CPU0_SB_DQ<3>   
          	               	AP36      	41B2      	GND                 
          	               	AP38      	23A3      	M_D_CPU0_SB_CB<2>   
          	               	AP40      	23A3      	M_D_CPU0_SB_CB<7>   
          	               	AP42      	41B2      	GND                 
          	               	AP44      	23B2      	M_D_CPU0_SA_PAR     
          	               	AP47      	21A2      	M_B_CPU0_SB_RSP<1>  
          	               	AP49      	41B2      	GND                 
          	               	AP51      	23B2      	M_D_CPU0_SA_CA<3>   
          	               	AP53      	23A2      	M_D_CPU0_SA_CS_N<3> 
          	               	AP55      	41B2      	GND                 
          	               	AP57      	23B3      	M_D_CPU0_SA_CB<6>   
          	               	AP59      	23B3      	M_D_CPU0_SA_CB<3>   
          	               	AP61      	41B2      	GND                 
          	               	AP63      	23B3      	M_D_CPU0_SA_DQ<30>  
          	               	AP65      	23B3      	M_D_CPU0_SA_DQ<27>  
          	               	AP67      	41B2      	GND                 
          	               	AP69      	23B3      	M_D_CPU0_SA_DQ<22>  
          	               	AP71      	23B3      	M_D_CPU0_SA_DQ<19>  
          	               	AP73      	41B2      	GND                 
          	               	AP75      	23B3      	M_D_CPU0_SA_DQ<14>  
          	               	AP77      	23B3      	M_D_CPU0_SA_DQ<11>  
          	               	AP79      	41A3      	GND                 
          	               	AP81      	34B2      	UPI_CPU0_CPU1_P2P2_DP<11>
          	               	AP83      	41A3      	GND                 
          	               	AP85      	31B2      	P5E_CPU0_PE4_TX_DN<11>
          	               	AP87      	41A3      	GND                 
          	               	AP89      	31B3      	P5E_CPU0_PE4_RX_DN<11>
          	               	AP91      	41A3      	GND                 
          	               	AR1       	41A3      	GND                 
          	               	AR3       	32B2      	UPI_CPU0_CPU1_P0P1_DN<13>
          	               	AR5       	41A3      	GND                 
          	               	AR7       	32B3      	UPI_CPU1_CPU0_P1P0_DN<12>
          	               	AR9       	41A3      	GND                 
          	               	AR11      	29B3      	P5E_CPU0_PE0_RX_DP<12>
          	               	AR13      	41A3      	GND                 
          	               	AR15      	29B2      	P5E_CPU0_PE0_TX_DP<11>
          	               	AR17      	19B3      	NC_CPU0_UPI0_APROBE<1>
          	               	AR19      	41A3      	GND                 
          	               	AR21      	23B2      	M_D_CPU0_SB_DQS_DP<8>
          	               	AR23      	41A3      	GND                 
          	               	AR25      	41A3      	GND                 
          	               	AR27      	23B2      	M_D_CPU0_SB_DQS_DP<6>
          	               	AR29      	41A3      	GND                 
          	               	AR31      	41A3      	GND                 
          	               	AR33      	23B2      	M_D_CPU0_SB_DQS_DP<5>
          	               	AR35      	41A3      	GND                 
          	               	AR37      	41A3      	GND                 
          	               	AR39      	23B2      	M_D_CPU0_SB_DQS_DN<4>
          	               	AR41      	41A3      	GND                 
          	               	AR43      	41A3      	GND                 
          	               	AR45      	23A3      	M_D_CPU0_CLK_DP<1>  
          	               	AR48      	41A3      	GND                 
          	               	AR50      	41A3      	GND                 
          	               	AR52      	23B2      	M_D_CPU0_SA_CA<1>   
          	               	AR54      	41A3      	GND                 
          	               	AR56      	41A3      	GND                 
          	               	AR58      	23B2      	M_D_CPU0_SA_DQS_DP<9>
          	               	AR60      	41A3      	GND                 
          	               	AR62      	41B3      	GND                 
          	               	AR64      	23B2      	M_D_CPU0_SA_DQS_DP<8>
          	               	AR66      	41B3      	GND                 
          	               	AR68      	41B3      	GND                 
          	               	AR70      	23B2      	M_D_CPU0_SA_DQS_DP<7>
          	               	AR72      	41B3      	GND                 
          	               	AR74      	41B3      	GND                 
          	               	AR76      	23B2      	M_D_CPU0_SA_DQS_DP<6>
          	               	AR78      	41B3      	GND                 
          	               	AR80      	34B2      	UPI_CPU0_CPU1_P2P2_DN<9>
          	               	AR82      	41B3      	GND                 
          	               	AR84      	41B3      	GND                 
          	               	AR86      	31B2      	P5E_CPU0_PE4_TX_DN<12>
          	               	AR88      	41B3      	GND                 
          	               	AR90      	31B3      	P5E_CPU0_PE4_RX_DP<12>
          	               	AT2       	32B2      	UPI_CPU0_CPU1_P0P1_DP<13>
          	               	AT4       	41B3      	GND                 
          	               	AT6       	32B3      	UPI_CPU1_CPU0_P1P0_DN<13>
          	               	AT8       	41B3      	GND                 
          	               	AT10      	29B3      	P5E_CPU0_PE0_RX_DP<13>
          	               	AT12      	41B3      	GND                 
          	               	AT14      	29B2      	P5E_CPU0_PE0_TX_DP<12>
          	               	AT16      	41B3      	GND                 
          	               	AT18      	13B2      	PD_CPU0_BIST_ENABLE 
          	               	AT20      	41B3      	GND                 
          	               	AT22      	41B3      	GND                 
          	               	AT24      	14B2      	NC_CPU0_VIEWPIN_DIE00<1>
          	               	AT26      	41B3      	GND                 
          	               	AT28      	41B3      	GND                 
          	               	AT30      	13B3      	CLK_100M_DB2000_CPU0_BCLK0_DN
          	               	AT32      	41B3      	GND                 
          	               	AT34      	41B3      	GND                 
          	               	AT36      	37B2      	PVCCD_HV_CPU0       
          	               	AT38      	41B3      	GND                 
          	               	AT40      	41B3      	GND                 
          	               	AT42      	20A2      	M_A_CPU0_SA_RSP<0>  
          	               	AT44      	41B3      	GND                 
          	               	AT47      	22A2      	M_C_CPU0_ALERT_N    
          	               	AT49      	20A2      	M_A_CPU0_ALERT_N    
          	               	AT51      	41B3      	GND                 
          	               	AT53      	41B3      	GND                 
          	               	AT55      	37B2      	PVCCD_HV_CPU0       
          	               	AT57      	41B3      	GND                 
          	               	AT59      	41B3      	GND                 
          	               	AT61      	37A1      	PVCCFA_EHV_CPU0     
          	               	AT63      	41B3      	GND                 
          	               	AT65      	41B3      	GND                 
          	               	AT67      	19B3      	NC_CPU0_UPI2_APROBE<1>
          	               	AT69      	41B3      	GND                 
          	               	AT71      	41B3      	GND                 
          	               	AT73      	38B2      	PVCCFA_EHV_FIVRA_CPU0
          	               	AT75      	41B3      	GND                 
          	               	AT77      	41B3      	GND                 
          	               	AT79      	41B3      	GND                 
          	               	AT81      	34B2      	UPI_CPU0_CPU1_P2P2_DP<9>
          	               	AT83      	34B2      	UPI_CPU0_CPU1_P2P2_DN<8>
          	               	AT85      	16B4      	VSENSE_PVCCFA_EHV_FIVRA_CPU0_DN
          	               	AT87      	31B2      	P5E_CPU0_PE4_TX_DP<12>
          	               	AT89      	38B2      	PVCCFA_EHV_FIVRA_CPU0
          	               	AT91      	31B3      	P5E_CPU0_PE4_RX_DN<12>
          	               	AU1       	32B2      	UPI_CPU0_CPU1_P0P1_DN<14>
          	               	AU3       	37B2      	PVCCD_HV_CPU0       
          	               	AU5       	32B3      	UPI_CPU1_CPU0_P1P0_DP<13>
          	               	AU7       	37B2      	PVCCD_HV_CPU0       
          	               	AU9       	29B3      	P5E_CPU0_PE0_RX_DN<13>
          	               	AU11      	16B4      	VSENSE_PVCCFA_EHV_CPU0_DP
          	               	AU13      	29B2      	P5E_CPU0_PE0_TX_DN<12>
          	               	AU15      	38B2      	PVCCFA_EHV_FIVRA_CPU0
          	               	AU17      	13B2      	PU_CPU0_FRMAGENT    
          	               	AU19      	14B2      	H_CPU0_PROCHOT_LVC1_N
          	               	AU21      	14B2      	H_CPU0_MEMHOT_IN_LVC1_N
          	               	AU23      	13B2      	PU_CPU0_SAFE_MODE_BOOT
          	               	AU25      	14B2      	NC_CPU0_VIEWPIN_DIE00<2>
          	               	AU27      	41B3      	GND                 
          	               	AU29      	13B3      	CLK_100M_DB2000_CPU0_BCLK2_DN
          	               	AU31      	41B3      	GND                 
          	               	AU33      	16B4      	NC_CPU0_DDR23_VIEWDIG1
          	               	AU35      	37B2      	PVCCD_HV_CPU0       
          	               	AU37      	41B3      	GND                 
          	               	AU39      	41B3      	GND                 
          	               	AU41      	41B3      	GND                 
          	               	AU43      	20A2      	M_A_CPU0_SA_RSP<1>  
          	               	AU45      	41B3      	GND                 
          	               	AU48      	41B3      	GND                 
          	               	AU50      	13B2      	RST_CPU0_DRAM_AB_N  
          	               	AU52      	18B3      	TP_CPU0_SPARE5      
          	               	AU54      	37B2      	PVCCD_HV_CPU0       
          	               	AU56      	16B4      	NC_CPU0_DDR01_VIEWDIG1
          	               	AU58      	16B4      	NC_CPU0_DDR01_VIEWDIG0
          	               	AU60      	37A1      	PVCCFA_EHV_CPU0     
          	               	AU62      	15B4      	TP_SPI_IBL_CPU0_TPM_CLK
          	               	AU64      	15B4      	TP_ESPI_IBL_CPU0_IO2_LVC1
          	               	AU66      	19B2      	NC_CPU0_PE4_APROBE<1>
          	               	AU68      	19B3      	NC_CPU0_UPI2_APROBE<0>
          	               	AU70      	41B3      	GND                 
          	               	AU72      	41B3      	GND                 
          	               	AU74      	41B3      	GND                 
          	               	AU76      	41B3      	GND                 
          	               	AU78      	34B2      	UPI_CPU0_CPU1_P2P2_DN<12>
          	               	AU80      	41B3      	GND                 
          	               	AU82      	34B2      	UPI_CPU0_CPU1_P2P2_DP<7>
          	               	AU84      	41B3      	GND                 
          	               	AU86      	31B2      	P5E_CPU0_PE4_TX_DN<13>
          	               	AU88      	41B3      	GND                 
          	               	AU90      	31B3      	P5E_CPU0_PE4_RX_DP<13>
          	               	AV2       	32B2      	UPI_CPU0_CPU1_P0P1_DP<14>
          	               	AV4       	41B3      	GND                 
          	               	AV6       	32B3      	UPI_CPU1_CPU0_P1P0_DP<14>
          	               	AV8       	41B3      	GND                 
          	               	AV10      	29B3      	P5E_CPU0_PE0_RX_DN<14>
          	               	AV12      	41B3      	GND                 
          	               	AV14      	29B2      	P5E_CPU0_PE0_TX_DN<13>
          	               	AV16      	41B3      	GND                 
          	               	AV18      	14B2      	H_CPU0_NMI_LVC1_N   
          	               	AV20      	14B3      	PWRGD_CPU0_LVC1     
          	               	AV22      	13B3      	H_CPU0_PREQ_QS_GTL_R_N
          	               	AV24      	14B2      	H_CPU0_MEMTRIP_LVC1_R_N
          	               	AV26      	14B2      	NC_CPU0_VIEWPIN_DIE00<3>
          	               	AV28      	13B3      	CLK_100M_DB2000_CPU0_BCLK2_DP
          	               	AV30      	13B3      	CLK_100M_DB2000_CPU0_BCLK0_DP
          	               	AV32      	16B4      	NC_CPU0_DDR23_VIEWDIG0
          	               	AV34      	37B2      	PVCCD_HV_CPU0       
          	               	AV36      	37B2      	PVCCD_HV_CPU0       
          	               	AV38      	16B3      	NC_CPU0_THERMADC    
          	               	AV40      	16B3      	NC_CPU0_THERMADA    
          	               	AV42      	20A2      	M_A_CPU0_SB_RSP<1>  
          	               	AV44      	20A2      	M_A_CPU0_SB_RSP<0>  
          	               	AV47      	23A2      	M_D_CPU0_ALERT_N    
          	               	AV49      	21A2      	M_B_CPU0_ALERT_N    
          	               	AV51      	13B2      	RST_CPU0_DRAM_CD_N  
          	               	AV53      	37B2      	PVCCD_HV_CPU0       
          	               	AV55      	37B2      	PVCCD_HV_CPU0       
          	               	AV57      	14B2      	FM_CPU_FBRK_DEBUG_R_N
          	               	AV59      	14B2      	TP_EV_CPU0_EXT_BGREF
          	               	AV61      	37A1      	PVCCFA_EHV_CPU0     
          	               	AV63      	15B4      	TP_SPI_S3M_CPU0_CS1_LVC1_R_N
          	               	AV65      	17B2      	NC_CPU0_MDFI_DIE01_EW0
          	               	AV67      	19B2      	NC_CPU0_PE4_APROBE<0>
          	               	AV69      	15B2      	FM_S3M_CPU0_LVC1_GPIO_2
          	               	AV71      	15B2      	FM_S3M_CPU0_LVC1_GPIO_1
          	               	AV73      	34B3      	UPI_CPU1_CPU0_P2P2_DN<10>
          	               	AV75      	34B3      	UPI_CPU1_CPU0_P2P2_DN<7>
          	               	AV77      	41B3      	GND                 
          	               	AV79      	34B2      	UPI_CPU0_CPU1_P2P2_DP<12>
          	               	AV81      	34B2      	UPI_CPU0_CPU1_P2P2_DN<7>
          	               	AV83      	34B2      	UPI_CPU0_CPU1_P2P2_DP<8>
          	               	AV85      	31B2      	P5E_CPU0_PE4_TX_DP<13>
          	               	AV87      	41B3      	GND                 
          	               	AV89      	31B3      	P5E_CPU0_PE4_RX_DN<13>
          	               	AV91      	41B3      	GND                 
          	               	AW1       	41B3      	GND                 
          	               	AW3       	32B2      	UPI_CPU0_CPU1_P0P1_DN<15>
          	               	AW5       	41B3      	GND                 
          	               	AW7       	32B3      	UPI_CPU1_CPU0_P1P0_DN<14>
          	               	AW9       	41B3      	GND                 
          	               	AW11      	29B3      	P5E_CPU0_PE0_RX_DP<14>
          	               	AW13      	41B3      	GND                 
          	               	AW15      	29B2      	P5E_CPU0_PE0_TX_DP<13>
          	               	AW17      	13B2      	PD_CPU0_DMIMODE_OVERRIDE
          	               	AW19      	15B2      	TP_FM_IBL_WAKE_CPU0_N
          	               	AW21      	41A4      	GND                 
          	               	AW23      	41A4      	GND                 
          	               	AW25      	41A4      	GND                 
          	               	AW60      	37A1      	PVCCFA_EHV_CPU0     
          	               	AW62      	41A4      	GND                 
          	               	AW64      	15B4      	TP_SPI_S3M_CPU0_IO1_LVC1_R
          	               	AW66      	41A4      	GND                 
          	               	AW68      	41A4      	GND                 
          	               	AW70      	15B2      	FM_S3M_CPU0_LVC1_GPIO_4
          	               	AW72      	41A4      	GND                 
          	               	AW74      	34B3      	UPI_CPU1_CPU0_P2P2_DP<7>
          	               	AW76      	38B2      	PVCCFA_EHV_FIVRA_CPU0
          	               	AW78      	34B2      	UPI_CPU0_CPU1_P2P2_DN<13>
          	               	AW80      	41A4      	GND                 
          	               	AW82      	41A4      	GND                 
          	               	AW84      	41A4      	GND                 
          	               	AW86      	31B2      	P5E_CPU0_PE4_TX_DN<14>
          	               	AW88      	41A4      	GND                 
          	               	AW90      	31B3      	P5E_CPU0_PE4_RX_DP<14>
          	               	AY2       	32B2      	UPI_CPU0_CPU1_P0P1_DP<15>
          	               	AY4       	41A4      	GND                 
          	               	AY6       	32B3      	UPI_CPU1_CPU0_P1P0_DN<15>
          	               	AY8       	41A4      	GND                 
          	               	AY10      	29B3      	P5E_CPU0_PE0_RX_DP<15>
          	               	AY12      	41A4      	GND                 
          	               	AY14      	29B2      	P5E_CPU0_PE0_TX_DP<14>
          	               	AY16      	41A4      	GND                 
          	               	AY18      	37B3      	PVCCINFAON_CPU0     
          	               	AY20      	14B3      	PU_TAP_ODT_CPU0_EN  
          	               	AY22      	14B2      	H_CPU0_ERR1_LVC1_R_N
          	               	AY24      	17B2      	NC_CPU0_SOC_SPARE0  
          	               	AY26      	14B2      	NC_CPU0_VIEWPIN_DIE00<0>
          	               	AY61      	15B4      	TP_SPI_IBL_CPU0_TPM_IO1
          	               	AY63      	13B2      	FM_CPU0_PKGID1      
          	               	AY65      	14B2      	NC_CPU0_VIEWPIN_DIE01<2>
          	               	AY67      	15B4      	TP_SPI_IBL_CPU0_TPM_CS0_N
          	               	AY69      	15B2      	FM_S3M_CPU0_LVC1_GPIO_3
          	               	AY71      	41A4      	GND                 
          	               	AY73      	34B3      	UPI_CPU1_CPU0_P2P2_DP<10>
          	               	AY75      	34B3      	UPI_CPU1_CPU0_P2P2_DN<9>
          	               	AY77      	41A4      	GND                 
          	               	AY79      	41A4      	GND                 
          	               	AY81      	41A4      	GND                 
          	               	AY83      	41A4      	GND                 
          	               	AY85      	16B4      	VSENSE_PVCCFA_EHV_FIVRA_CPU0_DP
          	               	AY87      	31B2      	P5E_CPU0_PE4_TX_DP<14>
          	               	AY89      	38B2      	PVCCFA_EHV_FIVRA_CPU0
          	               	AY91      	31B3      	P5E_CPU0_PE4_RX_DN<14>
          	               	B6        	42A2      	GND                 
          	               	B8        	20B3      	M_A_CPU0_SB_DQ<28>  
          	               	B10       	20B3      	M_A_CPU0_SB_DQ<25>  
          	               	B12       	42A2      	GND                 
          	               	B14       	21B3      	M_B_CPU0_SB_DQ<30>  
          	               	B16       	21B3      	M_B_CPU0_SB_DQ<25>  
          	               	B18       	42A2      	GND                 
          	               	B20       	20B3      	M_A_CPU0_SB_DQ<20>  
          	               	B22       	20B3      	M_A_CPU0_SB_DQ<17>  
          	               	B24       	42A2      	GND                 
          	               	B26       	20B3      	M_A_CPU0_SB_DQ<12>  
          	               	B28       	20A3      	M_A_CPU0_SB_DQ<9>   
          	               	B30       	42B2      	GND                 
          	               	B32       	20A3      	M_A_CPU0_SB_CB<0>   
          	               	B34       	20A3      	M_A_CPU0_SB_CB<5>   
          	               	B36       	42B2      	GND                 
          	               	B38       	20A2      	M_A_CPU0_SB_CS_N<0> 
          	               	B40       	20B2      	M_A_CPU0_SB_CA<4>   
          	               	B42       	42B2      	GND                 
          	               	B44       	20A3      	M_A_CPU0_CLK_DN<0>  
          	               	B49       	42B2      	GND                 
          	               	B51       	20B2      	M_A_CPU0_SA_CA<2>   
          	               	B53       	20A2      	M_A_CPU0_SA_CS_N<1> 
          	               	B55       	42B2      	GND                 
          	               	B57       	20B3      	M_A_CPU0_SA_CB<4>   
          	               	B59       	20B3      	M_A_CPU0_SA_CB<1>   
          	               	B61       	42B2      	GND                 
          	               	B63       	20B3      	M_A_CPU0_SA_DQ<28>  
          	               	B65       	20B3      	M_A_CPU0_SA_DQ<25>  
          	               	B67       	42B2      	GND                 
          	               	B69       	20B3      	M_A_CPU0_SA_DQ<20>  
          	               	B71       	20B2      	M_A_CPU0_SA_DQS_DN<2>
          	               	B73       	20B3      	M_A_CPU0_SA_DQ<16>  
          	               	B75       	42B2      	GND                 
          	               	B77       	20B2      	M_A_CPU0_SA_DQS_DN<0>
          	               	B79       	20B3      	M_A_CPU0_SA_DQ<1>   
          	               	B81       	20B3      	M_A_CPU0_SA_DQ<0>   
          	               	B83       	42B2      	GND                 
          	               	B85       	34B2      	UPI_CPU0_CPU1_P2P2_DN<23>
          	               	B87       	42B2      	GND                 
          	               	BA1       	32B2      	UPI_CPU0_CPU1_P0P1_DP<16>
          	               	BA3       	37B2      	PVCCD_HV_CPU0       
          	               	BA5       	32B3      	UPI_CPU1_CPU0_P1P0_DP<15>
          	               	BA7       	37B2      	PVCCD_HV_CPU0       
          	               	BA9       	29B3      	P5E_CPU0_PE0_RX_DN<15>
          	               	BA11      	16B4      	VSENSE_PVCCFA_EHV_CPU0_DN
          	               	BA13      	29B2      	P5E_CPU0_PE0_TX_DN<14>
          	               	BA15      	37B3      	PVCCINFAON_CPU0     
          	               	BA17      	41A4      	GND                 
          	               	BA19      	37B2      	PVNN_MAIN_CPU0      
          	               	BA21      	37B2      	P3V3_AUX            
          	               	BA23      	19B3      	PU_CPU0_UPI0_AC_COUPLING
          	               	BA25      	17B2      	NC_CPU0_SOC_SPARE4  
          	               	BA60      	41A4      	GND                 
          	               	BA62      	15B4      	TP_SPI_S3M_CPU0_IO0_LVC1_R
          	               	BA64      	41B4      	GND                 
          	               	BA66      	15B4      	TP_SPI_IBL_CPU0_TPM_IO0
          	               	BA68      	15B4      	TP_SPI_S3M_CPU0_OE_LVC1_R_N
          	               	BA70      	15B2      	FM_S3M_CPU0_LVC1_GPIO_0
          	               	BA72      	34B3      	UPI_CPU1_CPU0_P2P2_DP<11>
          	               	BA74      	41B4      	GND                 
          	               	BA76      	34B3      	UPI_CPU1_CPU0_P2P2_DP<9>
          	               	BA78      	34B2      	UPI_CPU0_CPU1_P2P2_DP<13>
          	               	BA80      	34B2      	UPI_CPU0_CPU1_P2P2_DN<6>
          	               	BA82      	34B2      	UPI_CPU0_CPU1_P2P2_DP<5>
          	               	BA84      	41B4      	GND                 
          	               	BA86      	31B2      	P5E_CPU0_PE4_TX_DN<15>
          	               	BA88      	41B4      	GND                 
          	               	BA90      	31B3      	P5E_CPU0_PE4_RX_DP<15>
          	               	BB2       	32B2      	UPI_CPU0_CPU1_P0P1_DN<16>
          	               	BB4       	41B4      	GND                 
          	               	BB6       	32B3      	UPI_CPU1_CPU0_P1P0_DP<16>
          	               	BB8       	41B4      	GND                 
          	               	BB10      	41B4      	GND                 
          	               	BB12      	41B4      	GND                 
          	               	BB14      	29B2      	P5E_CPU0_PE0_TX_DN<15>
          	               	BB16      	41B4      	GND                 
          	               	BB18      	28B3      	DMI_CPU0_PCH_RX_C_DN<0>
          	               	BB20      	41B4      	GND                 
          	               	BB22      	41B4      	GND                 
          	               	BB24      	41B4      	GND                 
          	               	BB26      	41B4      	GND                 
          	               	BB61      	15B4      	TP_SPI_S3M_CPU0_CS0_LVC1_R_N
          	               	BB63      	41B4      	GND                 
          	               	BB65      	19B3      	PU_CPU0_UPI2_AC_COUPLING
          	               	BB67      	15B4      	TP_SPI_IBL_CPU0_TPM_OE_N
          	               	BB69      	41B4      	GND                 
          	               	BB71      	41B4      	GND                 
          	               	BB73      	34B3      	UPI_CPU1_CPU0_P2P2_DN<11>
          	               	BB75      	34B3      	UPI_CPU1_CPU0_P2P2_DP<8>
          	               	BB77      	41B4      	GND                 
          	               	BB79      	41B4      	GND                 
          	               	BB81      	34B2      	UPI_CPU0_CPU1_P2P2_DP<6>
          	               	BB83      	41B4      	GND                 
          	               	BB85      	31B2      	P5E_CPU0_PE4_TX_DP<15>
          	               	BB87      	41B4      	GND                 
          	               	BB89      	31B3      	P5E_CPU0_PE4_RX_DN<15>
          	               	BB91      	41B4      	GND                 
          	               	BC1       	41B4      	GND                 
          	               	BC3       	32B2      	UPI_CPU0_CPU1_P0P1_DP<17>
          	               	BC5       	41B4      	GND                 
          	               	BC7       	32B3      	UPI_CPU1_CPU0_P1P0_DN<16>
          	               	BC9       	41B4      	GND                 
          	               	BC11      	29A3      	P5E_CPU0_PE1_RX_DN<15>
          	               	BC13      	41B4      	GND                 
          	               	BC15      	29B2      	P5E_CPU0_PE0_TX_DP<15>
          	               	BC17      	41B4      	GND                 
          	               	BC19      	28B3      	DMI_CPU0_PCH_RX_C_DP<0>
          	               	BC21      	37B2      	P3V3_AUX            
          	               	BC23      	16B3      	TP_CPU0_IFST_DONE_LVC1_R
          	               	BC25      	15B2      	TP_I3C_MNG2_BMC_SW_SDA
          	               	BC60      	37B3      	PVCCINFAON_CPU0     
          	               	BC62      	41B4      	GND                 
          	               	BC64      	15B4      	TP_SPI_S3M_CPU0_CLK_LVC1_R
          	               	BC66      	41B4      	GND                 
          	               	BC68      	19B2      	TP_TRC_CPU0_PTI<21> 
          	               	BC70      	19B2      	TP_TRC_CPU0_PTI<16> 
          	               	BC72      	41B4      	GND                 
          	               	BC74      	34B3      	UPI_CPU1_CPU0_P2P2_DN<0>
          	               	BC76      	41B4      	GND                 
          	               	BC78      	41B4      	GND                 
          	               	BC80      	34B2      	UPI_CPU0_CPU1_P2P2_DP<3>
          	               	BC82      	34B2      	UPI_CPU0_CPU1_P2P2_DN<5>
          	               	BC84      	41B4      	GND                 
          	               	BC86      	41B4      	GND                 
          	               	BC88      	41B4      	GND                 
          	               	BC90      	16B4      	VSENSE_PVCCIN_CPU0_DN
          	               	BD2       	32B2      	UPI_CPU0_CPU1_P0P1_DN<17>
          	               	BD4       	41B4      	GND                 
          	               	BD6       	32B3      	UPI_CPU1_CPU0_P1P0_DN<17>
          	               	BD8       	41B4      	GND                 
          	               	BD10      	29B3      	P5E_CPU0_PE1_RX_DP<15>
          	               	BD12      	41B4      	GND                 
          	               	BD14      	29B2      	P5E_CPU0_PE1_TX_DP<15>
          	               	BD16      	41B4      	GND                 
          	               	BD18      	28B3      	DMI_CPU0_PCH_RX_C_DN<1>
          	               	BD20      	41B4      	GND                 
          	               	BD22      	14B2      	H_CPU0_ERR2_LVC1_R_N
          	               	BD24      	16B4      	H_PMAX_TRIGGER_IO_CPU0
          	               	BD26      	14B2      	SVID_DIO0_CPU0      
          	               	BD61      	15B4      	TP_SPI_S3M_CPU0_IO3_LVC1_R
          	               	BD63      	15B4      	TP_ESPI_IBL_CPU0_ALERT1_N
          	               	BD65      	15B4      	TP_SPI_S3M_CPU0_IO2_LVC1_R
          	               	BD67      	19B2      	TP_TRC_CPU0_PTI<23> 
          	               	BD69      	19B2      	TP_TRC_CPU0_PTI<18> 
          	               	BD71      	17B2      	NC_CPU0_MDFI_DIE01_NS1
          	               	BD73      	34B3      	UPI_CPU1_CPU0_P2P2_DP<0>
          	               	BD75      	34B3      	UPI_CPU1_CPU0_P2P2_DN<8>
          	               	BD77      	18B3      	TP_CPU0_SPARE13     
          	               	BD79      	34B2      	UPI_CPU0_CPU1_P2P2_DN<3>
          	               	BD81      	41B4      	GND                 
          	               	BD83      	34B2      	UPI_CPU0_CPU1_P2P2_DP<4>
          	               	BD85      	41B4      	GND                 
          	               	BD87      	16B4      	VSENSE_PVCCIN_CPU0_DP
          	               	BD89      	41B4      	GND                 
          	               	BD91      	37B4      	PVCCIN_CPU0         
          	               	BE1       	32B2      	UPI_CPU0_CPU1_P0P1_DP<18>
          	               	BE3       	37B2      	PVCCD_HV_CPU0       
          	               	BE5       	32B3      	UPI_CPU1_CPU0_P1P0_DP<17>
          	               	BE7       	37B2      	PVCCD_HV_CPU0       
          	               	BE9       	29B3      	P5E_CPU0_PE1_RX_DP<14>
          	               	BE11      	37B2      	PVCCD_HV_CPU0       
          	               	BE13      	29A2      	P5E_CPU0_PE1_TX_DN<15>
          	               	BE15      	37B3      	PVCCINFAON_CPU0     
          	               	BE17      	28B3      	DMI_CPU0_PCH_RX_C_DP<1>
          	               	BE19      	37B2      	PVNN_MAIN_CPU0      
          	               	BE21      	17B2      	TP_CPU0_DIE_HVM_EN_LVC1
          	               	BE23      	16B3      	TP_CPU0_IFST_KOT_LVC1_R
          	               	BE25      	15B2      	TP_I3C_MNG2_BMC_SW_SCL
          	               	BE60      	37B3      	PVCCINFAON_CPU0     
          	               	BE62      	15B4      	TP_ESPI_IBL_CPU0_ALERT0_LVC1_N
          	               	BE64      	41B4      	GND                 
          	               	BE66      	41B4      	GND                 
          	               	BE68      	41B4      	GND                 
          	               	BE70      	19B2      	TP_TRC_CPU0_PTI<17> 
          	               	BE72      	38B2      	PVCCFA_EHV_FIVRA_CPU0
          	               	BE74      	41B4      	GND                 
          	               	BE76      	41B4      	GND                 
          	               	BE78      	41B4      	GND                 
          	               	BE80      	34B2      	UPI_CPU0_CPU1_P2P2_DP<1>
          	               	BE82      	34B2      	UPI_CPU0_CPU1_P2P2_DN<4>
          	               	BE84      	41B4      	GND                 
          	               	BE86      	37B4      	PVCCIN_CPU0         
          	               	BE88      	37B4      	PVCCIN_CPU0         
          	               	BE90      	37B4      	PVCCIN_CPU0         
          	               	BF2       	32B2      	UPI_CPU0_CPU1_P0P1_DN<18>
          	               	BF4       	41B4      	GND                 
          	               	BF6       	32B3      	UPI_CPU1_CPU0_P1P0_DP<18>
          	               	BF8       	41B4      	GND                 
          	               	BF10      	29A3      	P5E_CPU0_PE1_RX_DN<14>
          	               	BF12      	41B4      	GND                 
          	               	BF14      	29A2      	P5E_CPU0_PE1_TX_DN<14>
          	               	BF16      	41B4      	GND                 
          	               	BF18      	28B3      	DMI_CPU0_PCH_RX_C_DN<2>
          	               	BF20      	41B4      	GND                 
          	               	BF22      	14B2      	H_CPU0_ERR0_LVC1_R_N
          	               	BF24      	16B3      	TP_CPU0_IFST_TRIG_LVC1_R
          	               	BF26      	14B2      	SVID_CLK1_CPU0      
          	               	BF61      	41B4      	GND                 
          	               	BF63      	41B4      	GND                 
          	               	BF65      	15B4      	TP_ESPI_IBL_CPU0_CS0_LVC1_N
          	               	BF67      	19B2      	TP_TRC_CPU0_PTI2_CLK
          	               	BF69      	19B2      	TP_TRC_CPU0_PTI<19> 
          	               	BF71      	17B2      	NC_CPU0_MDFI_DIE01_NS0
          	               	BF73      	41B4      	GND                 
          	               	BF75      	41B4      	GND                 
          	               	BF77      	38B2      	PVCCFA_EHV_FIVRA_CPU0
          	               	BF79      	41A4      	GND                 
          	               	BF81      	34B2      	UPI_CPU0_CPU1_P2P2_DN<2>
          	               	BF83      	41A4      	GND                 
          	               	BF85      	37B4      	PVCCIN_CPU0         
          	               	BF87      	37B4      	PVCCIN_CPU0         
          	               	BF89      	37B4      	PVCCIN_CPU0         
          	               	BF91      	37B4      	PVCCIN_CPU0         
          	               	BG1       	41A4      	GND                 
          	               	BG3       	32B2      	UPI_CPU0_CPU1_P0P1_DP<19>
          	               	BG5       	41A4      	GND                 
          	               	BG7       	32B3      	UPI_CPU1_CPU0_P1P0_DN<18>
          	               	BG9       	41A4      	GND                 
          	               	BG11      	29A3      	P5E_CPU0_PE1_RX_DN<13>
          	               	BG13      	41A4      	GND                 
          	               	BG15      	29B2      	P5E_CPU0_PE1_TX_DP<14>
          	               	BG17      	41A4      	GND                 
          	               	BG19      	28B3      	DMI_CPU0_PCH_RX_C_DP<2>
          	               	BG21      	41A4      	GND                 
          	               	BG23      	41A4      	GND                 
          	               	BG25      	41A4      	GND                 
          	               	BG60      	37B3      	PVCCINFAON_CPU0     
          	               	BG62      	15B4      	TP_CLK_66M_ESPI_IBL_CPU0_LVC1
          	               	BG64      	15B4      	TP_RST_ESPI_IBL_CPU0_LVC1_N
          	               	BG66      	19B2      	TP_TRC_CPU0_PTI<27> 
          	               	BG68      	19B2      	TP_TRC_CPU0_PTI<22> 
          	               	BG70      	41A4      	GND                 
          	               	BG72      	13B2      	FM_CPU0_PROC_ID0    
          	               	BG74      	34B3      	UPI_CPU1_CPU0_P2P2_DP<3>
          	               	BG76      	34B3      	UPI_CPU1_CPU0_P2P2_DP<6>
          	               	BG78      	17B3      	NC_CPU0_HBM3_VIEWDIG0
          	               	BG80      	34B2      	UPI_CPU0_CPU1_P2P2_DN<1>
          	               	BG82      	34B2      	UPI_CPU0_CPU1_P2P2_DP<2>
          	               	BG84      	37B4      	PVCCIN_CPU0         
          	               	BG86      	37B4      	PVCCIN_CPU0         
          	               	BG88      	37B4      	PVCCIN_CPU0         
          	               	BG90      	37B4      	PVCCIN_CPU0         
          	               	BH2       	32B2      	UPI_CPU0_CPU1_P0P1_DN<19>
          	               	BH4       	41A4      	GND                 
          	               	BH6       	32B3      	UPI_CPU1_CPU0_P1P0_DN<19>
          	               	BH8       	41A4      	GND                 
          	               	BH10      	29B3      	P5E_CPU0_PE1_RX_DP<13>
          	               	BH12      	41A4      	GND                 
          	               	BH14      	29B2      	P5E_CPU0_PE1_TX_DP<13>
          	               	BH16      	41A4      	GND                 
          	               	BH18      	28B3      	DMI_CPU0_PCH_RX_C_DN<3>
          	               	BH20      	41A4      	GND                 
          	               	BH22      	16B3      	H_CPU0_RMCA_LVC1_R_N
          	               	BH24      	13B3      	PECI_CPU0_GTL_R     
          	               	BH26      	14B2      	SVID_CLK0_CPU0      
          	               	BH61      	14B3      	RST_CPU0_LVC1_N     
          	               	BH63      	15B4      	TP_ESPI_IBL_CPU0_OE_LVC1_N
          	               	BH65      	15B4      	TP_ESPI_IBL_CPU0_CS1_N
          	               	BH67      	41A4      	GND                 
          	               	BH69      	19B2      	TP_TRC_CPU0_PTI<20> 
          	               	BH71      	13B2      	FM_CPU0_PROC_ID1    
          	               	BH73      	41A4      	GND                 
          	               	BH75      	34B3      	UPI_CPU1_CPU0_P2P2_DN<6>
          	               	BH77      	41A4      	GND                 
          	               	BH79      	38B2      	PVCCFA_EHV_FIVRA_CPU0
          	               	BH81      	41A4      	GND                 
          	               	BH83      	41A4      	GND                 
          	               	BH85      	37B4      	PVCCIN_CPU0         
          	               	BH87      	37B4      	PVCCIN_CPU0         
          	               	BH89      	37B4      	PVCCIN_CPU0         
          	               	BH91      	37B4      	PVCCIN_CPU0         
          	               	BJ1       	32B2      	UPI_CPU0_CPU1_P0P1_DN<20>
          	               	BJ3       	37B2      	PVCCD_HV_CPU0       
          	               	BJ5       	32B3      	UPI_CPU1_CPU0_P1P0_DP<19>
          	               	BJ7       	37B2      	PVCCD_HV_CPU0       
          	               	BJ9       	29B3      	P5E_CPU0_PE1_RX_DP<12>
          	               	BJ11      	37B2      	PVCCD_HV_CPU0       
          	               	BJ13      	29A2      	P5E_CPU0_PE1_TX_DN<13>
          	               	BJ15      	37B3      	PVCCINFAON_CPU0     
          	               	BJ17      	28B3      	DMI_CPU0_PCH_RX_C_DP<3>
          	               	BJ19      	37B1      	PVNN_MAIN_CPU0      
          	               	BJ21      	17B2      	NC_CPU0_MDFI_DIE00_NS1
          	               	BJ23      	16B3      	DBP_CPU0_HOOK8_MBP2_GTL_QS_R_N
          	               	BJ25      	14B2      	SVID_ALERT1_CPU0_N  
          	               	BJ60      	37B3      	PVCCINFAON_CPU0     
          	               	BJ62      	41A4      	GND                 
          	               	BJ64      	15B4      	TP_ESPI_IBL_CPU0_IO1_LVC1
          	               	BJ66      	19B2      	TP_TRC_CPU0_PTI<28> 
          	               	BJ68      	41B4      	GND                 
          	               	BJ70      	14B2      	NC_CPU0_VIEWPIN_DIE01<3>
          	               	BJ72      	38B2      	PVCCFA_EHV_FIVRA_CPU0
          	               	BJ74      	34B3      	UPI_CPU1_CPU0_P2P2_DN<3>
          	               	BJ76      	34B3      	UPI_CPU1_CPU0_P2P2_DN<5>
          	               	BJ78      	38A3      	PVCCFA_EHV_FIVRA_CPU0
          	               	BJ80      	41B4      	GND                 
          	               	BJ82      	41B4      	GND                 
          	               	BJ84      	41B4      	GND                 
          	               	BJ86      	41B4      	GND                 
          	               	BJ88      	41B4      	GND                 
          	               	BJ90      	41B4      	GND                 
          	               	BK2       	32B2      	UPI_CPU0_CPU1_P0P1_DP<20>
          	               	BK4       	41B4      	GND                 
          	               	BK6       	32B3      	UPI_CPU1_CPU0_P1P0_DP<20>
          	               	BK8       	41B4      	GND                 
          	               	BK10      	29A3      	P5E_CPU0_PE1_RX_DN<12>
          	               	BK12      	41B4      	GND                 
          	               	BK14      	29A2      	P5E_CPU0_PE1_TX_DN<12>
          	               	BK16      	41B4      	GND                 
          	               	BK18      	28B3      	DMI_CPU0_PCH_RX_C_DP<4>
          	               	BK20      	41B4      	GND                 
          	               	BK22      	17B2      	NC_CPU0_MDFI_DIE00_NS0
          	               	BK24      	16B3      	DBP_CPU0_HOOK9_MBP3_GTL_QS_R_N
          	               	BK26      	14B2      	SVID_ALERT0_CPU0_N  
          	               	BK61      	37B3      	PVCCINFAON_CPU0     
          	               	BK63      	15B4      	TP_ESPI_IBL_CPU0_IO0_LVC1
          	               	BK65      	41B4      	GND                 
          	               	BK67      	19B2      	TP_TRC_CPU0_PTI3_CLK
          	               	BK69      	19B2      	TP_TRC_CPU0_PTI<24> 
          	               	BK71      	41B4      	GND                 
          	               	BK73      	34B3      	UPI_CPU1_CPU0_P2P2_DN<1>
          	               	BK75      	41B4      	GND                 
          	               	BK77      	34B3      	UPI_CPU1_CPU0_P2P2_DP<5>
          	               	BK79      	41B4      	GND                 
          	               	BK81      	37B4      	PVCCIN_CPU0         
          	               	BK83      	37B4      	PVCCIN_CPU0         
          	               	BK85      	37B4      	PVCCIN_CPU0         
          	               	BK87      	37B4      	PVCCIN_CPU0         
          	               	BK89      	37B4      	PVCCIN_CPU0         
          	               	BK91      	37B4      	PVCCIN_CPU0         
          	               	BL1       	41B4      	GND                 
          	               	BL3       	32B2      	UPI_CPU0_CPU1_P0P1_DN<21>
          	               	BL5       	41B4      	GND                 
          	               	BL7       	32B3      	UPI_CPU1_CPU0_P1P0_DN<20>
          	               	BL9       	41B4      	GND                 
          	               	BL11      	29A3      	P5E_CPU0_PE1_RX_DN<11>
          	               	BL13      	41B4      	GND                 
          	               	BL15      	29B2      	P5E_CPU0_PE1_TX_DP<12>
          	               	BL17      	41B4      	GND                 
          	               	BL19      	28B3      	DMI_CPU0_PCH_RX_C_DN<4>
          	               	BL21      	19B2      	NC_CPU0_PE0_APROBE<1>
          	               	BL23      	16B3      	DBP_CPU0_MBP0_GTL_R_N
          	               	BL25      	14B2      	SVID_DIO1_CPU0      
          	               	BL60      	17B3      	NC_CPU0_HBM3_VIEWDIG1
          	               	BL62      	14B2      	H_CPU0_THERMTRIP_LVC1_R_N
          	               	BL64      	13B2      	FM_CPU0_PKGID0      
          	               	BL66      	19B2      	TP_TRC_CPU0_PTI<29> 
          	               	BL68      	41B4      	GND                 
          	               	BL70      	41B4      	GND                 
          	               	BL72      	41B4      	GND                 
          	               	BL74      	34B3      	UPI_CPU1_CPU0_P2P2_DP<1>
          	               	BL76      	34B3      	UPI_CPU1_CPU0_P2P2_DP<4>
          	               	BL78      	41B4      	GND                 
          	               	BL80      	37B4      	PVCCIN_CPU0         
          	               	BL82      	37B4      	PVCCIN_CPU0         
          	               	BL84      	37B4      	PVCCIN_CPU0         
          	               	BL86      	37B4      	PVCCIN_CPU0         
          	               	BL88      	37B4      	PVCCIN_CPU0         
          	               	BL90      	37B4      	PVCCIN_CPU0         
          	               	BM2       	32B2      	UPI_CPU0_CPU1_P0P1_DP<21>
          	               	BM4       	41B4      	GND                 
          	               	BM6       	32B3      	UPI_CPU1_CPU0_P1P0_DN<21>
          	               	BM8       	41B4      	GND                 
          	               	BM10      	29B3      	P5E_CPU0_PE1_RX_DP<11>
          	               	BM12      	41B4      	GND                 
          	               	BM14      	29B2      	P5E_CPU0_PE1_TX_DP<11>
          	               	BM16      	41B4      	GND                 
          	               	BM18      	28B3      	DMI_CPU0_PCH_RX_C_DN<5>
          	               	BM20      	41B4      	GND                 
          	               	BM22      	41B4      	GND                 
          	               	BM24      	41B4      	GND                 
          	               	BM26      	41B4      	GND                 
          	               	BM61      	41B4      	GND                 
          	               	BM63      	15B4      	TP_ESPI_IBL_CPU0_IO3_LVC1
          	               	BM65      	17B2      	NC_CPU0_SOC_SPARE1  
          	               	BM67      	19B2      	TP_TRC_CPU0_PTI<30> 
          	               	BM69      	19B2      	TP_TRC_CPU0_PTI<25> 
          	               	BM71      	34B2      	UPI_CPU0_CPU1_P2P2_DN<0>
          	               	BM73      	41B4      	GND                 
          	               	BM75      	34B3      	UPI_CPU1_CPU0_P2P2_DN<2>
          	               	BM77      	41B4      	GND                 
          	               	BM79      	37B4      	PVCCIN_CPU0         
          	               	BM81      	37B4      	PVCCIN_CPU0         
          	               	BM83      	37B4      	PVCCIN_CPU0         
          	               	BM85      	37B4      	PVCCIN_CPU0         
          	               	BM87      	37B4      	PVCCIN_CPU0         
          	               	BM89      	37B4      	PVCCIN_CPU0         
          	               	BM91      	37B4      	PVCCIN_CPU0         
          	               	BN3       	32B2      	UPI_CPU0_CPU1_P0P1_DN<22>
          	               	BN5       	32B3      	UPI_CPU1_CPU0_P1P0_DP<21>
          	               	BN7       	37B2      	PVCCD_HV_CPU0       
          	               	BN9       	29A3      	P5E_CPU0_PE1_RX_DP<10>
          	               	BN11      	16B4      	VSENSE_PVCCD_HV_CPU0_DN
          	               	BN13      	29A2      	P5E_CPU0_PE1_TX_DN<11>
          	               	BN15      	37B3      	PVCCINFAON_CPU0     
          	               	BN17      	28B3      	DMI_CPU0_PCH_RX_C_DP<5>
          	               	BN19      	37B1      	PVNN_MAIN_CPU0      
          	               	BN21      	19B2      	NC_CPU0_PE0_APROBE<0>
          	               	BN23      	13B2      	H_CPU0_BMCINIT_LVC1 
          	               	BN25      	16B3      	DBP_CPU0_MBP1_GTL_R_N
          	               	BN27      	19B3      	TP_TRC_CPU0_PTI<12> 
          	               	BN29      	19B3      	TP_TRC_CPU0_PTI<14> 
          	               	BN31      	41B4      	GND                 
          	               	BN33      	37B4      	PVCCIN_CPU0         
          	               	BN35      	37B4      	PVCCIN_CPU0         
          	               	BN37      	37B4      	PVCCIN_CPU0         
          	               	BN39      	37B4      	PVCCIN_CPU0         
          	               	BN41      	37B4      	PVCCIN_CPU0         
          	               	BN43      	36A1      	PVCCIN_CPU0         
          	               	BN45      	36A1      	PVCCIN_CPU0         
          	               	BN48      	36A1      	PVCCIN_CPU0         
          	               	BN50      	36A1      	PVCCIN_CPU0         
          	               	BN52      	36A1      	PVCCIN_CPU0         
          	               	BN54      	36A1      	PVCCIN_CPU0         
          	               	BN56      	36A1      	PVCCIN_CPU0         
          	               	BN58      	36A1      	PVCCIN_CPU0         
          	               	BN60      	36A1      	PVCCIN_CPU0         
          	               	BN62      	41B4      	GND                 
          	               	BN64      	13B2      	FM_CPU0_PKGID2      
          	               	BN66      	19B2      	TP_TRC_CPU0_PTI<31> 
          	               	BN68      	19B2      	TP_TRC_CPU0_PTI<26> 
          	               	BN70      	41B4      	GND                 
          	               	BN72      	34B2      	UPI_CPU0_CPU1_P2P2_DP<0>
          	               	BN74      	34B3      	UPI_CPU1_CPU0_P2P2_DP<2>
          	               	BN76      	34B3      	UPI_CPU1_CPU0_P2P2_DN<4>
          	               	BN78      	36A1      	PVCCIN_CPU0         
          	               	BN80      	36A1      	PVCCIN_CPU0         
          	               	BN82      	36A1      	PVCCIN_CPU0         
          	               	BN84      	36A1      	PVCCIN_CPU0         
          	               	BN86      	36A1      	PVCCIN_CPU0         
          	               	BN88      	36A1      	PVCCIN_CPU0         
          	               	BN90      	36A1      	PVCCIN_CPU0         
          	               	BP2       	41B4      	GND                 
          	               	BP4       	41B4      	GND                 
          	               	BP6       	32B3      	UPI_CPU1_CPU0_P1P0_DP<22>
          	               	BP8       	41B4      	GND                 
          	               	BP10      	29A3      	P5E_CPU0_PE1_RX_DN<10>
          	               	BP12      	41B4      	GND                 
          	               	BP14      	29A2      	P5E_CPU0_PE1_TX_DN<10>
          	               	BP16      	41B4      	GND                 
          	               	BP18      	28B3      	DMI_CPU0_PCH_RX_C_DP<6>
          	               	BP20      	41B4      	GND                 
          	               	BP22      	17B2      	NC_CPU0_MDFI_DIE00_EW0
          	               	BP24      	14B2      	H_CPU0_CATERR_LVC1_R_N
          	               	BP26      	13B3      	H_CPU0_PRDY_QS_GTL_R_N
          	               	BP28      	19B3      	TP_TRC_CPU0_PTI<13> 
          	               	BP30      	19B3      	TP_TRC_CPU0_PTI<15> 
          	               	BP32      	36A1      	PVCCIN_CPU0         
          	               	BP34      	36A1      	PVCCIN_CPU0         
          	               	BP36      	36A1      	PVCCIN_CPU0         
          	               	BP38      	36A1      	PVCCIN_CPU0         
          	               	BP40      	36A1      	PVCCIN_CPU0         
          	               	BP42      	36B1      	PVCCIN_CPU0         
          	               	BP44      	36B1      	PVCCIN_CPU0         
          	               	BP47      	36B1      	PVCCIN_CPU0         
          	               	BP49      	36B1      	PVCCIN_CPU0         
          	               	BP51      	36B1      	PVCCIN_CPU0         
          	               	BP53      	36B1      	PVCCIN_CPU0         
          	               	BP55      	36B1      	PVCCIN_CPU0         
          	               	BP57      	36B1      	PVCCIN_CPU0         
          	               	BP59      	36B1      	PVCCIN_CPU0         
          	               	BP61      	36B1      	PVCCIN_CPU0         
          	               	BP63      	41B4      	GND                 
          	               	BP65      	17B2      	NC_CPU0_SOC_SPARE5  
          	               	BP67      	14B2      	NC_CPU0_VIEWPIN_DIE01<1>
          	               	BP69      	14B2      	NC_CPU0_VIEWPIN_DIE01<0>
          	               	BP71      	41B4      	GND                 
          	               	BP73      	41B4      	GND                 
          	               	BP75      	41B4      	GND                 
          	               	BP77      	41B4      	GND                 
          	               	BP79      	36B1      	PVCCIN_CPU0         
          	               	BP81      	36B1      	PVCCIN_CPU0         
          	               	BP83      	36B1      	PVCCIN_CPU0         
          	               	BP85      	36B1      	PVCCIN_CPU0         
          	               	BP87      	36B1      	PVCCIN_CPU0         
          	               	BP89      	36B1      	PVCCIN_CPU0         
          	               	BR3       	32B2      	UPI_CPU0_CPU1_P0P1_DP<22>
          	               	BR5       	41B4      	GND                 
          	               	BR7       	32B3      	UPI_CPU1_CPU0_P1P0_DN<22>
          	               	BR9       	41B4      	GND                 
          	               	BR11      	29A3      	P5E_CPU0_PE1_RX_DN<9>
          	               	BR13      	41B4      	GND                 
          	               	BR15      	29A2      	P5E_CPU0_PE1_TX_DP<10>
          	               	BR17      	41B4      	GND                 
          	               	BR19      	28B3      	DMI_CPU0_PCH_RX_C_DN<6>
          	               	BR21      	17B2      	NC_CPU0_MDFI_DIE00_EW1
          	               	BR23      	13B2      	TP_CPU0_BR23        
          	               	BR25      	13B3      	JTAG_DBP_CPU0_QS_GTL_R_TMS
          	               	BR27      	41B4      	GND                 
          	               	BR29      	41B4      	GND                 
          	               	BR31      	41B4      	GND                 
          	               	BR33      	41B4      	GND                 
          	               	BR35      	40A1      	GND                 
          	               	BR37      	40A1      	GND                 
          	               	BR39      	40A1      	GND                 
          	               	BR41      	40A1      	GND                 
          	               	BR43      	40A1      	GND                 
          	               	BR45      	40A1      	GND                 
          	               	BR48      	40A1      	GND                 
          	               	BR50      	40A1      	GND                 
          	               	BR52      	40A1      	GND                 
          	               	BR54      	40A1      	GND                 
          	               	BR56      	40A1      	GND                 
          	               	BR58      	40A1      	GND                 
          	               	BR60      	36B1      	PVCCIN_CPU0         
          	               	BR62      	36B1      	PVCCIN_CPU0         
          	               	BR64      	40A1      	GND                 
          	               	BR66      	40A1      	GND                 
          	               	BR68      	40A1      	GND                 
          	               	BR70      	40A1      	GND                 
          	               	BR72      	40A1      	GND                 
          	               	BR74      	40A1      	GND                 
          	               	BR76      	40A1      	GND                 
          	               	BR78      	36B1      	PVCCIN_CPU0         
          	               	BR80      	40A1      	GND                 
          	               	BR82      	40A1      	GND                 
          	               	BR84      	40A1      	GND                 
          	               	BR86      	40B1      	GND                 
          	               	BR88      	40B1      	GND                 
          	               	BR90      	40B1      	GND                 
          	               	BT2       	32B2      	UPI_CPU0_CPU1_P0P1_DN<23>
          	               	BT4       	40B1      	GND                 
          	               	BT6       	32B3      	UPI_CPU1_CPU0_P1P0_DN<23>
          	               	BT8       	40B1      	GND                 
          	               	BT10      	29A3      	P5E_CPU0_PE1_RX_DP<9>
          	               	BT12      	40B1      	GND                 
          	               	BT14      	29A2      	P5E_CPU0_PE1_TX_DP<9>
          	               	BT16      	40B1      	GND                 
          	               	BT18      	28B3      	DMI_CPU0_PCH_RX_C_DP<7>
          	               	BT20      	40B1      	GND                 
          	               	BT22      	13B3      	I3C_SPD_DDRABCD_CPU0_SCL
          	               	BT24      	13B3      	JTAG_DBP_CPU0_GTL_R_TCK
          	               	BT26      	13B2      	PU_CPU0_TXT_AGENT   
          	               	BT28      	19B3      	TP_TRC_CPU0_PTI<9>  
          	               	BT30      	19B3      	TP_TRC_CPU0_PTI<11> 
          	               	BT32      	36B1      	PVCCIN_CPU0         
          	               	BT34      	36B1      	PVCCIN_CPU0         
          	               	BT36      	36B1      	PVCCIN_CPU0         
          	               	BT38      	36B1      	PVCCIN_CPU0         
          	               	BT40      	36B1      	PVCCIN_CPU0         
          	               	BT42      	36B1      	PVCCIN_CPU0         
          	               	BT44      	36B1      	PVCCIN_CPU0         
          	               	BT47      	36B1      	PVCCIN_CPU0         
          	               	BT49      	36B1      	PVCCIN_CPU0         
          	               	BT51      	36B1      	PVCCIN_CPU0         
          	               	BT53      	36B1      	PVCCIN_CPU0         
          	               	BT55      	36B1      	PVCCIN_CPU0         
          	               	BT57      	36B1      	PVCCIN_CPU0         
          	               	BT59      	36B1      	PVCCIN_CPU0         
          	               	BT61      	36B1      	PVCCIN_CPU0         
          	               	BT63      	36B1      	PVCCIN_CPU0         
          	               	BT65      	36B1      	PVCCIN_CPU0         
          	               	BT67      	36B1      	PVCCIN_CPU0         
          	               	BT69      	36B1      	PVCCIN_CPU0         
          	               	BT71      	36B1      	PVCCIN_CPU0         
          	               	BT73      	36B1      	PVCCIN_CPU0         
          	               	BT75      	36B1      	PVCCIN_CPU0         
          	               	BT77      	36B1      	PVCCIN_CPU0         
          	               	BT79      	36B1      	PVCCIN_CPU0         
          	               	BT81      	36B1      	PVCCIN_CPU0         
          	               	BT83      	36B1      	PVCCIN_CPU0         
          	               	BT85      	36B1      	PVCCIN_CPU0         
          	               	BT87      	36B1      	PVCCIN_CPU0         
          	               	BT89      	36B1      	PVCCIN_CPU0         
          	               	BU3       	32B2      	UPI_CPU0_CPU1_P0P1_DP<23>
          	               	BU5       	32B3      	UPI_CPU1_CPU0_P1P0_DP<23>
          	               	BU7       	40B1      	GND                 
          	               	BU9       	29A3      	P5E_CPU0_PE1_RX_DP<8>
          	               	BU11      	16B4      	VSENSE_PVCCD_HV_CPU0_DP
          	               	BU13      	29A2      	P5E_CPU0_PE1_TX_DN<9>
          	               	BU15      	40B1      	GND                 
          	               	BU17      	28B3      	DMI_CPU0_PCH_RX_C_DN<7>
          	               	BU19      	40B1      	GND                 
          	               	BU21      	40B1      	GND                 
          	               	BU23      	40B1      	GND                 
          	               	BU25      	40B1      	GND                 
          	               	BU27      	19B3      	TP_TRC_CPU0_PTI<8>  
          	               	BU29      	19B3      	TP_TRC_CPU0_PTI<10> 
          	               	BU31      	40B1      	GND                 
          	               	BU33      	36B1      	PVCCIN_CPU0         
          	               	BU35      	36B1      	PVCCIN_CPU0         
          	               	BU37      	36B1      	PVCCIN_CPU0         
          	               	BU39      	36B1      	PVCCIN_CPU0         
          	               	BU41      	36B1      	PVCCIN_CPU0         
          	               	BU43      	36B1      	PVCCIN_CPU0         
          	               	BU45      	36A2      	PVCCIN_CPU0         
          	               	BU48      	36A2      	PVCCIN_CPU0         
          	               	BU50      	36A2      	PVCCIN_CPU0         
          	               	BU52      	36A2      	PVCCIN_CPU0         
          	               	BU54      	36A2      	PVCCIN_CPU0         
          	               	BU56      	36A2      	PVCCIN_CPU0         
          	               	BU58      	36A2      	PVCCIN_CPU0         
          	               	BU60      	36A2      	PVCCIN_CPU0         
          	               	BU62      	36A2      	PVCCIN_CPU0         
          	               	BU64      	36A2      	PVCCIN_CPU0         
          	               	BU66      	36A2      	PVCCIN_CPU0         
          	               	BU68      	36A2      	PVCCIN_CPU0         
          	               	BU70      	36A2      	PVCCIN_CPU0         
          	               	BU72      	36A2      	PVCCIN_CPU0         
          	               	BU74      	36A2      	PVCCIN_CPU0         
          	               	BU76      	36A2      	PVCCIN_CPU0         
          	               	BU78      	36A2      	PVCCIN_CPU0         
          	               	BU80      	36A2      	PVCCIN_CPU0         
          	               	BU82      	36A2      	PVCCIN_CPU0         
          	               	BU84      	36A2      	PVCCIN_CPU0         
          	               	BU86      	36A2      	PVCCIN_CPU0         
          	               	BU88      	36B2      	PVCCIN_CPU0         
          	               	BU90      	36B2      	PVCCIN_CPU0         
          	               	BV2       	40B1      	GND                 
          	               	BV4       	40B1      	GND                 
          	               	BV6       	40B1      	GND                 
          	               	BV8       	40B1      	GND                 
          	               	BV10      	29A3      	P5E_CPU0_PE1_RX_DN<8>
          	               	BV12      	40B1      	GND                 
          	               	BV14      	29A2      	P5E_CPU0_PE1_TX_DN<8>
          	               	BV16      	40B1      	GND                 
          	               	BV18      	40B1      	GND                 
          	               	BV20      	40B1      	GND                 
          	               	BV22      	19B3      	NC_CPU0_UPI1_APROBE<0>
          	               	BV24      	13B3      	JTAG_DBP_CPU0_GTL_R_TDI
          	               	BV26      	14B3      	FM_PEHPCPU0_ALERT_N 
          	               	BV28      	19B3      	TP_TRC_CPU0_PTI<7>  
          	               	BV30      	19B3      	TP_TRC_CPU0_PTI<5>  
          	               	BV32      	36B2      	PVCCIN_CPU0         
          	               	BV34      	36B2      	PVCCIN_CPU0         
          	               	BV36      	36B2      	PVCCIN_CPU0         
          	               	BV38      	36B2      	PVCCIN_CPU0         
          	               	BV40      	36B2      	PVCCIN_CPU0         
          	               	BV42      	36B2      	PVCCIN_CPU0         
          	               	BV44      	36B2      	PVCCIN_CPU0         
          	               	BV47      	36B2      	PVCCIN_CPU0         
          	               	BV49      	36B2      	PVCCIN_CPU0         
          	               	BV51      	36B2      	PVCCIN_CPU0         
          	               	BV53      	36B2      	PVCCIN_CPU0         
          	               	BV55      	36B2      	PVCCIN_CPU0         
          	               	BV57      	36B2      	PVCCIN_CPU0         
          	               	BV59      	36B2      	PVCCIN_CPU0         
          	               	BV61      	36B2      	PVCCIN_CPU0         
          	               	BV63      	36B2      	PVCCIN_CPU0         
          	               	BV65      	36B2      	PVCCIN_CPU0         
          	               	BV67      	36B2      	PVCCIN_CPU0         
          	               	BV69      	36B2      	PVCCIN_CPU0         
          	               	BV71      	36B2      	PVCCIN_CPU0         
          	               	BV73      	36B2      	PVCCIN_CPU0         
          	               	BV75      	36B2      	PVCCIN_CPU0         
          	               	BV77      	36B2      	PVCCIN_CPU0         
          	               	BV79      	36B2      	PVCCIN_CPU0         
          	               	BV81      	36B2      	PVCCIN_CPU0         
          	               	BV83      	36B2      	PVCCIN_CPU0         
          	               	BV85      	36B2      	PVCCIN_CPU0         
          	               	BV87      	36B2      	PVCCIN_CPU0         
          	               	BV89      	36B2      	PVCCIN_CPU0         
          	               	BW3       	40B1      	GND                 
          	               	BW5       	40B1      	GND                 
          	               	BW7       	33B2      	UPI_CPU0_CPU1_P1P0_DN<23>
          	               	BW9       	40B1      	GND                 
          	               	BW11      	29A3      	P5E_CPU0_PE1_RX_DN<7>
          	               	BW13      	40B1      	GND                 
          	               	BW15      	29A2      	P5E_CPU0_PE1_TX_DP<8>
          	               	BW17      	40B1      	GND                 
          	               	BW19      	28B2      	DMI_CPU0_PCH_TX_DP<0>
          	               	BW21      	19B3      	NC_CPU0_DMI_APROBE<1>
          	               	BW23      	19B2      	NC_CPU0_PE2_APROBE<1>
          	               	BW25      	13B2      	JTAG_CPU0_MUX_GTL_TDO
          	               	BW27      	40B1      	GND                 
          	               	BW29      	40B1      	GND                 
          	               	BW31      	40B1      	GND                 
          	               	BW33      	36B2      	PVCCIN_CPU0         
          	               	BW35      	36B2      	PVCCIN_CPU0         
          	               	BW37      	36B2      	PVCCIN_CPU0         
          	               	BW39      	36B2      	PVCCIN_CPU0         
          	               	BW41      	36B2      	PVCCIN_CPU0         
          	               	BW43      	36B2      	PVCCIN_CPU0         
          	               	BW45      	36B2      	PVCCIN_CPU0         
          	               	BW48      	36B2      	PVCCIN_CPU0         
          	               	BW50      	36B2      	PVCCIN_CPU0         
          	               	BW52      	36B2      	PVCCIN_CPU0         
          	               	BW54      	36B2      	PVCCIN_CPU0         
          	               	BW56      	36B2      	PVCCIN_CPU0         
          	               	BW58      	36B2      	PVCCIN_CPU0         
          	               	BW60      	36B2      	PVCCIN_CPU0         
          	               	BW62      	36B2      	PVCCIN_CPU0         
          	               	BW64      	36B2      	PVCCIN_CPU0         
          	               	BW66      	36B2      	PVCCIN_CPU0         
          	               	BW68      	36B2      	PVCCIN_CPU0         
          	               	BW70      	36B2      	PVCCIN_CPU0         
          	               	BW72      	36B2      	PVCCIN_CPU0         
          	               	BW74      	36B2      	PVCCIN_CPU0         
          	               	BW76      	36B2      	PVCCIN_CPU0         
          	               	BW78      	36B2      	PVCCIN_CPU0         
          	               	BW80      	36A3      	PVCCIN_CPU0         
          	               	BW82      	36A3      	PVCCIN_CPU0         
          	               	BW84      	36A3      	PVCCIN_CPU0         
          	               	BW86      	36A3      	PVCCIN_CPU0         
          	               	BW88      	36A3      	PVCCIN_CPU0         
          	               	BW90      	36A3      	PVCCIN_CPU0         
          	               	BY2       	33B3      	UPI_CPU1_CPU0_P0P1_DN<23>
          	               	BY4       	40B1      	GND                 
          	               	BY6       	33B2      	UPI_CPU0_CPU1_P1P0_DP<23>
          	               	BY8       	40B1      	GND                 
          	               	BY10      	29A3      	P5E_CPU0_PE1_RX_DP<7>
          	               	BY12      	40B1      	GND                 
          	               	BY14      	29A2      	P5E_CPU0_PE1_TX_DP<7>
          	               	BY16      	40B1      	GND                 
          	               	BY18      	28B2      	DMI_CPU0_PCH_TX_DN<1>
          	               	BY20      	40B1      	GND                 
          	               	BY22      	13B3      	I3C_SPD_DDRABCD_CPU0_SDA
          	               	BY24      	13B2      	PD_EXT_CLK_SEL_CPU0 
          	               	BY26      	14B3      	SMB_PEHPCPU0_GTL_SDA
          	               	BY28      	19B3      	TP_TRC_CPU0_PTI1_CLK
          	               	BY30      	19B3      	TP_TRC_CPU0_PTI<3>  
          	               	BY32      	36A3      	PVCCIN_CPU0         
          	               	BY34      	36A3      	PVCCIN_CPU0         
          	               	BY36      	36A3      	PVCCIN_CPU0         
          	               	BY38      	36A3      	PVCCIN_CPU0         
          	               	BY40      	36A3      	PVCCIN_CPU0         
          	               	BY42      	36A3      	PVCCIN_CPU0         
          	               	BY44      	36A3      	PVCCIN_CPU0         
          	               	BY47      	36A3      	PVCCIN_CPU0         
          	               	BY49      	36A3      	PVCCIN_CPU0         
          	               	BY51      	36A3      	PVCCIN_CPU0         
          	               	BY53      	36A3      	PVCCIN_CPU0         
          	               	BY55      	36A3      	PVCCIN_CPU0         
          	               	BY57      	36A3      	PVCCIN_CPU0         
          	               	BY59      	36A3      	PVCCIN_CPU0         
          	               	BY61      	36A3      	PVCCIN_CPU0         
          	               	BY63      	36B3      	PVCCIN_CPU0         
          	               	BY65      	36B3      	PVCCIN_CPU0         
          	               	BY67      	36B3      	PVCCIN_CPU0         
          	               	BY69      	36B3      	PVCCIN_CPU0         
          	               	BY71      	36B3      	PVCCIN_CPU0         
          	               	BY73      	36B3      	PVCCIN_CPU0         
          	               	BY75      	36B3      	PVCCIN_CPU0         
          	               	BY77      	36B3      	PVCCIN_CPU0         
          	               	BY79      	36B3      	PVCCIN_CPU0         
          	               	BY81      	36B3      	PVCCIN_CPU0         
          	               	BY83      	36B3      	PVCCIN_CPU0         
          	               	BY85      	36B3      	PVCCIN_CPU0         
          	               	BY87      	36B3      	PVCCIN_CPU0         
          	               	BY89      	36B3      	PVCCIN_CPU0         
          	               	C5        	42B2      	GND                 
          	               	C7        	20B3      	M_A_CPU0_SB_DQ<29>  
          	               	C9        	20B2      	M_A_CPU0_SB_DQS_DP<3>
          	               	C11       	20B3      	M_A_CPU0_SB_DQ<24>  
          	               	C13       	21B3      	M_B_CPU0_SB_DQ<28>  
          	               	C15       	21B2      	M_B_CPU0_SB_DQS_DP<3>
          	               	C17       	21B3      	M_B_CPU0_SB_DQ<24>  
          	               	C19       	20B3      	M_A_CPU0_SB_DQ<21>  
          	               	C21       	20B2      	M_A_CPU0_SB_DQS_DP<2>
          	               	C23       	20B3      	M_A_CPU0_SB_DQ<16>  
          	               	C25       	20B3      	M_A_CPU0_SB_DQ<13>  
          	               	C27       	20B2      	M_A_CPU0_SB_DQS_DP<1>
          	               	C29       	20A3      	M_A_CPU0_SB_DQ<8>   
          	               	C31       	20A3      	M_A_CPU0_SB_CB<1>   
          	               	C33       	20B2      	M_A_CPU0_SB_DQS_DP<9>
          	               	C35       	20A3      	M_A_CPU0_SB_CB<4>   
          	               	C37       	20A2      	M_A_CPU0_SB_CS_N<1> 
          	               	C39       	42B2      	GND                 
          	               	C41       	20B2      	M_A_CPU0_SB_CA<2>   
          	               	C43       	20A3      	M_A_CPU0_CLK_DP<0>  
          	               	C45       	42B2      	GND                 
          	               	C48       	20B2      	M_A_CPU0_SA_CA<6>   
          	               	C50       	20B2      	M_A_CPU0_SA_CA<4>   
          	               	C52       	42B2      	GND                 
          	               	C54       	20A2      	M_A_CPU0_SA_CS_N<0> 
          	               	C56       	20B3      	M_A_CPU0_SA_CB<5>   
          	               	C58       	20B2      	M_A_CPU0_SA_DQS_DP<4>
          	               	C60       	20B3      	M_A_CPU0_SA_CB<0>   
          	               	C62       	20B3      	M_A_CPU0_SA_DQ<29>  
          	               	C64       	20B2      	M_A_CPU0_SA_DQS_DP<3>
          	               	C66       	20B3      	M_A_CPU0_SA_DQ<24>  
          	               	C68       	20B3      	M_A_CPU0_SA_DQ<21>  
          	               	C70       	20B2      	M_A_CPU0_SA_DQS_DP<2>
          	               	C72       	42B2      	GND                 
          	               	C74       	42B2      	GND                 
          	               	C76       	20B3      	M_A_CPU0_SA_DQ<4>   
          	               	C78       	42B2      	GND                 
          	               	C80       	42B2      	GND                 
          	               	C82       	42B2      	GND                 
          	               	C84       	38A2      	PVCCFA_EHV_FIVRA_CPU0
          	               	C86       	42B2      	GND                 
          	               	C88       	38A2      	PVCCFA_EHV_FIVRA_CPU0
          	               	CA3       	40B1      	GND                 
          	               	CA5       	33B2      	UPI_CPU0_CPU1_P1P0_DN<22>
          	               	CA7       	37B2      	PVCCD_HV_CPU0       
          	               	CA9       	29A3      	P5E_CPU0_PE1_RX_DP<6>
          	               	CA11      	16B4      	VSENSE_PVCCINFAON_CPU0_DP
          	               	CA13      	29A2      	P5E_CPU0_PE1_TX_DN<7>
          	               	CA15      	37B3      	PVCCINFAON_CPU0     
          	               	CA17      	28B2      	DMI_CPU0_PCH_TX_DP<1>
          	               	CA19      	28B2      	DMI_CPU0_PCH_TX_DN<0>
          	               	CA21      	19B3      	NC_CPU0_DMI_APROBE<0>
          	               	CA23      	19B3      	NC_CPU0_UPI1_APROBE<1>
          	               	CA25      	14B3      	SMB_PEHPCPU0_GTL_SCL
          	               	CA27      	19B3      	TP_TRC_CPU0_PTI<6>  
          	               	CA29      	19B3      	TP_TRC_CPU0_PTI<4>  
          	               	CA31      	40B1      	GND                 
          	               	CA33      	36B3      	PVCCIN_CPU0         
          	               	CA35      	36B3      	PVCCIN_CPU0         
          	               	CA37      	36B3      	PVCCIN_CPU0         
          	               	CA39      	36B3      	PVCCIN_CPU0         
          	               	CA41      	36B3      	PVCCIN_CPU0         
          	               	CA43      	36B3      	PVCCIN_CPU0         
          	               	CA45      	36B3      	PVCCIN_CPU0         
          	               	CA48      	36B3      	PVCCIN_CPU0         
          	               	CA50      	36B3      	PVCCIN_CPU0         
          	               	CA52      	36B3      	PVCCIN_CPU0         
          	               	CA54      	36B3      	PVCCIN_CPU0         
          	               	CA56      	36B3      	PVCCIN_CPU0         
          	               	CA58      	36B3      	PVCCIN_CPU0         
          	               	CA60      	36B3      	PVCCIN_CPU0         
          	               	CA62      	36B3      	PVCCIN_CPU0         
          	               	CA64      	36B3      	PVCCIN_CPU0         
          	               	CA66      	36B3      	PVCCIN_CPU0         
          	               	CA68      	36B3      	PVCCIN_CPU0         
          	               	CA70      	36B3      	PVCCIN_CPU0         
          	               	CA72      	36B3      	PVCCIN_CPU0         
          	               	CA74      	36B3      	PVCCIN_CPU0         
          	               	CA76      	36B3      	PVCCIN_CPU0         
          	               	CA78      	36B3      	PVCCIN_CPU0         
          	               	CA80      	36B3      	PVCCIN_CPU0         
          	               	CA82      	36B3      	PVCCIN_CPU0         
          	               	CA84      	36B3      	PVCCIN_CPU0         
          	               	CA86      	36B3      	PVCCIN_CPU0         
          	               	CA88      	36B3      	PVCCIN_CPU0         
          	               	CA90      	36B3      	PVCCIN_CPU0         
          	               	CB2       	33B3      	UPI_CPU1_CPU0_P0P1_DP<23>
          	               	CB4       	40B1      	GND                 
          	               	CB6       	33B2      	UPI_CPU0_CPU1_P1P0_DP<22>
          	               	CB8       	40B1      	GND                 
          	               	CB10      	29A3      	P5E_CPU0_PE1_RX_DN<6>
          	               	CB12      	40B1      	GND                 
          	               	CB14      	29A2      	P5E_CPU0_PE1_TX_DN<6>
          	               	CB16      	40B1      	GND                 
          	               	CB18      	28B2      	DMI_CPU0_PCH_TX_DP<2>
          	               	CB20      	40B1      	GND                 
          	               	CB22      	40B1      	GND                 
          	               	CB24      	40B1      	GND                 
          	               	CB26      	40B1      	GND                 
          	               	CB28      	40B1      	GND                 
          	               	CB30      	19B3      	TP_TRC_CPU0_PTI0_CLK
          	               	CB32      	40B1      	GND                 
          	               	CB34      	40B1      	GND                 
          	               	CB36      	40B1      	GND                 
          	               	CB38      	40B1      	GND                 
          	               	CB40      	40B1      	GND                 
          	               	CB42      	40B1      	GND                 
          	               	CB44      	40B1      	GND                 
          	               	CB47      	40B1      	GND                 
          	               	CB49      	40B1      	GND                 
          	               	CB51      	40B1      	GND                 
          	               	CB53      	40B1      	GND                 
          	               	CB55      	40A2      	GND                 
          	               	CB57      	40A2      	GND                 
          	               	CB59      	40A2      	GND                 
          	               	CB61      	36B3      	PVCCIN_CPU0         
          	               	CB63      	40A2      	GND                 
          	               	CB65      	40A2      	GND                 
          	               	CB67      	40A2      	GND                 
          	               	CB69      	40A2      	GND                 
          	               	CB71      	40A2      	GND                 
          	               	CB73      	40A2      	GND                 
          	               	CB75      	36B3      	PVCCIN_CPU0         
          	               	CB77      	36B3      	PVCCIN_CPU0         
          	               	CB79      	40A2      	GND                 
          	               	CB81      	40A2      	GND                 
          	               	CB83      	40A2      	GND                 
          	               	CB85      	40A2      	GND                 
          	               	CB87      	40A2      	GND                 
          	               	CB89      	40A2      	GND                 
          	               	CC3       	33B3      	UPI_CPU1_CPU0_P0P1_DN<22>
          	               	CC5       	40A2      	GND                 
          	               	CC7       	33B2      	UPI_CPU0_CPU1_P1P0_DN<21>
          	               	CC9       	40A2      	GND                 
          	               	CC11      	29A3      	P5E_CPU0_PE1_RX_DN<5>
          	               	CC13      	40A2      	GND                 
          	               	CC15      	29A2      	P5E_CPU0_PE1_TX_DP<6>
          	               	CC17      	40A2      	GND                 
          	               	CC19      	28B2      	DMI_CPU0_PCH_TX_DN<2>
          	               	CC21      	19B2      	NC_CPU0_PE1_APROBE<1>
          	               	CC23      	19B2      	NC_CPU0_PE2_APROBE<0>
          	               	CC25      	14B3      	TP_H_SBLINK7_CPU0_PMDOWN
          	               	CC27      	19B3      	TP_TRC_CPU0_PTI<2>  
          	               	CC29      	19B3      	TP_TP_TRC_CPU0_PTI_MON<0>
          	               	CC31      	40A2      	GND                 
          	               	CC33      	36B3      	PVCCIN_CPU0         
          	               	CC35      	36B3      	PVCCIN_CPU0         
          	               	CC37      	36B3      	PVCCIN_CPU0         
          	               	CC39      	36B3      	PVCCIN_CPU0         
          	               	CC41      	36B3      	PVCCIN_CPU0         
          	               	CC43      	36B3      	PVCCIN_CPU0         
          	               	CC45      	36B3      	PVCCIN_CPU0         
          	               	CC48      	36B3      	PVCCIN_CPU0         
          	               	CC50      	36A4      	PVCCIN_CPU0         
          	               	CC52      	36A4      	PVCCIN_CPU0         
          	               	CC54      	36A4      	PVCCIN_CPU0         
          	               	CC56      	36A4      	PVCCIN_CPU0         
          	               	CC58      	36A4      	PVCCIN_CPU0         
          	               	CC60      	36A4      	PVCCIN_CPU0         
          	               	CC62      	40A2      	GND                 
          	               	CC64      	16B3      	NC_CPU0_LGSSPARE4   
          	               	CC66      	17B2      	NC_CPU0_MDFI_DIE01_EW1
          	               	CC68      	37B2      	PVPP_HBM_CPU0       
          	               	CC70      	40A2      	GND                 
          	               	CC72      	40B2      	GND                 
          	               	CC74      	40B2      	GND                 
          	               	CC76      	36A4      	PVCCIN_CPU0         
          	               	CC78      	36A4      	PVCCIN_CPU0         
          	               	CC80      	36A4      	PVCCIN_CPU0         
          	               	CC82      	36A4      	PVCCIN_CPU0         
          	               	CC84      	36A4      	PVCCIN_CPU0         
          	               	CC86      	36A4      	PVCCIN_CPU0         
          	               	CC88      	36A4      	PVCCIN_CPU0         
          	               	CC90      	36A4      	PVCCIN_CPU0         
          	               	CD2       	33B3      	UPI_CPU1_CPU0_P0P1_DP<22>
          	               	CD4       	40B2      	GND                 
          	               	CD6       	33B2      	UPI_CPU0_CPU1_P1P0_DP<21>
          	               	CD8       	40B2      	GND                 
          	               	CD10      	29A3      	P5E_CPU0_PE1_RX_DP<5>
          	               	CD12      	40B2      	GND                 
          	               	CD14      	29A2      	P5E_CPU0_PE1_TX_DP<5>
          	               	CD16      	40B2      	GND                 
          	               	CD18      	28B2      	DMI_CPU0_PCH_TX_DN<3>
          	               	CD20      	40B2      	GND                 
          	               	CD22      	17B2      	NC_CPU0_MDFI_DIE10_NS1
          	               	CD24      	14B3      	TP_H_SBLINK4_CPU0_PMDOWN
          	               	CD26      	17B2      	NC_CPU0_MDFI_DIE10_EW0
          	               	CD28      	19B3      	TP_TRC_CPU0_PTI_MON<1>
          	               	CD30      	17B2      	NC_CPU0_MDFI_DIE10_EW1
          	               	CD32      	36A4      	PVCCIN_CPU0         
          	               	CD34      	36A4      	PVCCIN_CPU0         
          	               	CD36      	36A4      	PVCCIN_CPU0         
          	               	CD38      	36A4      	PVCCIN_CPU0         
          	               	CD40      	36A4      	PVCCIN_CPU0         
          	               	CD42      	36A4      	PVCCIN_CPU0         
          	               	CD44      	36A4      	PVCCIN_CPU0         
          	               	CD47      	36B4      	PVCCIN_CPU0         
          	               	CD49      	36B4      	PVCCIN_CPU0         
          	               	CD51      	36B4      	PVCCIN_CPU0         
          	               	CD53      	36B4      	PVCCIN_CPU0         
          	               	CD55      	36B4      	PVCCIN_CPU0         
          	               	CD57      	36B4      	PVCCIN_CPU0         
          	               	CD59      	36B4      	PVCCIN_CPU0         
          	               	CD61      	40B2      	GND                 
          	               	CD63      	15B4      	SMB_S3M_CPU0_SDA    
          	               	CD65      	15B2      	TP_SGPIO_S3M_CPU0_RST_R_N
          	               	CD67      	37B2      	PVPP_HBM_CPU0       
          	               	CD69      	18B3      	TP_CPU0_SPARE11     
          	               	CD71      	13B3      	NC_CLK_PFT_OUT_CPU0_DP
          	               	CD73      	35B2      	NC                  
          	               	CD75      	40B2      	GND                 
          	               	CD77      	40B2      	GND                 
          	               	CD79      	36B4      	PVCCIN_CPU0         
          	               	CD81      	36B4      	PVCCIN_CPU0         
          	               	CD83      	36B4      	PVCCIN_CPU0         
          	               	CD85      	36B4      	PVCCIN_CPU0         
          	               	CD87      	36B4      	PVCCIN_CPU0         
          	               	CD89      	36B4      	PVCCIN_CPU0         
          	               	CE1       	33B3      	UPI_CPU1_CPU0_P0P1_DP<21>
          	               	CE3       	40B2      	GND                 
          	               	CE5       	33B2      	UPI_CPU0_CPU1_P1P0_DP<20>
          	               	CE7       	37B2      	PVCCD_HV_CPU0       
          	               	CE9       	29A3      	P5E_CPU0_PE1_RX_DP<4>
          	               	CE11      	16B4      	VSENSE_PVCCINFAON_CPU0_DN
          	               	CE13      	29A2      	P5E_CPU0_PE1_TX_DN<5>
          	               	CE15      	37B1      	PVCCINFAON_CPU0     
          	               	CE17      	28B2      	DMI_CPU0_PCH_TX_DP<3>
          	               	CE19      	37B3      	PVCCINFAON_CPU0     
          	               	CE21      	19B2      	NC_CPU0_PE1_APROBE<0>
          	               	CE23      	14B3      	TP_H_SBLINK6_CPU0_PMDOWN
          	               	CE25      	14B3      	TP_H_SBLINK4_CPU0_PMSYNC
          	               	CE60      	40B2      	GND                 
          	               	CE62      	16B3      	NC_CPU0_LGSSPARE3   
          	               	CE64      	15B4      	SMB_S3M_CPU0_SCL    
          	               	CE66      	40B2      	GND                 
          	               	CE68      	37B2      	PVPP_HBM_CPU0       
          	               	CE70      	13B3      	NC_CLK_PFT_OUT_CPU0_DN
          	               	CE72      	40B2      	GND                 
          	               	CE74      	38A3      	PVCCFA_EHV_FIVRA_CPU0
          	               	CE76      	40B2      	GND                 
          	               	CE78      	40B2      	GND                 
          	               	CE80      	36B4      	PVCCIN_CPU0         
          	               	CE82      	36B4      	PVCCIN_CPU0         
          	               	CE84      	36B4      	PVCCIN_CPU0         
          	               	CE86      	36B4      	PVCCIN_CPU0         
          	               	CE88      	36B4      	PVCCIN_CPU0         
          	               	CE90      	36B4      	PVCCIN_CPU0         
          	               	CF2       	33B3      	UPI_CPU1_CPU0_P0P1_DN<21>
          	               	CF4       	40B2      	GND                 
          	               	CF6       	33B2      	UPI_CPU0_CPU1_P1P0_DN<20>
          	               	CF8       	40B2      	GND                 
          	               	CF10      	29A3      	P5E_CPU0_PE1_RX_DN<4>
          	               	CF12      	40B2      	GND                 
          	               	CF14      	29A2      	P5E_CPU0_PE1_TX_DN<4>
          	               	CF16      	40B2      	GND                 
          	               	CF18      	28B2      	DMI_CPU0_PCH_TX_DN<4>
          	               	CF20      	40B2      	GND                 
          	               	CF22      	17B2      	NC_CPU0_MDFI_DIE10_NS0
          	               	CF24      	14B3      	TP_H_SBLINK7_CPU0_PMSYNC
          	               	CF26      	14B2      	H_CPU0_MEMHOT_OUT_LVC1_R_N
          	               	CF61      	15B2      	PUD_PCH_BOOT_MODE_CPU0
          	               	CF63      	15B2      	TP_SGPIO_S3M_CPU0_GSXCLK_R
          	               	CF65      	15B2      	TP_SGPIO_S3M_CPU0_GSXDOUT_R
          	               	CF67      	37B2      	PVPP_HBM_CPU0       
          	               	CF69      	40B2      	GND                 
          	               	CF71      	40B2      	GND                 
          	               	CF73      	35B2      	NC                  
          	               	CF75      	35B2      	NC                  
          	               	CF77      	35B2      	NC                  
          	               	CF79      	36B4      	PVCCIN_CPU0         
          	               	CF81      	36B4      	PVCCIN_CPU0         
          	               	CF83      	36B4      	PVCCIN_CPU0         
          	               	CF85      	36B4      	PVCCIN_CPU0         
          	               	CF87      	36B4      	PVCCIN_CPU0         
          	               	CF89      	36B4      	PVCCIN_CPU0         
          	               	CF91      	36B4      	PVCCIN_CPU0         
          	               	CG1       	40B2      	GND                 
          	               	CG3       	33B3      	UPI_CPU1_CPU0_P0P1_DN<20>
          	               	CG5       	40B2      	GND                 
          	               	CG7       	33B2      	UPI_CPU0_CPU1_P1P0_DN<19>
          	               	CG9       	40B2      	GND                 
          	               	CG11      	29A3      	P5E_CPU0_PE1_RX_DN<3>
          	               	CG13      	40B2      	GND                 
          	               	CG15      	29A2      	P5E_CPU0_PE1_TX_DP<4>
          	               	CG17      	40B2      	GND                 
          	               	CG19      	28B2      	DMI_CPU0_PCH_TX_DP<4>
          	               	CG21      	40B2      	GND                 
          	               	CG23      	40B2      	GND                 
          	               	CG25      	40B2      	GND                 
          	               	CG60      	18B3      	TP_CPU0_SPARE10     
          	               	CG62      	40B2      	GND                 
          	               	CG64      	40B2      	GND                 
          	               	CG66      	14B3      	FM_CPU0_SKTOCC_LVT3_N
          	               	CG68      	37B2      	PVPP_HBM_CPU0       
          	               	CG70      	40B2      	GND                 
          	               	CG72      	40B2      	GND                 
          	               	CG74      	40B2      	GND                 
          	               	CG76      	35B2      	NC                  
          	               	CG78      	40B2      	GND                 
          	               	CG80      	36B4      	PVCCIN_CPU0         
          	               	CG82      	36B4      	PVCCIN_CPU0         
          	               	CG84      	36B4      	PVCCIN_CPU0         
          	               	CG86      	36B4      	PVCCIN_CPU0         
          	               	CG88      	36B4      	PVCCIN_CPU0         
          	               	CG90      	36B4      	PVCCIN_CPU0         
          	               	CH2       	33B3      	UPI_CPU1_CPU0_P0P1_DP<20>
          	               	CH4       	40B2      	GND                 
          	               	CH6       	33B2      	UPI_CPU0_CPU1_P1P0_DP<19>
          	               	CH8       	40B2      	GND                 
          	               	CH10      	29A3      	P5E_CPU0_PE1_RX_DP<3>
          	               	CH12      	40B2      	GND                 
          	               	CH14      	29A2      	P5E_CPU0_PE1_TX_DP<3>
          	               	CH16      	40B2      	GND                 
          	               	CH18      	28B2      	DMI_CPU0_PCH_TX_DP<5>
          	               	CH20      	40B2      	GND                 
          	               	CH22      	14B3      	PD_CPU0_ENH_MCECC_DIS
          	               	CH24      	14B3      	TP_H_SBLINK6_CPU0_PMSYNC
          	               	CH26      	14B3      	TP_H_SBLINK3_CPU0_PMSYNC
          	               	CH61      	18B3      	TP_CPU0_SPARE9      
          	               	CH63      	15B2      	TP_SGPIO_S3M_CPU0_GSXDIN
          	               	CH65      	15B2      	PU_S3M_CPU0_CPLD_STATUS
          	               	CH67      	40B2      	GND                 
          	               	CH69      	17B2      	NC_CPU0_MDFI_DIE11_EW1
          	               	CH71      	15B4      	TP_PWRGD_S0_PWROK_CPU0_LVC1
          	               	CH73      	40B2      	GND                 
          	               	CH75      	35B2      	NC                  
          	               	CH77      	35B2      	NC                  
          	               	CH79      	40B2      	GND                 
          	               	CH81      	36B4      	PVCCIN_CPU0         
          	               	CH83      	40B2      	GND                 
          	               	CH85      	40B2      	GND                 
          	               	CH87      	40B2      	GND                 
          	               	CH89      	40B2      	GND                 
          	               	CH91      	36B4      	PVCCIN_CPU0         
          	               	CJ1       	33B3      	UPI_CPU1_CPU0_P0P1_DP<19>
          	               	CJ3       	37B1      	PVCCINFAON_CPU0     
          	               	CJ5       	33B2      	UPI_CPU0_CPU1_P1P0_DP<18>
          	               	CJ7       	37B1      	PVCCINFAON_CPU0     
          	               	CJ9       	29A3      	P5E_CPU0_PE1_RX_DP<2>
          	               	CJ11      	37B3      	PVCCINFAON_CPU0     
          	               	CJ13      	29A2      	P5E_CPU0_PE1_TX_DN<3>
          	               	CJ15      	37B1      	PVCCINFAON_CPU0     
          	               	CJ17      	28B2      	DMI_CPU0_PCH_TX_DN<5>
          	               	CJ19      	37B3      	PVCCINFAON_CPU0     
          	               	CJ21      	15B4      	TP_IBL_GRST_WARN_PLD_R_N
          	               	CJ23      	15B2      	TP_I2C_S3M_RTC_CPU0_SDA
          	               	CJ25      	15B2      	TP_I2C_S3M_RTC_CPU0_ALERT_N
          	               	CJ60      	40B2      	GND                 
          	               	CJ62      	14B2      	NC_CPU0_VIEWPIN_DIE11<0>
          	               	CJ64      	15B2      	PU_S3M_CPU0_CPLD_CONFD
          	               	CJ66      	15B2      	TP_SGPIO_S3M_CPU0_GSXDLOAD_R
          	               	CJ68      	17B2      	NC_CPU0_MDFI_DIE11_NS0
          	               	CJ70      	17B2      	NC_CPU0_MDFI_DIE11_EW0
          	               	CJ72      	13B3      	PUD_XTAL_CPU0_MODE1 
          	               	CJ74      	35B2      	NC                  
          	               	CJ76      	40B2      	GND                 
          	               	CJ78      	35B2      	NC                  
          	               	CJ80      	40B2      	GND                 
          	               	CJ82      	36B4      	PVCCIN_CPU0         
          	               	CJ84      	36B4      	PVCCIN_CPU0         
          	               	CJ86      	36B4      	PVCCIN_CPU0         
          	               	CJ88      	36B4      	PVCCIN_CPU0         
          	               	CJ90      	36B4      	PVCCIN_CPU0         
          	               	CK2       	33B3      	UPI_CPU1_CPU0_P0P1_DN<19>
          	               	CK4       	40B2      	GND                 
          	               	CK6       	33B2      	UPI_CPU0_CPU1_P1P0_DN<18>
          	               	CK8       	40B2      	GND                 
          	               	CK10      	29A3      	P5E_CPU0_PE1_RX_DN<2>
          	               	CK12      	40B2      	GND                 
          	               	CK14      	29A2      	P5E_CPU0_PE1_TX_DN<2>
          	               	CK16      	40B2      	GND                 
          	               	CK18      	28B2      	DMI_CPU0_PCH_TX_DN<6>
          	               	CK20      	40B2      	GND                 
          	               	CK22      	15B2      	TP_FM_IBL_SYS_RST_CPU0_N
          	               	CK24      	15B4      	TP_CPU0_PWRBTN_N    
          	               	CK26      	40B2      	GND                 
          	               	CK61      	18B3      	TP_CPU0_SPARE8      
          	               	CK63      	40A2      	GND                 
          	               	CK65      	15B2      	FM_S3M_CPU0_CPLD_CONFIG_N
          	               	CK67      	17B2      	NC_CPU0_MDFI_DIE11_NS1
          	               	CK69      	40A2      	GND                 
          	               	CK71      	19B3      	PU_CPU0_UPI3_AC_COUPLING
          	               	CK73      	38A3      	PVCCFA_EHV_FIVRA_CPU0
          	               	CK75      	35B2      	NC                  
          	               	CK77      	35B2      	NC                  
          	               	CK79      	38B3      	PVCCFA_EHV_FIVRA_CPU0
          	               	CK81      	40A2      	GND                 
          	               	CK83      	36B4      	PVCCIN_CPU0         
          	               	CK85      	36B4      	PVCCIN_CPU0         
          	               	CK87      	36B4      	PVCCIN_CPU0         
          	               	CK89      	36B4      	PVCCIN_CPU0         
          	               	CK91      	36B4      	PVCCIN_CPU0         
          	               	CL1       	40A2      	GND                 
          	               	CL3       	33B3      	UPI_CPU1_CPU0_P0P1_DN<18>
          	               	CL5       	40A2      	GND                 
          	               	CL7       	33B2      	UPI_CPU0_CPU1_P1P0_DN<17>
          	               	CL9       	40A2      	GND                 
          	               	CL11      	29A3      	P5E_CPU0_PE1_RX_DN<1>
          	               	CL13      	40A2      	GND                 
          	               	CL15      	29A2      	P5E_CPU0_PE1_TX_DP<2>
          	               	CL17      	40A2      	GND                 
          	               	CL19      	28B2      	DMI_CPU0_PCH_TX_DP<6>
          	               	CL21      	14B3      	TP_IBL_PLT_RST_SYNC_N
          	               	CL23      	15B2      	TP_I2C_S3M_RTC_CPU0_SCL
          	               	CL25      	14B3      	TP_H_SBLINK2_CPU0_PMSYNC
          	               	CL60      	18B3      	TP_CPU0_SPARE7      
          	               	CL62      	40A2      	GND                 
          	               	CL64      	14B2      	NC_CPU0_VIEWPIN_DIE11<3>
          	               	CL66      	15B2      	TP_CPU0_SSC_SYNC    
          	               	CL68      	19B2      	NC_CPU0_PE3_APROBE<0>
          	               	CL70      	18B3      	TP_CPU0_SPARE12     
          	               	CL72      	13B3      	PUD_XTAL_CPU0_MODE0 
          	               	CL74      	40A2      	GND                 
          	               	CL76      	35B2      	NC                  
          	               	CL78      	40A2      	GND                 
          	               	CL80      	40A2      	GND                 
          	               	CL82      	40A2      	GND                 
          	               	CL84      	36B4      	PVCCIN_CPU0         
          	               	CL86      	36B4      	PVCCIN_CPU0         
          	               	CL88      	36B4      	PVCCIN_CPU0         
          	               	CL90      	36B4      	PVCCIN_CPU0         
          	               	CM2       	33B3      	UPI_CPU1_CPU0_P0P1_DP<18>
          	               	CM4       	40A2      	GND                 
          	               	CM6       	33B2      	UPI_CPU0_CPU1_P1P0_DP<17>
          	               	CM8       	40A2      	GND                 
          	               	CM10      	29A3      	P5E_CPU0_PE1_RX_DP<1>
          	               	CM12      	40A2      	GND                 
          	               	CM14      	29A2      	P5E_CPU0_PE1_TX_DP<1>
          	               	CM16      	40A2      	GND                 
          	               	CM18      	28B2      	DMI_CPU0_PCH_TX_DN<7>
          	               	CM20      	40A2      	GND                 
          	               	CM22      	40A2      	GND                 
          	               	CM24      	40A2      	GND                 
          	               	CM26      	14B3      	TP_H_SBLINK3_CPU0_PMDOWN
          	               	CM61      	40A2      	GND                 
          	               	CM63      	14B2      	NC_CPU0_VIEWPIN_DIE11<2>
          	               	CM65      	40A2      	GND                 
          	               	CM67      	40B2      	GND                 
          	               	CM69      	19B2      	NC_CPU0_PE3_APROBE<1>
          	               	CM71      	14B3      	SMB_S3M_CPU0_PIROM_3V3AUX_SDA_1
          	               	CM73      	38B3      	PVCCFA_EHV_FIVRA_CPU0
          	               	CM75      	35B2      	NC                  
          	               	CM77      	35B2      	NC                  
          	               	CM79      	40B2      	GND                 
          	               	CM81      	40B2      	GND                 
          	               	CM83      	40B2      	GND                 
          	               	CM85      	40B2      	GND                 
          	               	CM87      	36B4      	PVCCIN_CPU0         
          	               	CM89      	36B4      	PVCCIN_CPU0         
          	               	CM91      	36B4      	PVCCIN_CPU0         
          	               	CN1       	33B3      	UPI_CPU1_CPU0_P0P1_DP<17>
          	               	CN3       	37B1      	PVCCINFAON_CPU0     
          	               	CN5       	33B2      	UPI_CPU0_CPU1_P1P0_DP<16>
          	               	CN7       	37B1      	PVCCINFAON_CPU0     
          	               	CN9       	29A3      	P5E_CPU0_PE1_RX_DP<0>
          	               	CN11      	37B1      	PVCCINFAON_CPU0     
          	               	CN13      	29A2      	P5E_CPU0_PE1_TX_DN<1>
          	               	CN15      	37B1      	PVCCINFAON_CPU0     
          	               	CN17      	28B2      	DMI_CPU0_PCH_TX_DP<7>
          	               	CN19      	37B3      	PVCCINFAON_CPU0     
          	               	CN21      	15B4      	TP_IBL_SLPS4_CPU0_R_N
          	               	CN23      	15B4      	TP_FM_IBL_ADR_ACK_CPU0
          	               	CN25      	14B3      	H_CPU0_PMSYNC_CPU1_R
          	               	CN60      	16B3      	NC_CPU0_LGSSPARE1   
          	               	CN62      	14B2      	NC_CPU0_VIEWPIN_DIE11<1>
          	               	CN64      	37B1      	PVCCINFAON_CPU0     
          	               	CN66      	37B1      	PVCCINFAON_CPU0     
          	               	CN68      	40B2      	GND                 
          	               	CN70      	40B2      	GND                 
          	               	CN72      	40B2      	GND                 
          	               	CN74      	40B2      	GND                 
          	               	CN76      	40B2      	GND                 
          	               	CN78      	38B3      	PVCCFA_EHV_FIVRA_CPU0
          	               	CN80      	35B3      	GND                 
          	               	CN82      	35B3      	GND                 
          	               	CN84      	40B2      	GND                 
          	               	CN86      	40B2      	GND                 
          	               	CN88      	36B4      	PVCCIN_CPU0         
          	               	CN90      	36B4      	PVCCIN_CPU0         
          	               	CP2       	33B3      	UPI_CPU1_CPU0_P0P1_DN<17>
          	               	CP4       	40B2      	GND                 
          	               	CP6       	33B2      	UPI_CPU0_CPU1_P1P0_DN<16>
          	               	CP8       	40B2      	GND                 
          	               	CP10      	29A3      	P5E_CPU0_PE1_RX_DN<0>
          	               	CP12      	40B2      	GND                 
          	               	CP14      	29A2      	P5E_CPU0_PE1_TX_DN<0>
          	               	CP16      	40B2      	GND                 
          	               	CP18      	40B2      	GND                 
          	               	CP20      	14B2      	H_CPU0_PM_FAST_WAKE_N
          	               	CP22      	15B4      	TP_JTAG_CPU0_PLD_TDO
          	               	CP24      	15B4      	TP_FM_IBL_ADR_COMPLETE_CPU0_R
          	               	CP26      	14B3      	TP_H_SBLINK2_CPU0_PMDOWN
          	               	CP61      	16B3      	NC_CPU0_LGSSPARE5   
          	               	CP63      	37B3      	PVCCINFAON_CPU0     
          	               	CP65      	37B1      	PVCCINFAON_CPU0     
          	               	CP67      	37B1      	PVCCINFAON_CPU0     
          	               	CP69      	19B3      	NC_CPU0_UPI3_APROBE<0>
          	               	CP71      	14B3      	PD_PIROM_CPU0_ADDR2 
          	               	CP73      	38B3      	PVCCFA_EHV_FIVRA_CPU0
          	               	CP75      	40B2      	GND                 
          	               	CP77      	40B2      	GND                 
          	               	CP79      	40B2      	GND                 
          	               	CP81      	35B3      	GND                 
          	               	CP83      	40B2      	GND                 
          	               	CP85      	30A2      	P5E_CPU0_PE3_TX_DN<15>
          	               	CP87      	40B2      	GND                 
          	               	CP89      	36B4      	PVCCIN_CPU0         
          	               	CP91      	40B2      	GND                 
          	               	CR1       	40B2      	GND                 
          	               	CR3       	33B3      	UPI_CPU1_CPU0_P0P1_DN<16>
          	               	CR5       	40B2      	GND                 
          	               	CR7       	33B2      	UPI_CPU0_CPU1_P1P0_DN<15>
          	               	CR9       	40B2      	GND                 
          	               	CR11      	40B2      	GND                 
          	               	CR13      	40B2      	GND                 
          	               	CR15      	29A2      	P5E_CPU0_PE1_TX_DP<0>
          	               	CR17      	40B2      	GND                 
          	               	CR19      	14B3      	TP_H_SBLINK5_CPU0_PMSYNC
          	               	CR21      	15B4      	TP_IBL_SLPS3_CPU0_R_N
          	               	CR23      	14B2      	NC_CPU0_VIEWPIN_DIE10<0>
          	               	CR25      	17B2      	NC_CPU0_VIEWPIN_GNR2
          	               	CR60      	16B3      	NC_CPU0_LGSSPARE0   
          	               	CR62      	40B2      	GND                 
          	               	CR64      	40B2      	GND                 
          	               	CR66      	37B1      	PVCCINFAON_CPU0     
          	               	CR68      	19B3      	NC_CPU0_UPI3_APROBE<1>
          	               	CR70      	14B3      	PD_PIROM_CPU0_ADDR0 
          	               	CR72      	14B3      	PU_PIROM_CPU0_SM_WP 
          	               	CR74      	35B2      	NC                  
          	               	CR76      	35B2      	NC                  
          	               	CR78      	40B2      	GND                 
          	               	CR80      	35B3      	GND                 
          	               	CR82      	35B3      	GND                 
          	               	CR84      	40B2      	GND                 
          	               	CR86      	30B2      	P5E_CPU0_PE3_TX_DP<15>
          	               	CR88      	40B2      	GND                 
          	               	CR90      	40B2      	GND                 
          	               	CT2       	33B3      	UPI_CPU1_CPU0_P0P1_DP<16>
          	               	CT4       	40B2      	GND                 
          	               	CT6       	33B2      	UPI_CPU0_CPU1_P1P0_DP<15>
          	               	CT8       	40B2      	GND                 
          	               	CT10      	40B2      	GND                 
          	               	CT12      	40B2      	GND                 
          	               	CT14      	30B2      	P5E_CPU0_PE2_TX_DP<0>
          	               	CT16      	40B2      	GND                 
          	               	CT18      	13B3      	I3C_SPD_DDREFGH_CPU0_SDA
          	               	CT20      	13B2      	PD_CPU0_TXT_PLTEN   
          	               	CT22      	15B4      	TP_JTAG_CPU0_PLD_TDI
          	               	CT24      	15B4      	TP_FM_IBL_ADR_TRIGGER_CPU0_R
          	               	CT26      	17B2      	NC_CPU0_VIEWPIN_GNR0
          	               	CT61      	13B2      	PU_CPU0_SOCKET_ID2  
          	               	CT63      	37B3      	PVCCINFAON_CPU0     
          	               	CT65      	37B1      	PVCCINFAON_CPU0     
          	               	CT67      	37B1      	PVCCINFAON_CPU0     
          	               	CT69      	40B2      	GND                 
          	               	CT71      	14B3      	PD_PIROM_CPU0_ADDR1 
          	               	CT73      	40B2      	GND                 
          	               	CT75      	35B2      	NC                  
          	               	CT77      	38B3      	PVCCFA_EHV_FIVRA_CPU0
          	               	CT79      	35B3      	GND                 
          	               	CT81      	40B2      	GND                 
          	               	CT83      	35B3      	GND                 
          	               	CT85      	38B3      	PVCCFA_EHV_FIVRA_CPU0
          	               	CT87      	30A2      	P5E_CPU0_PE3_TX_DN<14>
          	               	CT89      	40B2      	GND                 
          	               	CT91      	30B3      	P5E_CPU0_PE3_RX_DP<15>
          	               	CU1       	33B3      	UPI_CPU1_CPU0_P0P1_DP<15>
          	               	CU3       	37B1      	PVCCINFAON_CPU0     
          	               	CU5       	33B2      	UPI_CPU0_CPU1_P1P0_DP<14>
          	               	CU7       	37B1      	PVCCINFAON_CPU0     
          	               	CU9       	30B3      	P5E_CPU0_PE2_RX_DN<0>
          	               	CU11      	37B1      	PVCCINFAON_CPU0     
          	               	CU13      	30B2      	P5E_CPU0_PE2_TX_DN<0>
          	               	CU15      	37B1      	PVCCINFAON_CPU0     
          	               	CU17      	13B3      	I3C_SPD_DDREFGH_CPU0_SCL
          	               	CU19      	40B2      	GND                 
          	               	CU21      	40B2      	GND                 
          	               	CU23      	40B2      	GND                 
          	               	CU25      	40B2      	GND                 
          	               	CU60      	40B2      	GND                 
          	               	CU62      	16B3      	NC_CPU0_LGSSPARE2   
          	               	CU64      	37B1      	PVCCINFAON_CPU0     
          	               	CU66      	40B2      	GND                 
          	               	CU68      	40B2      	GND                 
          	               	CU70      	14B3      	SMB_S3M_CPU0_PIROM_3V3AUX_SCL_1
          	               	CU72      	40B2      	GND                 
          	               	CU74      	35B2      	NC                  
          	               	CU76      	35B2      	NC                  
          	               	CU78      	40B2      	GND                 
          	               	CU80      	35B3      	GND                 
          	               	CU82      	35B3      	GND                 
          	               	CU84      	40B2      	GND                 
          	               	CU86      	30B2      	P5E_CPU0_PE3_TX_DP<14>
          	               	CU88      	40B2      	GND                 
          	               	CU90      	30A3      	P5E_CPU0_PE3_RX_DN<15>
          	               	CV2       	33B3      	UPI_CPU1_CPU0_P0P1_DN<15>
          	               	CV4       	40B2      	GND                 
          	               	CV6       	33B2      	UPI_CPU0_CPU1_P1P0_DN<14>
          	               	CV8       	40B2      	GND                 
          	               	CV10      	30B3      	P5E_CPU0_PE2_RX_DP<0>
          	               	CV12      	40B2      	GND                 
          	               	CV14      	30B2      	P5E_CPU0_PE2_TX_DN<1>
          	               	CV16      	40A3      	GND                 
          	               	CV18      	14B3      	TP_H_SBLINK5_CPU0_PMDOWN
          	               	CV20      	15B4      	PWRGD_PLT_AUX_CPU0_LVT3
          	               	CV22      	15B4      	TP_JTAG_CPU0_PLD_TMS
          	               	CV24      	14B2      	NC_CPU0_VIEWPIN_DIE10<2>
          	               	CV26      	40A3      	GND                 
          	               	CV61      	37B3      	PVCCINFAON_CPU0     
          	               	CV63      	37B3      	PVCCINFAON_CPU0     
          	               	CV65      	37B1      	PVCCINFAON_CPU0     
          	               	CV67      	37B1      	PVCCINFAON_CPU0     
          	               	CV69      	15B4      	NC_UART_IBL_CPU0_TXD
          	               	CV71      	15B4      	NC_UART_IBL_CPU0_CTS
          	               	CV73      	35B2      	NC                  
          	               	CV75      	40A3      	GND                 
          	               	CV77      	35B2      	NC                  
          	               	CV79      	40A3      	GND                 
          	               	CV81      	35B3      	GND                 
          	               	CV83      	40A3      	GND                 
          	               	CV85      	30A2      	P5E_CPU0_PE3_TX_DN<13>
          	               	CV87      	40A3      	GND                 
          	               	CV89      	30A3      	P5E_CPU0_PE3_RX_DN<14>
          	               	CV91      	40A3      	GND                 
          	               	CW1       	40A3      	GND                 
          	               	CW3       	33B3      	UPI_CPU1_CPU0_P0P1_DP<14>
          	               	CW5       	40A3      	GND                 
          	               	CW7       	33B2      	UPI_CPU0_CPU1_P1P0_DN<13>
          	               	CW9       	40A3      	GND                 
          	               	CW11      	30B3      	P5E_CPU0_PE2_RX_DP<1>
          	               	CW13      	40A3      	GND                 
          	               	CW15      	30B2      	P5E_CPU0_PE2_TX_DP<1>
          	               	CW17      	40A3      	GND                 
          	               	CW19      	19B3      	PU_CPU0_UPI1_AC_COUPLING
          	               	CW21      	15B4      	TP_IBL_SLPS5_CPU0_R_N
          	               	CW23      	14B2      	NC_CPU0_VIEWPIN_DIE10<3>
          	               	CW25      	14B2      	NC_CPU0_VIEWPIN_DIE10<1>
          	               	CW27      	13B3      	CLK_100M_DB2000_CPU0_BCLK3_DN
          	               	CW29      	13B3      	CLK_100M_DB2000_CPU0_BCLK1_DP
          	               	CW31      	13B3      	CLK_25M_NSSC_CPU0_DN
          	               	CW33      	40A3      	GND                 
          	               	CW35      	37B2      	PVCCD_HV_CPU0       
          	               	CW37      	37B2      	PVCCD_HV_CPU0       
          	               	CW39      	14B3      	H_CPU0_PMDOWN_CPU1_R
          	               	CW41      	17B3      	NC_CPU0_HBM1_VIEWDIG1
          	               	CW43      	18B3      	TP_CPU0_SPARE6      
          	               	CW45      	14B3      	PWRGD_DRAMPWRGD_CPU0_GH_LVC1_R
          	               	CW48      	25A2      	M_F_CPU0_ALERT_N    
          	               	CW50      	26A2      	M_G_CPU0_ALERT_N    
          	               	CW52      	37B2      	PVCCD_HV_CPU0       
          	               	CW54      	37B2      	PVCCD_HV_CPU0       
          	               	CW56      	37B2      	PVCCD_HV_CPU0       
          	               	CW58      	17B2      	NC_CPU0_VIEWPIN_GNR1
          	               	CW60      	13B2      	PU_CPU0_SOCKET_ID0  
          	               	CW62      	37B3      	PVCCINFAON_CPU0     
          	               	CW64      	37B1      	PVCCINFAON_CPU0     
          	               	CW66      	37B1      	PVCCINFAON_CPU0     
          	               	CW68      	14B2      	NC_CPU0_RSVD<144>   
          	               	CW70      	40A3      	GND                 
          	               	CW72      	40A3      	GND                 
          	               	CW74      	35B2      	NC                  
          	               	CW76      	35B2      	NC                  
          	               	CW78      	40A3      	GND                 
          	               	CW80      	35B3      	GND                 
          	               	CW82      	35B3      	GND                 
          	               	CW84      	40A3      	GND                 
          	               	CW86      	30B2      	P5E_CPU0_PE3_TX_DP<13>
          	               	CW88      	40A3      	GND                 
          	               	CW90      	30B3      	P5E_CPU0_PE3_RX_DP<14>
          	               	CY2       	33B3      	UPI_CPU1_CPU0_P0P1_DN<14>
          	               	CY4       	40A3      	GND                 
          	               	CY6       	33B2      	UPI_CPU0_CPU1_P1P0_DP<13>
          	               	CY8       	40A3      	GND                 
          	               	CY10      	30B3      	P5E_CPU0_PE2_RX_DN<1>
          	               	CY12      	40A3      	GND                 
          	               	CY14      	30B2      	P5E_CPU0_PE2_TX_DP<2>
          	               	CY16      	40A3      	GND                 
          	               	CY18      	40B3      	GND                 
          	               	CY20      	15B2      	FM_S3M_CPU0_CPLD_CRC_ERROR
          	               	CY22      	15B4      	PD_JTAG_CPU0_PLD_TCK
          	               	CY24      	16B4      	NC_CPU0_DDR45_VIEWDIG0
          	               	CY26      	40B3      	GND                 
          	               	CY28      	13B3      	CLK_100M_DB2000_CPU0_BCLK1_DN
          	               	CY30      	40B3      	GND                 
          	               	CY32      	13B3      	CLK_25M_NSSC_CPU0_DP
          	               	CY34      	37B2      	PVCCD_HV_CPU0       
          	               	CY36      	37B2      	PVCCD_HV_CPU0       
          	               	CY38      	16B4      	NC_CPU0_DDR45_VIEWDIG1
          	               	CY40      	14B3      	H_CPU0_PMDOWN_PCH_R2
          	               	CY42      	13B2      	RST_CPU0_DRAM_EF_N  
          	               	CY44      	14B3      	PWRGD_DRAMPWRGD_CPU0_EF_LVC1_R
          	               	CY47      	24A2      	M_E_CPU0_ALERT_N    
          	               	CY49      	16B4      	NC_CPU0_DDR67_VIEWDIG1
          	               	CY51      	27A2      	M_H_CPU0_ALERT_N    
          	               	CY53      	37B2      	PVCCD_HV_CPU0       
          	               	CY55      	13B2      	RST_CPU0_DRAM_GH_N  
          	               	CY57      	17B2      	NC_CPU0_VIEWPIN_GNR3
          	               	CY59      	13B2      	PU_CPU0_LEGACY_SKT  
          	               	CY61      	13B2      	PU_CPU0_SOCKET_ID1  
          	               	CY63      	40B3      	GND                 
          	               	CY65      	37B1      	PVCCINFAON_CPU0     
          	               	CY67      	37B1      	PVCCINFAON_CPU0     
          	               	CY69      	15B4      	NC_UART_IBL_CPU0_RXD
          	               	CY71      	15B4      	NC_UART_IBL_CPU0_RTS
          	               	CY73      	40B3      	GND                 
          	               	CY75      	38B3      	PVCCFA_EHV_FIVRA_CPU0
          	               	CY77      	40B3      	GND                 
          	               	CY79      	38B3      	PVCCFA_EHV_FIVRA_CPU0
          	               	CY81      	40B3      	GND                 
          	               	CY83      	40B3      	GND                 
          	               	CY85      	38B3      	PVCCFA_EHV_FIVRA_CPU0
          	               	CY87      	30A2      	P5E_CPU0_PE3_TX_DN<12>
          	               	CY89      	38B3      	PVCCFA_EHV_FIVRA_CPU0
          	               	CY91      	30B3      	P5E_CPU0_PE3_RX_DP<13>
          	               	D4        	13B3      	NC_XTAL_CPU0_25M_OUT
          	               	D6        	42B2      	GND                 
          	               	D8        	42B2      	GND                 
          	               	D10       	42B2      	GND                 
          	               	D12       	42B2      	GND                 
          	               	D14       	42B2      	GND                 
          	               	D16       	42B2      	GND                 
          	               	D18       	42B2      	GND                 
          	               	D20       	42B2      	GND                 
          	               	D22       	42B2      	GND                 
          	               	D24       	42B2      	GND                 
          	               	D26       	42B2      	GND                 
          	               	D28       	42B2      	GND                 
          	               	D30       	42B2      	GND                 
          	               	D32       	42B2      	GND                 
          	               	D34       	42B2      	GND                 
          	               	D36       	42B2      	GND                 
          	               	D38       	42B2      	GND                 
          	               	D40       	42B2      	GND                 
          	               	D42       	42B2      	GND                 
          	               	D44       	42B2      	GND                 
          	               	D47       	42B2      	GND                 
          	               	D49       	42B2      	GND                 
          	               	D51       	42B2      	GND                 
          	               	D53       	42B2      	GND                 
          	               	D55       	42B2      	GND                 
          	               	D57       	42B2      	GND                 
          	               	D59       	42B2      	GND                 
          	               	D61       	42B2      	GND                 
          	               	D63       	42B2      	GND                 
          	               	D65       	42B2      	GND                 
          	               	D67       	42B2      	GND                 
          	               	D69       	42B2      	GND                 
          	               	D71       	42B2      	GND                 
          	               	D73       	20B3      	M_A_CPU0_SA_DQ<18>  
          	               	D75       	20B3      	M_A_CPU0_SA_DQ<5>   
          	               	D77       	20B2      	M_A_CPU0_SA_DQS_DP<0>
          	               	D79       	42B2      	GND                 
          	               	D81       	42B2      	GND                 
          	               	D83       	42B2      	GND                 
          	               	D85       	34B2      	UPI_CPU0_CPU1_P2P2_DP<23>
          	               	D87       	34B2      	UPI_CPU0_CPU1_P2P2_DN<21>
          	               	DA1       	33B3      	UPI_CPU1_CPU0_P0P1_DP<13>
          	               	DA3       	37B1      	PVCCINFAON_CPU0     
          	               	DA5       	33B2      	UPI_CPU0_CPU1_P1P0_DP<12>
          	               	DA7       	37B1      	PVCCINFAON_CPU0     
          	               	DA9       	30B3      	P5E_CPU0_PE2_RX_DN<2>
          	               	DA11      	37B1      	PVCCINFAON_CPU0     
          	               	DA13      	30B2      	P5E_CPU0_PE2_TX_DN<2>
          	               	DA15      	37B1      	PVCCINFAON_CPU0     
          	               	DA17      	27B3      	M_H_CPU0_SB_DQ<29>  
          	               	DA19      	40B3      	GND                 
          	               	DA21      	37B3      	PVCCINFAON_CPU0     
          	               	DA23      	40B3      	GND                 
          	               	DA25      	40B3      	GND                 
          	               	DA27      	13B3      	CLK_100M_DB2000_CPU0_BCLK3_DP
          	               	DA29      	40B3      	GND                 
          	               	DA31      	40B3      	GND                 
          	               	DA33      	40B3      	GND                 
          	               	DA35      	40B3      	GND                 
          	               	DA37      	40B3      	GND                 
          	               	DA39      	14B3      	H_CPU0_PMSYNC_PCH   
          	               	DA41      	40B3      	GND                 
          	               	DA43      	40B3      	GND                 
          	               	DA45      	16B4      	NC_CPU0_DDR67_VIEWDIG0
          	               	DA48      	40B3      	GND                 
          	               	DA50      	40B3      	GND                 
          	               	DA52      	13B2      	TP_CPU0_PROCDIS_COD_GTL_N
          	               	DA54      	40B3      	GND                 
          	               	DA56      	40B3      	GND                 
          	               	DA58      	40B3      	GND                 
          	               	DA60      	40B3      	GND                 
          	               	DA62      	40B3      	GND                 
          	               	DA64      	37B1      	PVCCINFAON_CPU0     
          	               	DA66      	40B3      	GND                 
          	               	DA68      	40B3      	GND                 
          	               	DA70      	18B3      	TP_CPU0_SPARE4      
          	               	DA72      	40B3      	GND                 
          	               	DA74      	40B3      	GND                 
          	               	DA76      	35B2      	NC                  
          	               	DA78      	35B3      	GND                 
          	               	DA80      	40B3      	GND                 
          	               	DA82      	40B3      	GND                 
          	               	DA84      	40B3      	GND                 
          	               	DA86      	30B2      	P5E_CPU0_PE3_TX_DP<12>
          	               	DA88      	40B3      	GND                 
          	               	DA90      	30A3      	P5E_CPU0_PE3_RX_DN<13>
          	               	DB2       	33B3      	UPI_CPU1_CPU0_P0P1_DN<13>
          	               	DB4       	40B3      	GND                 
          	               	DB6       	33B2      	UPI_CPU0_CPU1_P1P0_DN<12>
          	               	DB8       	40B3      	GND                 
          	               	DB10      	30B3      	P5E_CPU0_PE2_RX_DP<2>
          	               	DB12      	40B3      	GND                 
          	               	DB14      	30B2      	P5E_CPU0_PE2_TX_DN<3>
          	               	DB16      	40B3      	GND                 
          	               	DB18      	27B2      	M_H_CPU0_SB_DQS_DN<3>
          	               	DB20      	40B3      	GND                 
          	               	DB22      	40B3      	GND                 
          	               	DB24      	27B2      	M_H_CPU0_SB_DQS_DP<1>
          	               	DB26      	40B3      	GND                 
          	               	DB28      	40B3      	GND                 
          	               	DB30      	27B2      	M_H_CPU0_SB_DQS_DP<0>
          	               	DB32      	40B3      	GND                 
          	               	DB34      	40B3      	GND                 
          	               	DB36      	27B2      	M_H_CPU0_SB_DQS_DP<9>
          	               	DB38      	40B3      	GND                 
          	               	DB40      	40B3      	GND                 
          	               	DB42      	27A3      	M_H_CPU0_CLK_DP<1>  
          	               	DB44      	40B3      	GND                 
          	               	DB47      	40B3      	GND                 
          	               	DB49      	27B2      	M_H_CPU0_SA_CA<0>   
          	               	DB51      	40B3      	GND                 
          	               	DB53      	40B3      	GND                 
          	               	DB55      	27B2      	M_H_CPU0_SA_DQS_DP<4>
          	               	DB57      	40B3      	GND                 
          	               	DB59      	40B3      	GND                 
          	               	DB61      	27B2      	M_H_CPU0_SA_DQS_DP<3>
          	               	DB63      	40B3      	GND                 
          	               	DB65      	40B3      	GND                 
          	               	DB67      	27B2      	M_H_CPU0_SA_DQS_DP<2>
          	               	DB69      	40B3      	GND                 
          	               	DB71      	40B3      	GND                 
          	               	DB73      	27B2      	M_H_CPU0_SA_DQS_DN<1>
          	               	DB75      	40B3      	GND                 
          	               	DB77      	40B3      	GND                 
          	               	DB79      	35B3      	GND                 
          	               	DB81      	35B3      	GND                 
          	               	DB83      	35B3      	GND                 
          	               	DB85      	30A2      	P5E_CPU0_PE3_TX_DN<11>
          	               	DB87      	40B3      	GND                 
          	               	DB89      	30A3      	P5E_CPU0_PE3_RX_DN<12>
          	               	DB91      	40A4      	GND                 
          	               	DC1       	40A4      	GND                 
          	               	DC3       	33B3      	UPI_CPU1_CPU0_P0P1_DN<12>
          	               	DC5       	40A4      	GND                 
          	               	DC7       	33B2      	UPI_CPU0_CPU1_P1P0_DN<11>
          	               	DC9       	40A4      	GND                 
          	               	DC11      	30B3      	P5E_CPU0_PE2_RX_DP<3>
          	               	DC13      	40A4      	GND                 
          	               	DC15      	30B2      	P5E_CPU0_PE2_TX_DP<3>
          	               	DC17      	27B3      	M_H_CPU0_SB_DQ<31>  
          	               	DC19      	27B3      	M_H_CPU0_SB_DQ<25>  
          	               	DC21      	40A4      	GND                 
          	               	DC23      	27B3      	M_H_CPU0_SB_DQ<12>  
          	               	DC25      	27A3      	M_H_CPU0_SB_DQ<9>   
          	               	DC27      	40A4      	GND                 
          	               	DC29      	27A3      	M_H_CPU0_SB_DQ<4>   
          	               	DC31      	27A3      	M_H_CPU0_SB_DQ<1>   
          	               	DC33      	40A4      	GND                 
          	               	DC35      	27A3      	M_H_CPU0_SB_CB<0>   
          	               	DC37      	27A3      	M_H_CPU0_SB_CB<7>   
          	               	DC39      	40A4      	GND                 
          	               	DC41      	27B2      	M_H_CPU0_SA_CA<6>   
          	               	DC43      	24A2      	M_E_CPU0_SA_RSP<1>  
          	               	DC45      	40A4      	GND                 
          	               	DC48      	27B2      	M_H_CPU0_SA_CA<2>   
          	               	DC50      	27A2      	M_H_CPU0_SA_CS_N<3> 
          	               	DC52      	40A4      	GND                 
          	               	DC54      	27B3      	M_H_CPU0_SA_CB<4>   
          	               	DC56      	27B3      	M_H_CPU0_SA_CB<1>   
          	               	DC58      	40A4      	GND                 
          	               	DC60      	27B3      	M_H_CPU0_SA_DQ<28>  
          	               	DC62      	27B3      	M_H_CPU0_SA_DQ<25>  
          	               	DC64      	40A4      	GND                 
          	               	DC66      	27B3      	M_H_CPU0_SA_DQ<20>  
          	               	DC68      	27B3      	M_H_CPU0_SA_DQ<17>  
          	               	DC70      	40A4      	GND                 
          	               	DC72      	27B3      	M_H_CPU0_SA_DQ<12>  
          	               	DC74      	27B3      	M_H_CPU0_SA_DQ<9>   
          	               	DC76      	40A4      	GND                 
          	               	DC78      	40A4      	GND                 
          	               	DC80      	40A4      	GND                 
          	               	DC82      	35B3      	GND                 
          	               	DC84      	40A4      	GND                 
          	               	DC86      	30B2      	P5E_CPU0_PE3_TX_DP<11>
          	               	DC88      	40A4      	GND                 
          	               	DC90      	30B3      	P5E_CPU0_PE3_RX_DP<12>
          	               	DD2       	33B3      	UPI_CPU1_CPU0_P0P1_DP<12>
          	               	DD4       	40A4      	GND                 
          	               	DD6       	33B2      	UPI_CPU0_CPU1_P1P0_DP<11>
          	               	DD8       	40A4      	GND                 
          	               	DD10      	30B3      	P5E_CPU0_PE2_RX_DN<3>
          	               	DD12      	40A4      	GND                 
          	               	DD14      	30B2      	P5E_CPU0_PE2_TX_DP<4>
          	               	DD16      	40B4      	GND                 
          	               	DD18      	27B2      	M_H_CPU0_SB_DQS_DP<3>
          	               	DD20      	27B3      	M_H_CPU0_SB_DQ<24>  
          	               	DD22      	27B3      	M_H_CPU0_SB_DQ<13>  
          	               	DD24      	27B2      	M_H_CPU0_SB_DQS_DN<1>
          	               	DD26      	27A3      	M_H_CPU0_SB_DQ<8>   
          	               	DD28      	27A3      	M_H_CPU0_SB_DQ<7>   
          	               	DD30      	27B2      	M_H_CPU0_SB_DQS_DN<0>
          	               	DD32      	27A3      	M_H_CPU0_SB_DQ<0>   
          	               	DD34      	27A3      	M_H_CPU0_SB_CB<1>   
          	               	DD36      	27B2      	M_H_CPU0_SB_DQS_DN<9>
          	               	DD38      	27A3      	M_H_CPU0_SB_CB<6>   
          	               	DD40      	27B2      	M_H_CPU0_SA_PAR     
          	               	DD42      	27A3      	M_H_CPU0_CLK_DN<1>  
          	               	DD44      	24A2      	M_E_CPU0_SA_RSP<0>  
          	               	DD47      	27B2      	M_H_CPU0_SA_CA<4>   
          	               	DD49      	40B4      	GND                 
          	               	DD51      	27A2      	M_H_CPU0_SA_CS_N<2> 
          	               	DD53      	27B3      	M_H_CPU0_SA_CB<5>   
          	               	DD55      	27B2      	M_H_CPU0_SA_DQS_DN<4>
          	               	DD57      	27B3      	M_H_CPU0_SA_CB<0>   
          	               	DD59      	27B3      	M_H_CPU0_SA_DQ<29>  
          	               	DD61      	27B2      	M_H_CPU0_SA_DQS_DN<3>
          	               	DD63      	27B3      	M_H_CPU0_SA_DQ<24>  
          	               	DD65      	27B3      	M_H_CPU0_SA_DQ<21>  
          	               	DD67      	27B2      	M_H_CPU0_SA_DQS_DN<2>
          	               	DD69      	27B3      	M_H_CPU0_SA_DQ<16>  
          	               	DD71      	27B3      	M_H_CPU0_SA_DQ<13>  
          	               	DD73      	27B2      	M_H_CPU0_SA_DQS_DP<1>
          	               	DD75      	27B3      	M_H_CPU0_SA_DQ<8>   
          	               	DD77      	38B3      	PVCCFA_EHV_FIVRA_CPU0
          	               	DD79      	40B4      	GND                 
          	               	DD81      	35B3      	GND                 
          	               	DD83      	38B3      	PVCCFA_EHV_FIVRA_CPU0
          	               	DD85      	38B3      	PVCCFA_EHV_FIVRA_CPU0
          	               	DD87      	30A2      	P5E_CPU0_PE3_TX_DN<10>
          	               	DD89      	38B3      	PVCCFA_EHV_FIVRA_CPU0
          	               	DD91      	30A3      	P5E_CPU0_PE3_RX_DN<11>
          	               	DE1       	33B3      	UPI_CPU1_CPU0_P0P1_DN<11>
          	               	DE3       	37B1      	PVCCINFAON_CPU0     
          	               	DE5       	33B2      	UPI_CPU0_CPU1_P1P0_DP<10>
          	               	DE7       	37B1      	PVCCINFAON_CPU0     
          	               	DE9       	30B3      	P5E_CPU0_PE2_RX_DN<4>
          	               	DE11      	37B1      	PVCCINFAON_CPU0     
          	               	DE13      	30B2      	P5E_CPU0_PE2_TX_DN<4>
          	               	DE15      	37B1      	PVCCINFAON_CPU0     
          	               	DE17      	40B4      	GND                 
          	               	DE19      	40B4      	GND                 
          	               	DE21      	40B4      	GND                 
          	               	DE23      	40B4      	GND                 
          	               	DE25      	40B4      	GND                 
          	               	DE27      	40B4      	GND                 
          	               	DE29      	40B4      	GND                 
          	               	DE31      	40B4      	GND                 
          	               	DE33      	40B4      	GND                 
          	               	DE35      	40B4      	GND                 
          	               	DE37      	40B4      	GND                 
          	               	DE39      	40B4      	GND                 
          	               	DE41      	40B4      	GND                 
          	               	DE43      	40B4      	GND                 
          	               	DE45      	40B4      	GND                 
          	               	DE48      	40B4      	GND                 
          	               	DE50      	40B4      	GND                 
          	               	DE52      	40B4      	GND                 
          	               	DE54      	40B4      	GND                 
          	               	DE56      	40B4      	GND                 
          	               	DE58      	40B4      	GND                 
          	               	DE60      	40B4      	GND                 
          	               	DE62      	40B4      	GND                 
          	               	DE64      	40B4      	GND                 
          	               	DE66      	40B4      	GND                 
          	               	DE68      	40B4      	GND                 
          	               	DE70      	40B4      	GND                 
          	               	DE72      	40B4      	GND                 
          	               	DE74      	40B4      	GND                 
          	               	DE76      	40B4      	GND                 
          	               	DE78      	35B3      	GND                 
          	               	DE80      	35B3      	GND                 
          	               	DE82      	40B4      	GND                 
          	               	DE84      	40B4      	GND                 
          	               	DE86      	30A2      	P5E_CPU0_PE3_TX_DP<10>
          	               	DE88      	40B4      	GND                 
          	               	DE90      	30B3      	P5E_CPU0_PE3_RX_DP<11>
          	               	DF2       	33B3      	UPI_CPU1_CPU0_P0P1_DP<11>
          	               	DF4       	40B4      	GND                 
          	               	DF6       	33B2      	UPI_CPU0_CPU1_P1P0_DN<10>
          	               	DF8       	40B4      	GND                 
          	               	DF10      	30B3      	P5E_CPU0_PE2_RX_DP<4>
          	               	DF12      	40B4      	GND                 
          	               	DF14      	30B2      	P5E_CPU0_PE2_TX_DN<5>
          	               	DF16      	40B4      	GND                 
          	               	DF18      	27B2      	M_H_CPU0_SB_DQS_DN<8>
          	               	DF20      	27B3      	M_H_CPU0_SB_DQ<26>  
          	               	DF22      	27B3      	M_H_CPU0_SB_DQ<15>  
          	               	DF24      	27B2      	M_H_CPU0_SB_DQS_DP<6>
          	               	DF26      	27A3      	M_H_CPU0_SB_DQ<10>  
          	               	DF28      	27A3      	M_H_CPU0_SB_DQ<5>   
          	               	DF30      	27B2      	M_H_CPU0_SB_DQS_DP<5>
          	               	DF32      	27A3      	M_H_CPU0_SB_DQ<2>   
          	               	DF34      	27A3      	M_H_CPU0_SB_CB<3>   
          	               	DF36      	27B2      	M_H_CPU0_SB_DQS_DP<4>
          	               	DF38      	27A3      	M_H_CPU0_SB_CB<4>   
          	               	DF40      	27A2      	M_H_CPU0_SB_CA<0>   
          	               	DF42      	27A3      	M_H_CPU0_CLK_DP<0>  
          	               	DF44      	24A2      	M_E_CPU0_SB_RSP<0>  
          	               	DF47      	27B2      	M_H_CPU0_SA_CA<5>   
          	               	DF49      	40B4      	GND                 
          	               	DF51      	27A2      	M_H_CPU0_SA_CS_N<0> 
          	               	DF53      	27B3      	M_H_CPU0_SA_CB<7>   
          	               	DF55      	27B2      	M_H_CPU0_SA_DQS_DP<9>
          	               	DF57      	27B3      	M_H_CPU0_SA_CB<2>   
          	               	DF59      	27B3      	M_H_CPU0_SA_DQ<31>  
          	               	DF61      	27B2      	M_H_CPU0_SA_DQS_DP<8>
          	               	DF63      	27B3      	M_H_CPU0_SA_DQ<26>  
          	               	DF65      	27B3      	M_H_CPU0_SA_DQ<23>  
          	               	DF67      	27B2      	M_H_CPU0_SA_DQS_DP<7>
          	               	DF69      	27B3      	M_H_CPU0_SA_DQ<18>  
          	               	DF71      	27B3      	M_H_CPU0_SA_DQ<15>  
          	               	DF73      	27B2      	M_H_CPU0_SA_DQS_DP<6>
          	               	DF75      	27B3      	M_H_CPU0_SA_DQ<10>  
          	               	DF77      	35B3      	GND                 
          	               	DF79      	40B4      	GND                 
          	               	DF81      	35B3      	GND                 
          	               	DF83      	35B3      	GND                 
          	               	DF85      	30A2      	P5E_CPU0_PE3_TX_DN<9>
          	               	DF87      	40B4      	GND                 
          	               	DF89      	30A3      	P5E_CPU0_PE3_RX_DP<10>
          	               	DF91      	40B4      	GND                 
          	               	DG1       	40B4      	GND                 
          	               	DG3       	33B3      	UPI_CPU1_CPU0_P0P1_DN<10>
          	               	DG5       	40B4      	GND                 
          	               	DG7       	33B2      	UPI_CPU0_CPU1_P1P0_DP<9>
          	               	DG9       	40B4      	GND                 
          	               	DG11      	30B3      	P5E_CPU0_PE2_RX_DP<5>
          	               	DG13      	40B4      	GND                 
          	               	DG15      	30B2      	P5E_CPU0_PE2_TX_DP<5>
          	               	DG17      	27B3      	M_H_CPU0_SB_DQ<28>  
          	               	DG19      	27B3      	M_H_CPU0_SB_DQ<27>  
          	               	DG21      	40B4      	GND                 
          	               	DG23      	27B3      	M_H_CPU0_SB_DQ<14>  
          	               	DG25      	27B3      	M_H_CPU0_SB_DQ<11>  
          	               	DG27      	40B4      	GND                 
          	               	DG29      	27A3      	M_H_CPU0_SB_DQ<6>   
          	               	DG31      	27A3      	M_H_CPU0_SB_DQ<3>   
          	               	DG33      	40B4      	GND                 
          	               	DG35      	27A3      	M_H_CPU0_SB_CB<2>   
          	               	DG37      	27A3      	M_H_CPU0_SB_CB<5>   
          	               	DG39      	40B4      	GND                 
          	               	DG41      	27A2      	M_H_CPU0_SB_CA<1>   
          	               	DG43      	24A2      	M_E_CPU0_SB_RSP<1>  
          	               	DG45      	40B4      	GND                 
          	               	DG48      	27B2      	M_H_CPU0_SA_CA<3>   
          	               	DG50      	27A2      	M_H_CPU0_SA_CS_N<1> 
          	               	DG52      	40B4      	GND                 
          	               	DG54      	27B3      	M_H_CPU0_SA_CB<6>   
          	               	DG56      	27B3      	M_H_CPU0_SA_CB<3>   
          	               	DG58      	40B4      	GND                 
          	               	DG60      	27B3      	M_H_CPU0_SA_DQ<30>  
          	               	DG62      	27B3      	M_H_CPU0_SA_DQ<27>  
          	               	DG64      	40B4      	GND                 
          	               	DG66      	27B3      	M_H_CPU0_SA_DQ<22>  
          	               	DG68      	27B3      	M_H_CPU0_SA_DQ<19>  
          	               	DG70      	40B4      	GND                 
          	               	DG72      	27B3      	M_H_CPU0_SA_DQ<14>  
          	               	DG74      	27B3      	M_H_CPU0_SA_DQ<11>  
          	               	DG76      	40B4      	GND                 
          	               	DG78      	35B3      	GND                 
          	               	DG80      	40A4      	GND                 
          	               	DG82      	35B3      	GND                 
          	               	DG84      	40A4      	GND                 
          	               	DG86      	30A2      	P5E_CPU0_PE3_TX_DP<9>
          	               	DG88      	40A4      	GND                 
          	               	DG90      	30A3      	P5E_CPU0_PE3_RX_DN<10>
          	               	DH2       	33B3      	UPI_CPU1_CPU0_P0P1_DP<10>
          	               	DH4       	40A4      	GND                 
          	               	DH6       	33B2      	UPI_CPU0_CPU1_P1P0_DN<9>
          	               	DH8       	40A4      	GND                 
          	               	DH10      	30B3      	P5E_CPU0_PE2_RX_DN<5>
          	               	DH12      	40A4      	GND                 
          	               	DH14      	30B2      	P5E_CPU0_PE2_TX_DP<6>
          	               	DH16      	40A4      	GND                 
          	               	DH18      	27B2      	M_H_CPU0_SB_DQS_DP<8>
          	               	DH20      	40A4      	GND                 
          	               	DH22      	40A4      	GND                 
          	               	DH24      	27B2      	M_H_CPU0_SB_DQS_DN<6>
          	               	DH26      	40A4      	GND                 
          	               	DH28      	40A4      	GND                 
          	               	DH30      	27B2      	M_H_CPU0_SB_DQS_DN<5>
          	               	DH32      	40A4      	GND                 
          	               	DH34      	40A4      	GND                 
          	               	DH36      	27B2      	M_H_CPU0_SB_DQS_DN<4>
          	               	DH38      	40A4      	GND                 
          	               	DH40      	40A4      	GND                 
          	               	DH42      	27A3      	M_H_CPU0_CLK_DN<0>  
          	               	DH44      	40A4      	GND                 
          	               	DH47      	40A4      	GND                 
          	               	DH49      	27B2      	M_H_CPU0_SA_CA<1>   
          	               	DH51      	40A4      	GND                 
          	               	DH53      	40A4      	GND                 
          	               	DH55      	27B2      	M_H_CPU0_SA_DQS_DN<9>
          	               	DH57      	40A4      	GND                 
          	               	DH59      	40A4      	GND                 
          	               	DH61      	27B2      	M_H_CPU0_SA_DQS_DN<8>
          	               	DH63      	40A4      	GND                 
          	               	DH65      	40B4      	GND                 
          	               	DH67      	27B2      	M_H_CPU0_SA_DQS_DN<7>
          	               	DH69      	40B4      	GND                 
          	               	DH71      	40B4      	GND                 
          	               	DH73      	27B2      	M_H_CPU0_SA_DQS_DN<6>
          	               	DH75      	40B4      	GND                 
          	               	DH77      	40B4      	GND                 
          	               	DH79      	35B3      	GND                 
          	               	DH81      	35B3      	GND                 
          	               	DH83      	35B3      	GND                 
          	               	DH85      	40B4      	GND                 
          	               	DH87      	30A2      	P5E_CPU0_PE3_TX_DN<8>
          	               	DH89      	38B3      	PVCCFA_EHV_FIVRA_CPU0
          	               	DH91      	30A3      	P5E_CPU0_PE3_RX_DN<9>
          	               	DJ1       	33B3      	UPI_CPU1_CPU0_P0P1_DN<9>
          	               	DJ3       	37B1      	PVCCINFAON_CPU0     
          	               	DJ5       	33B2      	UPI_CPU0_CPU1_P1P0_DP<8>
          	               	DJ7       	37B1      	PVCCINFAON_CPU0     
          	               	DJ9       	30B3      	P5E_CPU0_PE2_RX_DN<6>
          	               	DJ11      	37B1      	PVCCINFAON_CPU0     
          	               	DJ13      	30B2      	P5E_CPU0_PE2_TX_DN<6>
          	               	DJ15      	37B1      	PVCCINFAON_CPU0     
          	               	DJ17      	27B3      	M_H_CPU0_SB_DQ<30>  
          	               	DJ19      	40B4      	GND                 
          	               	DJ21      	27B2      	M_H_CPU0_SB_DQS_DP<2>
          	               	DJ23      	40B4      	GND                 
          	               	DJ25      	40B4      	GND                 
          	               	DJ27      	26B2      	M_G_CPU0_SB_DQS_DN<1>
          	               	DJ29      	40B4      	GND                 
          	               	DJ31      	40B4      	GND                 
          	               	DJ33      	26B2      	M_G_CPU0_SB_DQS_DN<0>
          	               	DJ35      	40B4      	GND                 
          	               	DJ37      	40B4      	GND                 
          	               	DJ39      	27B2      	M_H_CPU0_SB_CA<6>   
          	               	DJ41      	40B4      	GND                 
          	               	DJ43      	40B4      	GND                 
          	               	DJ45      	26A3      	M_G_CPU0_CLK_DP<1>  
          	               	DJ48      	40B4      	GND                 
          	               	DJ50      	40B4      	GND                 
          	               	DJ52      	26B2      	M_G_CPU0_SA_CA<0>   
          	               	DJ54      	40B4      	GND                 
          	               	DJ56      	40B4      	GND                 
          	               	DJ58      	26B2      	M_G_CPU0_SA_DQS_DP<4>
          	               	DJ60      	40B4      	GND                 
          	               	DJ62      	40B4      	GND                 
          	               	DJ64      	26B2      	M_G_CPU0_SA_DQS_DP<3>
          	               	DJ66      	40B4      	GND                 
          	               	DJ68      	40B4      	GND                 
          	               	DJ70      	26B2      	M_G_CPU0_SA_DQS_DN<1>
          	               	DJ72      	40B4      	GND                 
          	               	DJ74      	40B4      	GND                 
          	               	DJ76      	27B2      	M_H_CPU0_SA_DQS_DN<0>
          	               	DJ78      	35B3      	GND                 
          	               	DJ80      	40B4      	GND                 
          	               	DJ82      	40B4      	GND                 
          	               	DJ84      	40B4      	GND                 
          	               	DJ86      	30A2      	P5E_CPU0_PE3_TX_DP<8>
          	               	DJ88      	40B4      	GND                 
          	               	DJ90      	30A3      	P5E_CPU0_PE3_RX_DP<9>
          	               	DK2       	33B3      	UPI_CPU1_CPU0_P0P1_DP<9>
          	               	DK4       	40B4      	GND                 
          	               	DK6       	33B2      	UPI_CPU0_CPU1_P1P0_DN<8>
          	               	DK8       	40B4      	GND                 
          	               	DK10      	30B3      	P5E_CPU0_PE2_RX_DP<6>
          	               	DK12      	40B4      	GND                 
          	               	DK14      	30B2      	P5E_CPU0_PE2_TX_DN<7>
          	               	DK16      	40B4      	GND                 
          	               	DK18      	40B4      	GND                 
          	               	DK20      	27B3      	M_H_CPU0_SB_DQ<20>  
          	               	DK22      	27B3      	M_H_CPU0_SB_DQ<17>  
          	               	DK24      	40B4      	GND                 
          	               	DK26      	26B3      	M_G_CPU0_SB_DQ<12>  
          	               	DK28      	26A3      	M_G_CPU0_SB_DQ<9>   
          	               	DK30      	40B4      	GND                 
          	               	DK32      	26A3      	M_G_CPU0_SB_DQ<4>   
          	               	DK34      	26A3      	M_G_CPU0_SB_DQ<1>   
          	               	DK36      	40B4      	GND                 
          	               	DK38      	27A2      	M_H_CPU0_SB_CS_N<2> 
          	               	DK40      	27B2      	M_H_CPU0_SB_CA<4>   
          	               	DK42      	40B4      	GND                 
          	               	DK44      	26B2      	M_G_CPU0_SA_CA<6>   
          	               	DK47      	25A2      	M_F_CPU0_SB_RSP<1>  
          	               	DK49      	40B4      	GND                 
          	               	DK51      	26B2      	M_G_CPU0_SA_CA<2>   
          	               	DK53      	26A2      	M_G_CPU0_SA_CS_N<3> 
          	               	DK55      	40B4      	GND                 
          	               	DK57      	26B3      	M_G_CPU0_SA_CB<4>   
          	               	DK59      	26B3      	M_G_CPU0_SA_CB<1>   
          	               	DK61      	40B4      	GND                 
          	               	DK63      	26B3      	M_G_CPU0_SA_DQ<28>  
          	               	DK65      	26B3      	M_G_CPU0_SA_DQ<25>  
          	               	DK67      	40B4      	GND                 
          	               	DK69      	26B3      	M_G_CPU0_SA_DQ<12>  
          	               	DK71      	26B3      	M_G_CPU0_SA_DQ<9>   
          	               	DK73      	40B4      	GND                 
          	               	DK75      	27B3      	M_H_CPU0_SA_DQ<4>   
          	               	DK77      	40B4      	GND                 
          	               	DK79      	40B4      	GND                 
          	               	DK81      	40B4      	GND                 
          	               	DK83      	40B4      	GND                 
          	               	DK85      	30A2      	P5E_CPU0_PE3_TX_DN<7>
          	               	DK87      	40B4      	GND                 
          	               	DK89      	30A3      	P5E_CPU0_PE3_RX_DP<8>
          	               	DK91      	40B4      	GND                 
          	               	DL1       	40B4      	GND                 
          	               	DL3       	33B3      	UPI_CPU1_CPU0_P0P1_DN<8>
          	               	DL5       	40B4      	GND                 
          	               	DL7       	33B2      	UPI_CPU0_CPU1_P1P0_DN<7>
          	               	DL9       	40B4      	GND                 
          	               	DL11      	30B3      	P5E_CPU0_PE2_RX_DP<7>
          	               	DL13      	40B4      	GND                 
          	               	DL15      	30B2      	P5E_CPU0_PE2_TX_DP<7>
          	               	DL17      	40B4      	GND                 
          	               	DL19      	27B3      	M_H_CPU0_SB_DQ<21>  
          	               	DL21      	27B2      	M_H_CPU0_SB_DQS_DN<2>
          	               	DL23      	27B3      	M_H_CPU0_SB_DQ<16>  
          	               	DL25      	26B3      	M_G_CPU0_SB_DQ<13>  
          	               	DL27      	26B2      	M_G_CPU0_SB_DQS_DP<1>
          	               	DL29      	26A3      	M_G_CPU0_SB_DQ<10>  
          	               	DL31      	26A3      	M_G_CPU0_SB_DQ<5>   
          	               	DL33      	26B2      	M_G_CPU0_SB_DQS_DP<0>
          	               	DL35      	26A3      	M_G_CPU0_SB_DQ<0>   
          	               	DL37      	27A2      	M_H_CPU0_SB_CS_N<0> 
          	               	DL39      	40B4      	GND                 
          	               	DL41      	27B2      	M_H_CPU0_SB_CA<2>   
          	               	DL43      	26B2      	M_G_CPU0_SA_PAR     
          	               	DL45      	26A3      	M_G_CPU0_CLK_DN<1>  
          	               	DL48      	25A2      	M_F_CPU0_SB_RSP<0>  
          	               	DL50      	26B2      	M_G_CPU0_SA_CA<4>   
          	               	DL52      	40B4      	GND                 
          	               	DL54      	26A2      	M_G_CPU0_SA_CS_N<2> 
          	               	DL56      	26B3      	M_G_CPU0_SA_CB<5>   
          	               	DL58      	26B2      	M_G_CPU0_SA_DQS_DN<4>
          	               	DL60      	26B3      	M_G_CPU0_SA_CB<0>   
          	               	DL62      	26B3      	M_G_CPU0_SA_DQ<29>  
          	               	DL64      	26B2      	M_G_CPU0_SA_DQS_DN<3>
          	               	DL66      	26B3      	M_G_CPU0_SA_DQ<24>  
          	               	DL68      	26B3      	M_G_CPU0_SA_DQ<13>  
          	               	DL70      	26B2      	M_G_CPU0_SA_DQS_DP<1>
          	               	DL72      	26B3      	M_G_CPU0_SA_DQ<8>   
          	               	DL74      	27B3      	M_H_CPU0_SA_DQ<5>   
          	               	DL76      	27B2      	M_H_CPU0_SA_DQS_DP<0>
          	               	DL78      	35B3      	GND                 
          	               	DL80      	35B2      	NC                  
          	               	DL82      	35B2      	NC                  
          	               	DL84      	40B4      	GND                 
          	               	DL86      	30A2      	P5E_CPU0_PE3_TX_DP<7>
          	               	DL88      	40B4      	GND                 
          	               	DL90      	30A3      	P5E_CPU0_PE3_RX_DN<8>
          	               	DM2       	33B3      	UPI_CPU1_CPU0_P0P1_DP<8>
          	               	DM4       	39A1      	GND                 
          	               	DM6       	33B2      	UPI_CPU0_CPU1_P1P0_DP<7>
          	               	DM8       	39A1      	GND                 
          	               	DM10      	30B3      	P5E_CPU0_PE2_RX_DN<7>
          	               	DM12      	39A1      	GND                 
          	               	DM14      	30B2      	P5E_CPU0_PE2_TX_DP<8>
          	               	DM16      	39A1      	GND                 
          	               	DM18      	39A1      	GND                 
          	               	DM20      	39A1      	GND                 
          	               	DM22      	39A1      	GND                 
          	               	DM24      	39A1      	GND                 
          	               	DM26      	39A1      	GND                 
          	               	DM28      	39A1      	GND                 
          	               	DM30      	39A1      	GND                 
          	               	DM32      	39A1      	GND                 
          	               	DM34      	39A1      	GND                 
          	               	DM36      	39A1      	GND                 
          	               	DM38      	39A1      	GND                 
          	               	DM40      	39A1      	GND                 
          	               	DM42      	39A1      	GND                 
          	               	DM44      	39A1      	GND                 
          	               	DM47      	39A1      	GND                 
          	               	DM49      	39A1      	GND                 
          	               	DM51      	39A1      	GND                 
          	               	DM53      	39A1      	GND                 
          	               	DM55      	39B1      	GND                 
          	               	DM57      	39B1      	GND                 
          	               	DM59      	39B1      	GND                 
          	               	DM61      	39B1      	GND                 
          	               	DM63      	39B1      	GND                 
          	               	DM65      	39B1      	GND                 
          	               	DM67      	39B1      	GND                 
          	               	DM69      	39B1      	GND                 
          	               	DM71      	39B1      	GND                 
          	               	DM73      	39B1      	GND                 
          	               	DM75      	39B1      	GND                 
          	               	DM77      	39B1      	GND                 
          	               	DM79      	39B1      	GND                 
          	               	DM81      	35B2      	NC                  
          	               	DM83      	38B3      	PVCCFA_EHV_FIVRA_CPU0
          	               	DM85      	38B3      	PVCCFA_EHV_FIVRA_CPU0
          	               	DM87      	30A2      	P5E_CPU0_PE3_TX_DN<6>
          	               	DM89      	38B3      	PVCCFA_EHV_FIVRA_CPU0
          	               	DM91      	30A3      	P5E_CPU0_PE3_RX_DP<7>
          	               	DN1       	33B3      	UPI_CPU1_CPU0_P0P1_DN<7>
          	               	DN3       	38B3      	PVCCFA_EHV_FIVRA_CPU0
          	               	DN5       	33B2      	UPI_CPU0_CPU1_P1P0_DP<6>
          	               	DN7       	38B3      	PVCCFA_EHV_FIVRA_CPU0
          	               	DN9       	30B3      	P5E_CPU0_PE2_RX_DN<8>
          	               	DN11      	38B3      	PVCCFA_EHV_FIVRA_CPU0
          	               	DN13      	30B2      	P5E_CPU0_PE2_TX_DN<8>
          	               	DN15      	38B3      	PVCCFA_EHV_FIVRA_CPU0
          	               	DN17      	39B1      	GND                 
          	               	DN19      	27B3      	M_H_CPU0_SB_DQ<23>  
          	               	DN21      	27B2      	M_H_CPU0_SB_DQS_DP<7>
          	               	DN23      	27B3      	M_H_CPU0_SB_DQ<18>  
          	               	DN25      	26B3      	M_G_CPU0_SB_DQ<15>  
          	               	DN27      	26B2      	M_G_CPU0_SB_DQS_DN<6>
          	               	DN29      	26A3      	M_G_CPU0_SB_DQ<8>   
          	               	DN31      	26A3      	M_G_CPU0_SB_DQ<7>   
          	               	DN33      	26B2      	M_G_CPU0_SB_DQS_DP<5>
          	               	DN35      	26A3      	M_G_CPU0_SB_DQ<2>   
          	               	DN37      	27A2      	M_H_CPU0_SB_CS_N<1> 
          	               	DN39      	39B1      	GND                 
          	               	DN41      	27B2      	M_H_CPU0_SB_CA<3>   
          	               	DN43      	26A2      	M_G_CPU0_SB_CA<0>   
          	               	DN45      	26A3      	M_G_CPU0_CLK_DP<0>  
          	               	DN48      	25A2      	M_F_CPU0_SA_RSP<0>  
          	               	DN50      	26B2      	M_G_CPU0_SA_CA<5>   
          	               	DN52      	39B1      	GND                 
          	               	DN54      	26A2      	M_G_CPU0_SA_CS_N<0> 
          	               	DN56      	26B3      	M_G_CPU0_SA_CB<7>   
          	               	DN58      	26B2      	M_G_CPU0_SA_DQS_DP<9>
          	               	DN60      	26B3      	M_G_CPU0_SA_CB<2>   
          	               	DN62      	26B3      	M_G_CPU0_SA_DQ<31>  
          	               	DN64      	26B2      	M_G_CPU0_SA_DQS_DP<8>
          	               	DN66      	26B3      	M_G_CPU0_SA_DQ<26>  
          	               	DN68      	26B3      	M_G_CPU0_SA_DQ<15>  
          	               	DN70      	26B2      	M_G_CPU0_SA_DQS_DP<6>
          	               	DN72      	26B3      	M_G_CPU0_SA_DQ<10>  
          	               	DN74      	27B3      	M_H_CPU0_SA_DQ<7>   
          	               	DN76      	27B2      	M_H_CPU0_SA_DQS_DP<5>
          	               	DN78      	39B1      	GND                 
          	               	DN80      	35B2      	NC                  
          	               	DN82      	35B2      	NC                  
          	               	DN84      	39B1      	GND                 
          	               	DN86      	30A2      	P5E_CPU0_PE3_TX_DP<6>
          	               	DN88      	39B1      	GND                 
          	               	DN90      	30A3      	P5E_CPU0_PE3_RX_DN<7>
          	               	DP2       	33B3      	UPI_CPU1_CPU0_P0P1_DP<7>
          	               	DP4       	39B1      	GND                 
          	               	DP6       	33B2      	UPI_CPU0_CPU1_P1P0_DN<6>
          	               	DP8       	39B1      	GND                 
          	               	DP10      	30B3      	P5E_CPU0_PE2_RX_DP<8>
          	               	DP12      	39B1      	GND                 
          	               	DP14      	30B2      	P5E_CPU0_PE2_TX_DN<9>
          	               	DP16      	39B1      	GND                 
          	               	DP18      	39B1      	GND                 
          	               	DP20      	27B3      	M_H_CPU0_SB_DQ<22>  
          	               	DP22      	27B3      	M_H_CPU0_SB_DQ<19>  
          	               	DP24      	39B1      	GND                 
          	               	DP26      	26B3      	M_G_CPU0_SB_DQ<14>  
          	               	DP28      	26B3      	M_G_CPU0_SB_DQ<11>  
          	               	DP30      	39B1      	GND                 
          	               	DP32      	26A3      	M_G_CPU0_SB_DQ<6>   
          	               	DP34      	26A3      	M_G_CPU0_SB_DQ<3>   
          	               	DP36      	39B1      	GND                 
          	               	DP38      	27A2      	M_H_CPU0_SB_CS_N<3> 
          	               	DP40      	27B2      	M_H_CPU0_SB_CA<5>   
          	               	DP42      	39B1      	GND                 
          	               	DP44      	26A2      	M_G_CPU0_SB_CA<1>   
          	               	DP47      	25A2      	M_F_CPU0_SA_RSP<1>  
          	               	DP49      	39B1      	GND                 
          	               	DP51      	26B2      	M_G_CPU0_SA_CA<3>   
          	               	DP53      	26A2      	M_G_CPU0_SA_CS_N<1> 
          	               	DP55      	39B1      	GND                 
          	               	DP57      	26B3      	M_G_CPU0_SA_CB<6>   
          	               	DP59      	26B3      	M_G_CPU0_SA_CB<3>   
          	               	DP61      	39B1      	GND                 
          	               	DP63      	26B3      	M_G_CPU0_SA_DQ<30>  
          	               	DP65      	26B3      	M_G_CPU0_SA_DQ<27>  
          	               	DP67      	39B1      	GND                 
          	               	DP69      	26B3      	M_G_CPU0_SA_DQ<14>  
          	               	DP71      	26B3      	M_G_CPU0_SA_DQ<11>  
          	               	DP73      	39B1      	GND                 
          	               	DP75      	27B3      	M_H_CPU0_SA_DQ<6>   
          	               	DP77      	27B3      	M_H_CPU0_SA_DQ<3>   
          	               	DP79      	35B2      	NC                  
          	               	DP81      	39B1      	GND                 
          	               	DP83      	35B2      	NC                  
          	               	DP85      	30A2      	P5E_CPU0_PE3_TX_DN<5>
          	               	DP87      	39B1      	GND                 
          	               	DP89      	30A3      	P5E_CPU0_PE3_RX_DN<6>
          	               	DP91      	39B1      	GND                 
          	               	DR1       	39B1      	GND                 
          	               	DR3       	33B3      	UPI_CPU1_CPU0_P0P1_DP<6>
          	               	DR5       	39B1      	GND                 
          	               	DR7       	33B2      	UPI_CPU0_CPU1_P1P0_DN<5>
          	               	DR9       	39B1      	GND                 
          	               	DR11      	30B3      	P5E_CPU0_PE2_RX_DP<9>
          	               	DR13      	39B1      	GND                 
          	               	DR15      	30B2      	P5E_CPU0_PE2_TX_DP<9>
          	               	DR17      	25B3      	M_F_CPU0_SB_DQ<31>  
          	               	DR19      	39B1      	GND                 
          	               	DR21      	27B2      	M_H_CPU0_SB_DQS_DN<7>
          	               	DR23      	39B1      	GND                 
          	               	DR25      	39B1      	GND                 
          	               	DR27      	26B2      	M_G_CPU0_SB_DQS_DP<6>
          	               	DR29      	39B1      	GND                 
          	               	DR31      	39B1      	GND                 
          	               	DR33      	26B2      	M_G_CPU0_SB_DQS_DN<5>
          	               	DR35      	39B1      	GND                 
          	               	DR37      	39B1      	GND                 
          	               	DR39      	27A2      	M_H_CPU0_SB_PAR     
          	               	DR41      	39B1      	GND                 
          	               	DR43      	39B1      	GND                 
          	               	DR45      	26A3      	M_G_CPU0_CLK_DN<0>  
          	               	DR48      	39B1      	GND                 
          	               	DR50      	39B1      	GND                 
          	               	DR52      	26B2      	M_G_CPU0_SA_CA<1>   
          	               	DR54      	39B1      	GND                 
          	               	DR56      	39B1      	GND                 
          	               	DR58      	26B2      	M_G_CPU0_SA_DQS_DN<9>
          	               	DR60      	39B1      	GND                 
          	               	DR62      	39B1      	GND                 
          	               	DR64      	26B2      	M_G_CPU0_SA_DQS_DN<8>
          	               	DR66      	39B1      	GND                 
          	               	DR68      	39B1      	GND                 
          	               	DR70      	26B2      	M_G_CPU0_SA_DQS_DN<6>
          	               	DR72      	39B1      	GND                 
          	               	DR74      	39A2      	GND                 
          	               	DR76      	27B2      	M_H_CPU0_SA_DQS_DN<5>
          	               	DR78      	39A2      	GND                 
          	               	DR80      	35B2      	NC                  
          	               	DR82      	35B2      	NC                  
          	               	DR84      	39A2      	GND                 
          	               	DR86      	30A2      	P5E_CPU0_PE3_TX_DP<5>
          	               	DR88      	39A2      	GND                 
          	               	DR90      	30A3      	P5E_CPU0_PE3_RX_DP<6>
          	               	DT2       	33B3      	UPI_CPU1_CPU0_P0P1_DN<6>
          	               	DT4       	39A2      	GND                 
          	               	DT6       	33B2      	UPI_CPU0_CPU1_P1P0_DP<5>
          	               	DT8       	39A2      	GND                 
          	               	DT10      	30B3      	P5E_CPU0_PE2_RX_DN<9>
          	               	DT12      	39A2      	GND                 
          	               	DT14      	30B2      	P5E_CPU0_PE2_TX_DP<10>
          	               	DT16      	39A2      	GND                 
          	               	DT18      	25B2      	M_F_CPU0_SB_DQS_DN<3>
          	               	DT20      	39A2      	GND                 
          	               	DT22      	39A2      	GND                 
          	               	DT24      	26B2      	M_G_CPU0_SB_DQS_DP<2>
          	               	DT26      	39A2      	GND                 
          	               	DT28      	39A2      	GND                 
          	               	DT30      	25B2      	M_F_CPU0_SB_DQS_DP<0>
          	               	DT32      	39A2      	GND                 
          	               	DT34      	39A2      	GND                 
          	               	DT36      	26B2      	M_G_CPU0_SB_DQS_DP<9>
          	               	DT38      	39A2      	GND                 
          	               	DT40      	39A2      	GND                 
          	               	DT42      	26B2      	M_G_CPU0_SB_CA<6>   
          	               	DT44      	39A2      	GND                 
          	               	DT47      	39A2      	GND                 
          	               	DT49      	25A3      	M_F_CPU0_CLK_DP<1>  
          	               	DT51      	39A2      	GND                 
          	               	DT53      	39A2      	GND                 
          	               	DT55      	25B2      	M_F_CPU0_SA_DQS_DP<3>
          	               	DT57      	39A2      	GND                 
          	               	DT59      	39A2      	GND                 
          	               	DT61      	26B2      	M_G_CPU0_SA_DQS_DN<2>
          	               	DT63      	39B2      	GND                 
          	               	DT65      	39B2      	GND                 
          	               	DT67      	25B2      	M_F_CPU0_SA_DQS_DN<1>
          	               	DT69      	39B2      	GND                 
          	               	DT71      	39B2      	GND                 
          	               	DT73      	26B2      	M_G_CPU0_SA_DQS_DP<0>
          	               	DT75      	39B2      	GND                 
          	               	DT77      	27B3      	M_H_CPU0_SA_DQ<1>   
          	               	DT79      	38B3      	PVCCFA_EHV_FIVRA_CPU0
          	               	DT81      	35B2      	NC                  
          	               	DT83      	39B2      	GND                 
          	               	DT85      	38B3      	PVCCFA_EHV_FIVRA_CPU0
          	               	DT87      	30A2      	P5E_CPU0_PE3_TX_DN<4>
          	               	DT89      	38B3      	PVCCFA_EHV_FIVRA_CPU0
          	               	DT91      	30A3      	P5E_CPU0_PE3_RX_DP<5>
          	               	DU1       	33B3      	UPI_CPU1_CPU0_P0P1_DN<5>
          	               	DU3       	38B3      	PVCCFA_EHV_FIVRA_CPU0
          	               	DU5       	33B2      	UPI_CPU0_CPU1_P1P0_DP<4>
          	               	DU7       	38B3      	PVCCFA_EHV_FIVRA_CPU0
          	               	DU9       	30B3      	P5E_CPU0_PE2_RX_DN<10>
          	               	DU11      	38B3      	PVCCFA_EHV_FIVRA_CPU0
          	               	DU13      	30B2      	P5E_CPU0_PE2_TX_DN<10>
          	               	DU15      	38B3      	PVCCFA_EHV_FIVRA_CPU0
          	               	DU17      	25B3      	M_F_CPU0_SB_DQ<29>  
          	               	DU19      	25B3      	M_F_CPU0_SB_DQ<25>  
          	               	DU21      	39B2      	GND                 
          	               	DU23      	26B3      	M_G_CPU0_SB_DQ<20>  
          	               	DU25      	26B3      	M_G_CPU0_SB_DQ<17>  
          	               	DU27      	39B2      	GND                 
          	               	DU29      	25A3      	M_F_CPU0_SB_DQ<4>   
          	               	DU31      	25A3      	M_F_CPU0_SB_DQ<1>   
          	               	DU33      	39B2      	GND                 
          	               	DU35      	26A3      	M_G_CPU0_SB_CB<0>   
          	               	DU37      	26A3      	M_G_CPU0_SB_CB<5>   
          	               	DU39      	39B2      	GND                 
          	               	DU41      	26A2      	M_G_CPU0_SB_CS_N<2> 
          	               	DU43      	26B2      	M_G_CPU0_SB_CA<4>   
          	               	DU45      	39B2      	GND                 
          	               	DU48      	26A2      	M_G_CPU0_SB_RSP<0>  
          	               	DU50      	25A2      	M_F_CPU0_SB_CA<1>   
          	               	DU52      	39B2      	GND                 
          	               	DU54      	25B3      	M_F_CPU0_SA_DQ<28>  
          	               	DU56      	25B3      	M_F_CPU0_SA_DQ<25>  
          	               	DU58      	39B2      	GND                 
          	               	DU60      	26B3      	M_G_CPU0_SA_DQ<20>  
          	               	DU62      	26B3      	M_G_CPU0_SA_DQ<17>  
          	               	DU64      	39B2      	GND                 
          	               	DU66      	25B3      	M_F_CPU0_SA_DQ<12>  
          	               	DU68      	25B3      	M_F_CPU0_SA_DQ<9>   
          	               	DU70      	39B2      	GND                 
          	               	DU72      	26B3      	M_G_CPU0_SA_DQ<4>   
          	               	DU74      	26B3      	M_G_CPU0_SA_DQ<1>   
          	               	DU76      	39B2      	GND                 
          	               	DU78      	39B2      	GND                 
          	               	DU80      	35B2      	NC                  
          	               	DU82      	35B2      	NC                  
          	               	DU84      	39B2      	GND                 
          	               	DU86      	30A2      	P5E_CPU0_PE3_TX_DP<4>
          	               	DU88      	39B2      	GND                 
          	               	DU90      	30A3      	P5E_CPU0_PE3_RX_DN<5>
          	               	DV2       	33B3      	UPI_CPU1_CPU0_P0P1_DP<5>
          	               	DV4       	39B2      	GND                 
          	               	DV6       	33B2      	UPI_CPU0_CPU1_P1P0_DN<4>
          	               	DV8       	39B2      	GND                 
          	               	DV10      	30B3      	P5E_CPU0_PE2_RX_DP<10>
          	               	DV12      	39B2      	GND                 
          	               	DV14      	30B2      	P5E_CPU0_PE2_TX_DN<11>
          	               	DV16      	39B2      	GND                 
          	               	DV18      	25B2      	M_F_CPU0_SB_DQS_DP<3>
          	               	DV20      	25B3      	M_F_CPU0_SB_DQ<24>  
          	               	DV22      	26B3      	M_G_CPU0_SB_DQ<21>  
          	               	DV24      	26B2      	M_G_CPU0_SB_DQS_DN<2>
          	               	DV26      	26B3      	M_G_CPU0_SB_DQ<16>  
          	               	DV28      	25A3      	M_F_CPU0_SB_DQ<5>   
          	               	DV30      	25B2      	M_F_CPU0_SB_DQS_DN<0>
          	               	DV32      	25A3      	M_F_CPU0_SB_DQ<0>   
          	               	DV34      	26A3      	M_G_CPU0_SB_CB<1>   
          	               	DV36      	26B2      	M_G_CPU0_SB_DQS_DN<9>
          	               	DV38      	26A3      	M_G_CPU0_SB_CB<4>   
          	               	DV40      	26A2      	M_G_CPU0_SB_CS_N<3> 
          	               	DV42      	39B2      	GND                 
          	               	DV44      	26B2      	M_G_CPU0_SB_CA<2>   
          	               	DV47      	26A2      	M_G_CPU0_SB_RSP<1>  
          	               	DV49      	25A3      	M_F_CPU0_CLK_DN<1>  
          	               	DV51      	25A2      	M_F_CPU0_SB_CA<0>   
          	               	DV53      	25B3      	M_F_CPU0_SA_DQ<29>  
          	               	DV55      	25B2      	M_F_CPU0_SA_DQS_DN<3>
          	               	DV57      	25B3      	M_F_CPU0_SA_DQ<24>  
          	               	DV59      	26B3      	M_G_CPU0_SA_DQ<21>  
          	               	DV61      	26B2      	M_G_CPU0_SA_DQS_DP<2>
          	               	DV63      	26B3      	M_G_CPU0_SA_DQ<16>  
          	               	DV65      	25B3      	M_F_CPU0_SA_DQ<13>  
          	               	DV67      	25B2      	M_F_CPU0_SA_DQS_DP<1>
          	               	DV69      	25B3      	M_F_CPU0_SA_DQ<8>   
          	               	DV71      	26B3      	M_G_CPU0_SA_DQ<5>   
          	               	DV73      	26B2      	M_G_CPU0_SA_DQS_DN<0>
          	               	DV75      	26B3      	M_G_CPU0_SA_DQ<0>   
          	               	DV77      	39B2      	GND                 
          	               	DV79      	39B2      	GND                 
          	               	DV81      	39B2      	GND                 
          	               	DV83      	39B2      	GND                 
          	               	DV85      	30A2      	P5E_CPU0_PE3_TX_DN<3>
          	               	DV87      	39B2      	GND                 
          	               	DV89      	30A3      	P5E_CPU0_PE3_RX_DN<4>
          	               	DV91      	39B2      	GND                 
          	               	DW1       	39B2      	GND                 
          	               	DW3       	33B3      	UPI_CPU1_CPU0_P0P1_DP<4>
          	               	DW5       	39B2      	GND                 
          	               	DW7       	33B2      	UPI_CPU0_CPU1_P1P0_DN<3>
          	               	DW9       	39B2      	GND                 
          	               	DW11      	30B3      	P5E_CPU0_PE2_RX_DP<11>
          	               	DW13      	39B2      	GND                 
          	               	DW15      	30B2      	P5E_CPU0_PE2_TX_DP<11>
          	               	DW17      	39B2      	GND                 
          	               	DW19      	39B2      	GND                 
          	               	DW21      	39B2      	GND                 
          	               	DW23      	39B2      	GND                 
          	               	DW25      	39B2      	GND                 
          	               	DW27      	39B2      	GND                 
          	               	DW29      	39B2      	GND                 
          	               	DW31      	39B2      	GND                 
          	               	DW33      	39B2      	GND                 
          	               	DW35      	39B2      	GND                 
          	               	DW37      	39B2      	GND                 
          	               	DW39      	39B2      	GND                 
          	               	DW41      	39B2      	GND                 
          	               	DW43      	39B2      	GND                 
          	               	DW45      	39B2      	GND                 
          	               	DW48      	39B2      	GND                 
          	               	DW50      	39B2      	GND                 
          	               	DW52      	39B2      	GND                 
          	               	DW54      	39B2      	GND                 
          	               	DW56      	39B2      	GND                 
          	               	DW58      	39B2      	GND                 
          	               	DW60      	39B2      	GND                 
          	               	DW62      	39B2      	GND                 
          	               	DW64      	39B2      	GND                 
          	               	DW66      	39A2      	GND                 
          	               	DW68      	39A2      	GND                 
          	               	DW70      	39A2      	GND                 
          	               	DW72      	39A2      	GND                 
          	               	DW74      	39A2      	GND                 
          	               	DW76      	39A2      	GND                 
          	               	DW78      	27B3      	M_H_CPU0_SA_DQ<2>   
          	               	DW80      	39A2      	GND                 
          	               	DW82      	39A2      	GND                 
          	               	DW84      	39A2      	GND                 
          	               	DW86      	30A2      	P5E_CPU0_PE3_TX_DP<3>
          	               	DW88      	39A2      	GND                 
          	               	DW90      	30A3      	P5E_CPU0_PE3_RX_DP<4>
          	               	DY2       	33B3      	UPI_CPU1_CPU0_P0P1_DN<4>
          	               	DY4       	39A2      	GND                 
          	               	DY6       	33B2      	UPI_CPU0_CPU1_P1P0_DP<3>
          	               	DY8       	39A2      	GND                 
          	               	DY10      	30B3      	P5E_CPU0_PE2_RX_DN<11>
          	               	DY12      	39A2      	GND                 
          	               	DY14      	30B2      	P5E_CPU0_PE2_TX_DP<12>
          	               	DY16      	39A2      	GND                 
          	               	DY18      	25B2      	M_F_CPU0_SB_DQS_DN<8>
          	               	DY20      	25B3      	M_F_CPU0_SB_DQ<26>  
          	               	DY22      	26B3      	M_G_CPU0_SB_DQ<23>  
          	               	DY24      	26B2      	M_G_CPU0_SB_DQS_DP<7>
          	               	DY26      	26B3      	M_G_CPU0_SB_DQ<18>  
          	               	DY28      	25A3      	M_F_CPU0_SB_DQ<7>   
          	               	DY30      	25B2      	M_F_CPU0_SB_DQS_DP<5>
          	               	DY32      	25A3      	M_F_CPU0_SB_DQ<2>   
          	               	DY34      	26A3      	M_G_CPU0_SB_CB<3>   
          	               	DY36      	26B2      	M_G_CPU0_SB_DQS_DP<4>
          	               	DY38      	26A3      	M_G_CPU0_SB_CB<6>   
          	               	DY40      	26A2      	M_G_CPU0_SB_CS_N<1> 
          	               	DY42      	39A2      	GND                 
          	               	DY44      	26B2      	M_G_CPU0_SB_CA<3>   
          	               	DY47      	26A2      	M_G_CPU0_SA_RSP<1>  
          	               	DY49      	25A3      	M_F_CPU0_CLK_DN<0>  
          	               	DY51      	25B2      	M_F_CPU0_SA_CA<6>   
          	               	DY53      	25B3      	M_F_CPU0_SA_DQ<31>  
          	               	DY55      	25B2      	M_F_CPU0_SA_DQS_DP<8>
          	               	DY57      	25B3      	M_F_CPU0_SA_DQ<26>  
          	               	DY59      	26B3      	M_G_CPU0_SA_DQ<23>  
          	               	DY61      	26B2      	M_G_CPU0_SA_DQS_DP<7>
          	               	DY63      	26B3      	M_G_CPU0_SA_DQ<18>  
          	               	DY65      	25B3      	M_F_CPU0_SA_DQ<15>  
          	               	DY67      	25B2      	M_F_CPU0_SA_DQS_DP<6>
          	               	DY69      	25B3      	M_F_CPU0_SA_DQ<10>  
          	               	DY71      	26B3      	M_G_CPU0_SA_DQ<7>   
          	               	DY73      	26B2      	M_G_CPU0_SA_DQS_DP<5>
          	               	DY75      	26B3      	M_G_CPU0_SA_DQ<2>   
          	               	DY77      	39A2      	GND                 
          	               	DY79      	27B3      	M_H_CPU0_SA_DQ<0>   
          	               	DY81      	35B3      	GND                 
          	               	DY83      	35B3      	GND                 
          	               	DY85      	38B3      	PVCCFA_EHV_FIVRA_CPU0
          	               	DY87      	30A2      	P5E_CPU0_PE3_TX_DN<2>
          	               	DY89      	38B3      	PVCCFA_EHV_FIVRA_CPU0
          	               	DY91      	30A3      	P5E_CPU0_PE3_RX_DN<3>
          	               	E5        	42B2      	GND                 
          	               	E7        	20B3      	M_A_CPU0_SB_DQ<31>  
          	               	E9        	20B2      	M_A_CPU0_SB_DQS_DP<8>
          	               	E11       	20B3      	M_A_CPU0_SB_DQ<26>  
          	               	E13       	21B3      	M_B_CPU0_SB_DQ<29>  
          	               	E15       	21B2      	M_B_CPU0_SB_DQS_DN<8>
          	               	E17       	21B3      	M_B_CPU0_SB_DQ<26>  
          	               	E19       	20B3      	M_A_CPU0_SB_DQ<23>  
          	               	E21       	20B2      	M_A_CPU0_SB_DQS_DP<7>
          	               	E23       	20B3      	M_A_CPU0_SB_DQ<18>  
          	               	E25       	20B3      	M_A_CPU0_SB_DQ<15>  
          	               	E27       	20B2      	M_A_CPU0_SB_DQS_DP<6>
          	               	E29       	20A3      	M_A_CPU0_SB_DQ<10>  
          	               	E31       	20A3      	M_A_CPU0_SB_CB<3>   
          	               	E33       	20B2      	M_A_CPU0_SB_DQS_DP<4>
          	               	E35       	20A3      	M_A_CPU0_SB_CB<6>   
          	               	E37       	20A2      	M_A_CPU0_SB_CS_N<3> 
          	               	E39       	42B2      	GND                 
          	               	E41       	20B2      	M_A_CPU0_SB_CA<3>   
          	               	E43       	20A2      	M_A_CPU0_SB_CA<0>   
          	               	E45       	20A3      	M_A_CPU0_CLK_DP<1>  
          	               	E48       	20B2      	M_A_CPU0_SA_PAR     
          	               	E50       	20B2      	M_A_CPU0_SA_CA<5>   
          	               	E52       	42A2      	GND                 
          	               	E54       	20A2      	M_A_CPU0_SA_CS_N<2> 
          	               	E56       	20B3      	M_A_CPU0_SA_CB<7>   
          	               	E58       	20B2      	M_A_CPU0_SA_DQS_DP<9>
          	               	E60       	20B3      	M_A_CPU0_SA_CB<2>   
          	               	E62       	20B3      	M_A_CPU0_SA_DQ<31>  
          	               	E64       	20B2      	M_A_CPU0_SA_DQS_DP<8>
          	               	E66       	20B3      	M_A_CPU0_SA_DQ<26>  
          	               	E68       	20B3      	M_A_CPU0_SA_DQ<23>  
          	               	E70       	20B2      	M_A_CPU0_SA_DQS_DP<7>
          	               	E72       	20B3      	M_A_CPU0_SA_DQ<17>  
          	               	E74       	42A2      	GND                 
          	               	E76       	42A2      	GND                 
          	               	E78       	42A2      	GND                 
          	               	E80       	34B3      	UPI_CPU1_CPU0_P2P2_DN<23>
          	               	E82       	34B3      	UPI_CPU1_CPU0_P2P2_DN<22>
          	               	E84       	34B2      	UPI_CPU0_CPU1_P2P2_DN<22>
          	               	E86       	42A2      	GND                 
          	               	E88       	34B2      	UPI_CPU0_CPU1_P2P2_DP<21>
          	               	EA1       	33B3      	UPI_CPU1_CPU0_P0P1_DN<3>
          	               	EA3       	38B3      	PVCCFA_EHV_FIVRA_CPU0
          	               	EA5       	33B2      	UPI_CPU0_CPU1_P1P0_DP<2>
          	               	EA7       	38B3      	PVCCFA_EHV_FIVRA_CPU0
          	               	EA9       	30B3      	P5E_CPU0_PE2_RX_DN<12>
          	               	EA11      	38B3      	PVCCFA_EHV_FIVRA_CPU0
          	               	EA13      	30B2      	P5E_CPU0_PE2_TX_DN<12>
          	               	EA15      	38B3      	PVCCFA_EHV_FIVRA_CPU0
          	               	EA17      	25B3      	M_F_CPU0_SB_DQ<28>  
          	               	EA19      	25B3      	M_F_CPU0_SB_DQ<27>  
          	               	EA21      	39A2      	GND                 
          	               	EA23      	26B3      	M_G_CPU0_SB_DQ<22>  
          	               	EA25      	26B3      	M_G_CPU0_SB_DQ<19>  
          	               	EA27      	39A2      	GND                 
          	               	EA29      	25A3      	M_F_CPU0_SB_DQ<6>   
          	               	EA31      	25A3      	M_F_CPU0_SB_DQ<3>   
          	               	EA33      	39A2      	GND                 
          	               	EA35      	26A3      	M_G_CPU0_SB_CB<2>   
          	               	EA37      	26A3      	M_G_CPU0_SB_CB<7>   
          	               	EA39      	39A2      	GND                 
          	               	EA41      	26A2      	M_G_CPU0_SB_CS_N<0> 
          	               	EA43      	26B2      	M_G_CPU0_SB_CA<5>   
          	               	EA45      	39A2      	GND                 
          	               	EA48      	26A2      	M_G_CPU0_SA_RSP<0>  
          	               	EA50      	25B2      	M_F_CPU0_SA_PAR     
          	               	EA52      	39A2      	GND                 
          	               	EA54      	25B3      	M_F_CPU0_SA_DQ<30>  
          	               	EA56      	25B3      	M_F_CPU0_SA_DQ<27>  
          	               	EA58      	39B2      	GND                 
          	               	EA60      	26B3      	M_G_CPU0_SA_DQ<22>  
          	               	EA62      	26B3      	M_G_CPU0_SA_DQ<19>  
          	               	EA64      	39B2      	GND                 
          	               	EA66      	25B3      	M_F_CPU0_SA_DQ<14>  
          	               	EA68      	25B3      	M_F_CPU0_SA_DQ<11>  
          	               	EA70      	39B2      	GND                 
          	               	EA72      	26B3      	M_G_CPU0_SA_DQ<6>   
          	               	EA74      	26B3      	M_G_CPU0_SA_DQ<3>   
          	               	EA76      	39B2      	GND                 
          	               	EA78      	39B2      	GND                 
          	               	EA80      	39B2      	GND                 
          	               	EA82      	35B3      	GND                 
          	               	EA84      	39B2      	GND                 
          	               	EA86      	30A2      	P5E_CPU0_PE3_TX_DP<2>
          	               	EA88      	39B2      	GND                 
          	               	EA90      	30A3      	P5E_CPU0_PE3_RX_DP<3>
          	               	EB2       	33B3      	UPI_CPU1_CPU0_P0P1_DP<3>
          	               	EB4       	39B2      	GND                 
          	               	EB6       	33B2      	UPI_CPU0_CPU1_P1P0_DN<2>
          	               	EB8       	39B2      	GND                 
          	               	EB10      	30B3      	P5E_CPU0_PE2_RX_DP<12>
          	               	EB12      	39B2      	GND                 
          	               	EB14      	30B2      	P5E_CPU0_PE2_TX_DN<13>
          	               	EB16      	39B2      	GND                 
          	               	EB18      	25B2      	M_F_CPU0_SB_DQS_DP<8>
          	               	EB20      	39B2      	GND                 
          	               	EB22      	39B2      	GND                 
          	               	EB24      	26B2      	M_G_CPU0_SB_DQS_DN<7>
          	               	EB26      	39B2      	GND                 
          	               	EB28      	39B2      	GND                 
          	               	EB30      	25B2      	M_F_CPU0_SB_DQS_DN<5>
          	               	EB32      	39B2      	GND                 
          	               	EB34      	39B2      	GND                 
          	               	EB36      	26B2      	M_G_CPU0_SB_DQS_DN<4>
          	               	EB38      	39B2      	GND                 
          	               	EB40      	39B2      	GND                 
          	               	EB42      	26A2      	M_G_CPU0_SB_PAR     
          	               	EB44      	39B2      	GND                 
          	               	EB47      	39B2      	GND                 
          	               	EB49      	25A3      	M_F_CPU0_CLK_DP<0>  
          	               	EB51      	39B2      	GND                 
          	               	EB53      	39B2      	GND                 
          	               	EB55      	25B2      	M_F_CPU0_SA_DQS_DN<8>
          	               	EB57      	39B2      	GND                 
          	               	EB59      	39B2      	GND                 
          	               	EB61      	26B2      	M_G_CPU0_SA_DQS_DN<7>
          	               	EB63      	39B2      	GND                 
          	               	EB65      	39B2      	GND                 
          	               	EB67      	25B2      	M_F_CPU0_SA_DQS_DN<6>
          	               	EB69      	39B2      	GND                 
          	               	EB71      	39B2      	GND                 
          	               	EB73      	26B2      	M_G_CPU0_SA_DQS_DN<5>
          	               	EB75      	39B2      	GND                 
          	               	EB77      	25B3      	M_F_CPU0_SA_DQ<0>   
          	               	EB79      	39B2      	GND                 
          	               	EB81      	35B3      	GND                 
          	               	EB83      	39B2      	GND                 
          	               	EB85      	30A2      	P5E_CPU0_PE3_TX_DN<1>
          	               	EB87      	39B2      	GND                 
          	               	EB89      	30A3      	P5E_CPU0_PE3_RX_DP<2>
          	               	EB91      	39B2      	GND                 
          	               	EC1       	39B2      	GND                 
          	               	EC3       	33B3      	UPI_CPU1_CPU0_P0P1_DN<2>
          	               	EC5       	39B2      	GND                 
          	               	EC7       	33B2      	UPI_CPU0_CPU1_P1P0_DN<1>
          	               	EC9       	39B2      	GND                 
          	               	EC11      	30B3      	P5E_CPU0_PE2_RX_DP<13>
          	               	EC13      	39B2      	GND                 
          	               	EC15      	30B2      	P5E_CPU0_PE2_TX_DP<13>
          	               	EC17      	25B3      	M_F_CPU0_SB_DQ<30>  
          	               	EC19      	39B2      	GND                 
          	               	EC21      	25B2      	M_F_CPU0_SB_DQS_DP<1>
          	               	EC23      	39B2      	GND                 
          	               	EC25      	39B2      	GND                 
          	               	EC27      	24B2      	M_E_CPU0_SB_DQS_DP<0>
          	               	EC29      	39B2      	GND                 
          	               	EC31      	39B2      	GND                 
          	               	EC33      	25B2      	M_F_CPU0_SB_DQS_DP<9>
          	               	EC35      	39B2      	GND                 
          	               	EC37      	39B2      	GND                 
          	               	EC39      	25B2      	M_F_CPU0_SB_CA<6>   
          	               	EC41      	39B2      	GND                 
          	               	EC43      	39B2      	GND                 
          	               	EC45      	24A3      	M_E_CPU0_CLK_DP<1>  
          	               	EC48      	39B2      	GND                 
          	               	EC50      	39B2      	GND                 
          	               	EC52      	25B2      	M_F_CPU0_SA_CA<0>   
          	               	EC54      	39B2      	GND                 
          	               	EC56      	39B2      	GND                 
          	               	EC58      	25B2      	M_F_CPU0_SA_DQS_DP<4>
          	               	EC60      	39B2      	GND                 
          	               	EC62      	39B2      	GND                 
          	               	EC64      	25B2      	M_F_CPU0_SA_DQS_DN<2>
          	               	EC66      	39B2      	GND                 
          	               	EC68      	39B2      	GND                 
          	               	EC70      	24B2      	M_E_CPU0_SA_DQS_DN<1>
          	               	EC72      	39B2      	GND                 
          	               	EC74      	39B2      	GND                 
          	               	EC76      	25B2      	M_F_CPU0_SA_DQS_DP<0>
          	               	EC78      	38B3      	PVCCFA_EHV_FIVRA_CPU0
          	               	EC80      	35B3      	GND                 
          	               	EC82      	39A3      	GND                 
          	               	EC84      	39A3      	GND                 
          	               	EC86      	30A2      	P5E_CPU0_PE3_TX_DP<1>
          	               	EC88      	39A3      	GND                 
          	               	EC90      	30A3      	P5E_CPU0_PE3_RX_DN<2>
          	               	ED2       	33B3      	UPI_CPU1_CPU0_P0P1_DP<2>
          	               	ED4       	39A3      	GND                 
          	               	ED6       	33B2      	UPI_CPU0_CPU1_P1P0_DP<1>
          	               	ED8       	39A3      	GND                 
          	               	ED10      	30B3      	P5E_CPU0_PE2_RX_DN<13>
          	               	ED12      	39A3      	GND                 
          	               	ED14      	30B2      	P5E_CPU0_PE2_TX_DP<14>
          	               	ED16      	39A3      	GND                 
          	               	ED18      	39A3      	GND                 
          	               	ED20      	25B3      	M_F_CPU0_SB_DQ<12>  
          	               	ED22      	25A3      	M_F_CPU0_SB_DQ<9>   
          	               	ED24      	39A3      	GND                 
          	               	ED26      	24A3      	M_E_CPU0_SB_DQ<4>   
          	               	ED28      	24A3      	M_E_CPU0_SB_DQ<1>   
          	               	ED30      	39A3      	GND                 
          	               	ED32      	25A3      	M_F_CPU0_SB_CB<0>   
          	               	ED34      	25A3      	M_F_CPU0_SB_CB<5>   
          	               	ED36      	39A3      	GND                 
          	               	ED38      	25A2      	M_F_CPU0_SB_CS_N<2> 
          	               	ED40      	25B2      	M_F_CPU0_SB_CA<4>   
          	               	ED42      	39A3      	GND                 
          	               	ED44      	24B2      	M_E_CPU0_SA_CA<6>   
          	               	ED47      	27A2      	M_H_CPU0_SB_RSP<1>  
          	               	ED49      	39A3      	GND                 
          	               	ED51      	25B2      	M_F_CPU0_SA_CA<2>   
          	               	ED53      	25A2      	M_F_CPU0_SA_CS_N<3> 
          	               	ED55      	39A3      	GND                 
          	               	ED57      	25B3      	M_F_CPU0_SA_CB<4>   
          	               	ED59      	25B3      	M_F_CPU0_SA_CB<1>   
          	               	ED61      	39A3      	GND                 
          	               	ED63      	25B3      	M_F_CPU0_SA_DQ<20>  
          	               	ED65      	25B3      	M_F_CPU0_SA_DQ<17>  
          	               	ED67      	39A3      	GND                 
          	               	ED69      	24B3      	M_E_CPU0_SA_DQ<12>  
          	               	ED71      	24B3      	M_E_CPU0_SA_DQ<9>   
          	               	ED73      	39A3      	GND                 
          	               	ED75      	25B3      	M_F_CPU0_SA_DQ<4>   
          	               	ED77      	25B3      	M_F_CPU0_SA_DQ<2>   
          	               	ED79      	38B3      	PVCCFA_EHV_FIVRA_CPU0
          	               	ED81      	35B3      	GND                 
          	               	ED83      	35B3      	GND                 
          	               	ED85      	38B3      	PVCCFA_EHV_FIVRA_CPU0
          	               	ED87      	30A2      	P5E_CPU0_PE3_TX_DP<0>
          	               	ED89      	38B3      	PVCCFA_EHV_FIVRA_CPU0
          	               	ED91      	30A3      	P5E_CPU0_PE3_RX_DN<1>
          	               	EE3       	33B3      	UPI_CPU1_CPU0_P0P1_DN<1>
          	               	EE5       	33B2      	UPI_CPU0_CPU1_P1P0_DP<0>
          	               	EE7       	38B3      	PVCCFA_EHV_FIVRA_CPU0
          	               	EE9       	30B3      	P5E_CPU0_PE2_RX_DN<14>
          	               	EE11      	38B3      	PVCCFA_EHV_FIVRA_CPU0
          	               	EE13      	30B2      	P5E_CPU0_PE2_TX_DN<14>
          	               	EE15      	38B3      	PVCCFA_EHV_FIVRA_CPU0
          	               	EE17      	39A3      	GND                 
          	               	EE19      	25B3      	M_F_CPU0_SB_DQ<13>  
          	               	EE21      	25B2      	M_F_CPU0_SB_DQS_DN<1>
          	               	EE23      	25A3      	M_F_CPU0_SB_DQ<8>   
          	               	EE25      	24A3      	M_E_CPU0_SB_DQ<5>   
          	               	EE27      	24B2      	M_E_CPU0_SB_DQS_DN<0>
          	               	EE29      	24A3      	M_E_CPU0_SB_DQ<0>   
          	               	EE31      	25A3      	M_F_CPU0_SB_CB<1>   
          	               	EE33      	25B2      	M_F_CPU0_SB_DQS_DN<9>
          	               	EE35      	25A3      	M_F_CPU0_SB_CB<4>   
          	               	EE37      	25A2      	M_F_CPU0_SB_CS_N<3> 
          	               	EE39      	39A3      	GND                 
          	               	EE41      	25B2      	M_F_CPU0_SB_CA<2>   
          	               	EE43      	24B2      	M_E_CPU0_SA_PAR     
          	               	EE45      	24A3      	M_E_CPU0_CLK_DN<1>  
          	               	EE48      	27A2      	M_H_CPU0_SB_RSP<0>  
          	               	EE50      	25B2      	M_F_CPU0_SA_CA<4>   
          	               	EE52      	39A3      	GND                 
          	               	EE54      	25A2      	M_F_CPU0_SA_CS_N<2> 
          	               	EE56      	25B3      	M_F_CPU0_SA_CB<5>   
          	               	EE58      	25B2      	M_F_CPU0_SA_DQS_DN<4>
          	               	EE60      	25B3      	M_F_CPU0_SA_CB<0>   
          	               	EE62      	25B3      	M_F_CPU0_SA_DQ<21>  
          	               	EE64      	25B2      	M_F_CPU0_SA_DQS_DP<2>
          	               	EE66      	25B3      	M_F_CPU0_SA_DQ<16>  
          	               	EE68      	24B3      	M_E_CPU0_SA_DQ<13>  
          	               	EE70      	24B2      	M_E_CPU0_SA_DQS_DP<1>
          	               	EE72      	24B3      	M_E_CPU0_SA_DQ<8>   
          	               	EE74      	25B3      	M_F_CPU0_SA_DQ<5>   
          	               	EE76      	25B2      	M_F_CPU0_SA_DQS_DN<0>
          	               	EE78      	39A3      	GND                 
          	               	EE80      	39A3      	GND                 
          	               	EE82      	35B3      	GND                 
          	               	EE84      	38B3      	PVCCFA_EHV_FIVRA_CPU0
          	               	EE86      	30A2      	P5E_CPU0_PE3_TX_DN<0>
          	               	EE88      	39B3      	GND                 
          	               	EE90      	30A3      	P5E_CPU0_PE3_RX_DP<1>
          	               	EF2       	39B3      	GND                 
          	               	EF4       	39B3      	GND                 
          	               	EF6       	33B2      	UPI_CPU0_CPU1_P1P0_DN<0>
          	               	EF8       	39B3      	GND                 
          	               	EF10      	30B3      	P5E_CPU0_PE2_RX_DP<14>
          	               	EF12      	39B3      	GND                 
          	               	EF14      	30B2      	P5E_CPU0_PE2_TX_DN<15>
          	               	EF16      	39B3      	GND                 
          	               	EF18      	39B3      	GND                 
          	               	EF20      	39B3      	GND                 
          	               	EF22      	39B3      	GND                 
          	               	EF24      	39B3      	GND                 
          	               	EF26      	39B3      	GND                 
          	               	EF28      	39B3      	GND                 
          	               	EF30      	39B3      	GND                 
          	               	EF32      	39B3      	GND                 
          	               	EF34      	39B3      	GND                 
          	               	EF36      	39B3      	GND                 
          	               	EF38      	39B3      	GND                 
          	               	EF40      	39B3      	GND                 
          	               	EF42      	39B3      	GND                 
          	               	EF44      	39B3      	GND                 
          	               	EF47      	39B3      	GND                 
          	               	EF49      	39B3      	GND                 
          	               	EF51      	39B3      	GND                 
          	               	EF53      	39B3      	GND                 
          	               	EF55      	39B3      	GND                 
          	               	EF57      	39B3      	GND                 
          	               	EF59      	39B3      	GND                 
          	               	EF61      	39B3      	GND                 
          	               	EF63      	39B3      	GND                 
          	               	EF65      	39B3      	GND                 
          	               	EF67      	39B3      	GND                 
          	               	EF69      	39B3      	GND                 
          	               	EF71      	39B3      	GND                 
          	               	EF73      	39B3      	GND                 
          	               	EF75      	39B3      	GND                 
          	               	EF77      	39B3      	GND                 
          	               	EF79      	38B3      	PVCCFA_EHV_FIVRA_CPU0
          	               	EF81      	35B3      	GND                 
          	               	EF83      	35B3      	GND                 
          	               	EF85      	39B3      	GND                 
          	               	EF87      	39B3      	GND                 
          	               	EF89      	39B3      	GND                 
          	               	EG3       	33B3      	UPI_CPU1_CPU0_P0P1_DP<1>
          	               	EG5       	39B3      	GND                 
          	               	EG7       	39B3      	GND                 
          	               	EG9       	39B3      	GND                 
          	               	EG11      	30B3      	P5E_CPU0_PE2_RX_DP<15>
          	               	EG13      	39B3      	GND                 
          	               	EG15      	30B2      	P5E_CPU0_PE2_TX_DP<15>
          	               	EG17      	17B3      	NC_CPU0_HBM0_VIEWDIG1
          	               	EG19      	25B3      	M_F_CPU0_SB_DQ<15>  
          	               	EG21      	25B2      	M_F_CPU0_SB_DQS_DP<6>
          	               	EG23      	25A3      	M_F_CPU0_SB_DQ<10>  
          	               	EG25      	24A3      	M_E_CPU0_SB_DQ<7>   
          	               	EG27      	24B2      	M_E_CPU0_SB_DQS_DP<5>
          	               	EG29      	24A3      	M_E_CPU0_SB_DQ<2>   
          	               	EG31      	25A3      	M_F_CPU0_SB_CB<3>   
          	               	EG33      	25B2      	M_F_CPU0_SB_DQS_DP<4>
          	               	EG35      	25A3      	M_F_CPU0_SB_CB<6>   
          	               	EG37      	25A2      	M_F_CPU0_SB_CS_N<1> 
          	               	EG39      	39B3      	GND                 
          	               	EG41      	25B2      	M_F_CPU0_SB_CA<3>   
          	               	EG43      	24A2      	M_E_CPU0_SB_CA<0>   
          	               	EG45      	24A3      	M_E_CPU0_CLK_DP<0>  
          	               	EG48      	27A2      	M_H_CPU0_SA_RSP<0>  
          	               	EG50      	25B2      	M_F_CPU0_SA_CA<5>   
          	               	EG52      	39B3      	GND                 
          	               	EG54      	25A2      	M_F_CPU0_SA_CS_N<0> 
          	               	EG56      	25B3      	M_F_CPU0_SA_CB<7>   
          	               	EG58      	25B2      	M_F_CPU0_SA_DQS_DP<9>
          	               	EG60      	25B3      	M_F_CPU0_SA_CB<2>   
          	               	EG62      	25B3      	M_F_CPU0_SA_DQ<23>  
          	               	EG64      	25B2      	M_F_CPU0_SA_DQS_DP<7>
          	               	EG66      	25B3      	M_F_CPU0_SA_DQ<18>  
          	               	EG68      	24B3      	M_E_CPU0_SA_DQ<15>  
          	               	EG70      	24B2      	M_E_CPU0_SA_DQS_DP<6>
          	               	EG72      	24B3      	M_E_CPU0_SA_DQ<10>  
          	               	EG74      	25B3      	M_F_CPU0_SA_DQ<7>   
          	               	EG76      	25B2      	M_F_CPU0_SA_DQS_DP<5>
          	               	EG78      	25B3      	M_F_CPU0_SA_DQ<3>   
          	               	EG80      	38B3      	PVCCFA_EHV_FIVRA_CPU0
          	               	EG82      	39B3      	GND                 
          	               	EG84      	39B3      	GND                 
          	               	EG86      	39B3      	GND                 
          	               	EG88      	39B3      	GND                 
          	               	EG90      	39B3      	GND                 
          	               	EH2       	33B3      	UPI_CPU1_CPU0_P0P1_DN<0>
          	               	EH4       	39B3      	GND                 
          	               	EH6       	39B3      	GND                 
          	               	EH8       	26B3      	M_G_CPU0_SB_DQ<25>  
          	               	EH10      	30B3      	P5E_CPU0_PE2_RX_DN<15>
          	               	EH12      	39B3      	GND                 
          	               	EH14      	39B3      	GND                 
          	               	EH16      	39B3      	GND                 
          	               	EH18      	39B3      	GND                 
          	               	EH20      	25B3      	M_F_CPU0_SB_DQ<14>  
          	               	EH22      	25B3      	M_F_CPU0_SB_DQ<11>  
          	               	EH24      	39B3      	GND                 
          	               	EH26      	24A3      	M_E_CPU0_SB_DQ<6>   
          	               	EH28      	24A3      	M_E_CPU0_SB_DQ<3>   
          	               	EH30      	39B3      	GND                 
          	               	EH32      	25A3      	M_F_CPU0_SB_CB<2>   
          	               	EH34      	25A3      	M_F_CPU0_SB_CB<7>   
          	               	EH36      	39A4      	GND                 
          	               	EH38      	25A2      	M_F_CPU0_SB_CS_N<0> 
          	               	EH40      	25B2      	M_F_CPU0_SB_CA<5>   
          	               	EH42      	39A4      	GND                 
          	               	EH44      	24A2      	M_E_CPU0_SB_CA<1>   
          	               	EH47      	27A2      	M_H_CPU0_SA_RSP<1>  
          	               	EH49      	39A4      	GND                 
          	               	EH51      	25B2      	M_F_CPU0_SA_CA<3>   
          	               	EH53      	25A2      	M_F_CPU0_SA_CS_N<1> 
          	               	EH55      	39A4      	GND                 
          	               	EH57      	25B3      	M_F_CPU0_SA_CB<6>   
          	               	EH59      	25B3      	M_F_CPU0_SA_CB<3>   
          	               	EH61      	39A4      	GND                 
          	               	EH63      	25B3      	M_F_CPU0_SA_DQ<22>  
          	               	EH65      	25B3      	M_F_CPU0_SA_DQ<19>  
          	               	EH67      	39A4      	GND                 
          	               	EH69      	24B3      	M_E_CPU0_SA_DQ<14>  
          	               	EH71      	24B3      	M_E_CPU0_SA_DQ<11>  
          	               	EH73      	39A4      	GND                 
          	               	EH75      	25B3      	M_F_CPU0_SA_DQ<6>   
          	               	EH77      	25B3      	M_F_CPU0_SA_DQ<1>   
          	               	EH79      	39A4      	GND                 
          	               	EH81      	39A4      	GND                 
          	               	EH83      	39A4      	GND                 
          	               	EH85      	35B2      	NC                  
          	               	EH87      	35B2      	NC                  
          	               	EH89      	30A3      	P5E_CPU0_PE3_RX_DN<0>
          	               	EJ3       	33B3      	UPI_CPU1_CPU0_P0P1_DP<0>
          	               	EJ5       	26B3      	M_G_CPU0_SB_DQ<29>  
          	               	EJ7       	39A4      	GND                 
          	               	EJ9       	39A4      	GND                 
          	               	EJ11      	39A4      	GND                 
          	               	EJ13      	39A4      	GND                 
          	               	EJ15      	38B3      	PVCCFA_EHV_FIVRA_CPU0
          	               	EJ17      	39A4      	GND                 
          	               	EJ19      	39A4      	GND                 
          	               	EJ21      	25B2      	M_F_CPU0_SB_DQS_DN<6>
          	               	EJ23      	39A4      	GND                 
          	               	EJ25      	39A4      	GND                 
          	               	EJ27      	24B2      	M_E_CPU0_SB_DQS_DN<5>
          	               	EJ29      	39A4      	GND                 
          	               	EJ31      	39A4      	GND                 
          	               	EJ33      	25B2      	M_F_CPU0_SB_DQS_DN<4>
          	               	EJ35      	39A4      	GND                 
          	               	EJ37      	39A4      	GND                 
          	               	EJ39      	25A2      	M_F_CPU0_SB_PAR     
          	               	EJ41      	39B4      	GND                 
          	               	EJ43      	39B4      	GND                 
          	               	EJ45      	24A3      	M_E_CPU0_CLK_DN<0>  
          	               	EJ48      	39B4      	GND                 
          	               	EJ50      	39B4      	GND                 
          	               	EJ52      	25B2      	M_F_CPU0_SA_CA<1>   
          	               	EJ54      	39B4      	GND                 
          	               	EJ56      	39B4      	GND                 
          	               	EJ58      	25B2      	M_F_CPU0_SA_DQS_DN<9>
          	               	EJ60      	39B4      	GND                 
          	               	EJ62      	39B4      	GND                 
          	               	EJ64      	25B2      	M_F_CPU0_SA_DQS_DN<7>
          	               	EJ66      	39B4      	GND                 
          	               	EJ68      	39B4      	GND                 
          	               	EJ70      	24B2      	M_E_CPU0_SA_DQS_DN<6>
          	               	EJ72      	39B4      	GND                 
          	               	EJ74      	39B4      	GND                 
          	               	EJ76      	25B2      	M_F_CPU0_SA_DQS_DN<5>
          	               	EJ78      	39B4      	GND                 
          	               	EJ80      	35B3      	GND                 
          	               	EJ82      	35B3      	GND                 
          	               	EJ84      	38B3      	PVCCFA_EHV_FIVRA_CPU0
          	               	EJ86      	35B2      	NC                  
          	               	EJ88      	39B4      	GND                 
          	               	EJ90      	30A3      	P5E_CPU0_PE3_RX_DP<0>
          	               	EK2       	39B4      	GND                 
          	               	EK4       	39B4      	GND                 
          	               	EK6       	26B3      	M_G_CPU0_SB_DQ<28>  
          	               	EK8       	26B3      	M_G_CPU0_SB_DQ<24>  
          	               	EK10      	39B4      	GND                 
          	               	EK12      	25B2      	M_F_CPU0_SB_DQS_DP<2>
          	               	EK14      	39B4      	GND                 
          	               	EK16      	39B4      	GND                 
          	               	EK18      	24B2      	M_E_CPU0_SB_DQS_DN<3>
          	               	EK20      	39B4      	GND                 
          	               	EK22      	39B4      	GND                 
          	               	EK24      	24B2      	M_E_CPU0_SB_DQS_DN<2>
          	               	EK26      	39B4      	GND                 
          	               	EK28      	39B4      	GND                 
          	               	EK30      	24B2      	M_E_CPU0_SB_DQS_DN<1>
          	               	EK32      	39B4      	GND                 
          	               	EK34      	39B4      	GND                 
          	               	EK36      	24B2      	M_E_CPU0_SB_DQS_DN<9>
          	               	EK38      	39B4      	GND                 
          	               	EK40      	39B4      	GND                 
          	               	EK42      	24B2      	M_E_CPU0_SB_CA<6>   
          	               	EK44      	39B4      	GND                 
          	               	EK47      	39B4      	GND                 
          	               	EK49      	24B2      	M_E_CPU0_SA_CA<2>   
          	               	EK51      	39B4      	GND                 
          	               	EK53      	39B4      	GND                 
          	               	EK55      	24B2      	M_E_CPU0_SA_DQS_DP<4>
          	               	EK57      	39B4      	GND                 
          	               	EK59      	39B4      	GND                 
          	               	EK61      	24B2      	M_E_CPU0_SA_DQS_DN<3>
          	               	EK63      	39B4      	GND                 
          	               	EK65      	39B4      	GND                 
          	               	EK67      	24B2      	M_E_CPU0_SA_DQS_DN<2>
          	               	EK69      	39B4      	GND                 
          	               	EK71      	39B4      	GND                 
          	               	EK73      	24B3      	M_E_CPU0_SA_DQ<5>   
          	               	EK75      	39B4      	GND                 
          	               	EK77      	39B4      	GND                 
          	               	EK79      	39B4      	GND                 
          	               	EK81      	35B3      	GND                 
          	               	EK83      	39B4      	GND                 
          	               	EK85      	35B2      	NC                  
          	               	EK87      	35B2      	NC                  
          	               	EK89      	39B4      	GND                 
          	               	EL3       	39B4      	GND                 
          	               	EL5       	39B4      	GND                 
          	               	EL7       	39B4      	GND                 
          	               	EL9       	39B4      	GND                 
          	               	EL11      	25B3      	M_F_CPU0_SB_DQ<20>  
          	               	EL13      	25B3      	M_F_CPU0_SB_DQ<17>  
          	               	EL15      	39B4      	GND                 
          	               	EL17      	24B3      	M_E_CPU0_SB_DQ<28>  
          	               	EL19      	24B3      	M_E_CPU0_SB_DQ<25>  
          	               	EL21      	39B4      	GND                 
          	               	EL23      	24B3      	M_E_CPU0_SB_DQ<20>  
          	               	EL25      	24B3      	M_E_CPU0_SB_DQ<17>  
          	               	EL27      	39B4      	GND                 
          	               	EL29      	24B3      	M_E_CPU0_SB_DQ<12>  
          	               	EL31      	24A3      	M_E_CPU0_SB_DQ<9>   
          	               	EL33      	39B4      	GND                 
          	               	EL35      	24A3      	M_E_CPU0_SB_CB<0>   
          	               	EL37      	24A3      	M_E_CPU0_SB_CB<5>   
          	               	EL39      	39B4      	GND                 
          	               	EL41      	24A2      	M_E_CPU0_SB_CS_N<3> 
          	               	EL43      	24B2      	M_E_CPU0_SB_CA<4>   
          	               	EL45      	39B4      	GND                 
          	               	EL48      	24B2      	M_E_CPU0_SA_CA<3>   
          	               	EL50      	24A2      	M_E_CPU0_SA_CS_N<3> 
          	               	EL52      	39B4      	GND                 
          	               	EL54      	24B3      	M_E_CPU0_SA_CB<4>   
          	               	EL56      	24B3      	M_E_CPU0_SA_CB<1>   
          	               	EL58      	39B4      	GND                 
          	               	EL60      	24B3      	M_E_CPU0_SA_DQ<28>  
          	               	EL62      	24B3      	M_E_CPU0_SA_DQ<25>  
          	               	EL64      	39B4      	GND                 
          	               	EL66      	24B3      	M_E_CPU0_SA_DQ<22>  
          	               	EL68      	24B2      	M_E_CPU0_SA_DQS_DP<2>
          	               	EL70      	39B4      	GND                 
          	               	EL72      	39B4      	GND                 
          	               	EL74      	24B3      	M_E_CPU0_SA_DQ<4>   
          	               	EL76      	39B4      	GND                 
          	               	EL78      	24B3      	M_E_CPU0_SA_DQ<0>   
          	               	EL80      	35B3      	GND                 
          	               	EL82      	35B3      	GND                 
          	               	EL84      	35B2      	NC                  
          	               	EL86      	39A4      	GND                 
          	               	EL88      	35B2      	NC                  
          	               	EM4       	26B3      	M_G_CPU0_SB_DQ<31>  
          	               	EM6       	26B2      	M_G_CPU0_SB_DQS_DN<8>
          	               	EM8       	39A4      	GND                 
          	               	EM10      	25B3      	M_F_CPU0_SB_DQ<21>  
          	               	EM12      	25B2      	M_F_CPU0_SB_DQS_DN<2>
          	               	EM14      	25B3      	M_F_CPU0_SB_DQ<16>  
          	               	EM16      	24B3      	M_E_CPU0_SB_DQ<29>  
          	               	EM18      	24B2      	M_E_CPU0_SB_DQS_DP<3>
          	               	EM20      	24B3      	M_E_CPU0_SB_DQ<24>  
          	               	EM22      	24B3      	M_E_CPU0_SB_DQ<21>  
          	               	EM24      	24B2      	M_E_CPU0_SB_DQS_DP<2>
          	               	EM26      	24B3      	M_E_CPU0_SB_DQ<16>  
          	               	EM28      	24B3      	M_E_CPU0_SB_DQ<13>  
          	               	EM30      	24B2      	M_E_CPU0_SB_DQS_DP<1>
          	               	EM32      	24A3      	M_E_CPU0_SB_DQ<8>   
          	               	EM34      	24A3      	M_E_CPU0_SB_CB<1>   
          	               	EM36      	24B2      	M_E_CPU0_SB_DQS_DP<9>
          	               	EM38      	24A3      	M_E_CPU0_SB_CB<4>   
          	               	EM40      	24A2      	M_E_CPU0_SB_CS_N<2> 
          	               	EM42      	39A4      	GND                 
          	               	EM44      	24B2      	M_E_CPU0_SB_CA<2>   
          	               	EM47      	24B2      	M_E_CPU0_SA_CA<4>   
          	               	EM49      	39A4      	GND                 
          	               	EM51      	24A2      	M_E_CPU0_SA_CS_N<2> 
          	               	EM53      	24B3      	M_E_CPU0_SA_CB<5>   
          	               	EM55      	24B2      	M_E_CPU0_SA_DQS_DN<4>
          	               	EM57      	24B3      	M_E_CPU0_SA_CB<0>   
          	               	EM59      	24B3      	M_E_CPU0_SA_DQ<29>  
          	               	EM61      	24B2      	M_E_CPU0_SA_DQS_DP<3>
          	               	EM63      	24B3      	M_E_CPU0_SA_DQ<24>  
          	               	EM65      	24B3      	M_E_CPU0_SA_DQ<21>  
          	               	EM67      	24B2      	M_E_CPU0_SA_DQS_DP<7>
          	               	EM69      	24B3      	M_E_CPU0_SA_DQ<17>  
          	               	EM71      	24B3      	M_E_CPU0_SA_DQ<16>  
          	               	EM73      	39A4      	GND                 
          	               	EM75      	24B2      	M_E_CPU0_SA_DQS_DN<5>
          	               	EM77      	24B3      	M_E_CPU0_SA_DQ<1>   
          	               	EM79      	39A4      	GND                 
          	               	EM81      	39A4      	GND                 
          	               	EM83      	39A4      	GND                 
          	               	EM85      	35B2      	NC                  
          	               	EM87      	35B2      	NC                  
          	               	EN5       	26B2      	M_G_CPU0_SB_DQS_DP<8>
          	               	EN7       	26B2      	M_G_CPU0_SB_DQS_DP<3>
          	               	EN9       	39A4      	GND                 
          	               	EN11      	39A4      	GND                 
          	               	EN13      	39A4      	GND                 
          	               	EN15      	39A4      	GND                 
          	               	EN17      	39A4      	GND                 
          	               	EN19      	39A4      	GND                 
          	               	EN21      	39A4      	GND                 
          	               	EN23      	39A4      	GND                 
          	               	EN25      	39A4      	GND                 
          	               	EN27      	39A4      	GND                 
          	               	EN29      	39A4      	GND                 
          	               	EN31      	39A4      	GND                 
          	               	EN33      	39A4      	GND                 
          	               	EN35      	39A4      	GND                 
          	               	EN37      	39B4      	GND                 
          	               	EN39      	39B4      	GND                 
          	               	EN41      	39B4      	GND                 
          	               	EN43      	39B4      	GND                 
          	               	EN45      	39B4      	GND                 
          	               	EN48      	39B4      	GND                 
          	               	EN50      	39B4      	GND                 
          	               	EN52      	39B4      	GND                 
          	               	EN54      	39B4      	GND                 
          	               	EN56      	39B4      	GND                 
          	               	EN58      	39B4      	GND                 
          	               	EN60      	39B4      	GND                 
          	               	EN62      	39B4      	GND                 
          	               	EN64      	39B4      	GND                 
          	               	EN66      	39B4      	GND                 
          	               	EN68      	24B2      	M_E_CPU0_SA_DQS_DN<7>
          	               	EN70      	24B3      	M_E_CPU0_SA_DQ<18>  
          	               	EN72      	39B4      	GND                 
          	               	EN74      	24B2      	M_E_CPU0_SA_DQS_DP<5>
          	               	EN76      	24B2      	M_E_CPU0_SA_DQS_DP<0>
          	               	EN78      	39B4      	GND                 
          	               	EN80      	39B4      	GND                 
          	               	EN82      	35B3      	GND                 
          	               	EN84      	38B3      	PVCCFA_EHV_FIVRA_CPU0
          	               	EN86      	35B2      	NC                  
          	               	EN88      	39B4      	GND                 
          	               	EP4       	26B3      	M_G_CPU0_SB_DQ<30>  
          	               	EP6       	26B2      	M_G_CPU0_SB_DQS_DN<3>
          	               	EP8       	26B3      	M_G_CPU0_SB_DQ<26>  
          	               	EP10      	25B3      	M_F_CPU0_SB_DQ<23>  
          	               	EP12      	25B2      	M_F_CPU0_SB_DQS_DP<7>
          	               	EP14      	25B3      	M_F_CPU0_SB_DQ<18>  
          	               	EP16      	24B3      	M_E_CPU0_SB_DQ<31>  
          	               	EP18      	24B2      	M_E_CPU0_SB_DQS_DP<8>
          	               	EP20      	24B3      	M_E_CPU0_SB_DQ<26>  
          	               	EP22      	24B3      	M_E_CPU0_SB_DQ<23>  
          	               	EP24      	24B2      	M_E_CPU0_SB_DQS_DP<7>
          	               	EP26      	24B3      	M_E_CPU0_SB_DQ<18>  
          	               	EP28      	24B3      	M_E_CPU0_SB_DQ<15>  
          	               	EP30      	24B2      	M_E_CPU0_SB_DQS_DP<6>
          	               	EP32      	24A3      	M_E_CPU0_SB_DQ<10>  
          	               	EP34      	24A3      	M_E_CPU0_SB_CB<3>   
          	               	EP36      	24B2      	M_E_CPU0_SB_DQS_DP<4>
          	               	EP38      	24A3      	M_E_CPU0_SB_CB<6>   
          	               	EP40      	24A2      	M_E_CPU0_SB_CS_N<0> 
          	               	EP42      	24A2      	M_E_CPU0_SB_PAR     
          	               	EP44      	24B2      	M_E_CPU0_SB_CA<3>   
          	               	EP47      	24B2      	M_E_CPU0_SA_CA<5>   
          	               	EP49      	24B2      	M_E_CPU0_SA_CA<0>   
          	               	EP51      	24A2      	M_E_CPU0_SA_CS_N<0> 
          	               	EP53      	24B3      	M_E_CPU0_SA_CB<7>   
          	               	EP55      	24B2      	M_E_CPU0_SA_DQS_DP<9>
          	               	EP57      	24B3      	M_E_CPU0_SA_CB<2>   
          	               	EP59      	24B3      	M_E_CPU0_SA_DQ<31>  
          	               	EP61      	24B2      	M_E_CPU0_SA_DQS_DP<8>
          	               	EP63      	24B3      	M_E_CPU0_SA_DQ<26>  
          	               	EP65      	24B3      	M_E_CPU0_SA_DQ<23>  
          	               	EP67      	39B4      	GND                 
          	               	EP69      	39B4      	GND                 
          	               	EP71      	39B4      	GND                 
          	               	EP73      	24B3      	M_E_CPU0_SA_DQ<6>   
          	               	EP75      	24B2      	M_E_CPU0_SA_DQS_DN<0>
          	               	EP77      	39B4      	GND                 
          	               	EP79      	24B3      	M_E_CPU0_SA_DQ<2>   
          	               	EP81      	35B3      	GND                 
          	               	EP83      	39B4      	GND                 
          	               	EP85      	35B2      	NC                  
          	               	EP87      	35B2      	NC                  
          	               	ER5       	39B4      	GND                 
          	               	ER7       	39B4      	GND                 
          	               	ER9       	39B4      	GND                 
          	               	ER11      	25B3      	M_F_CPU0_SB_DQ<22>  
          	               	ER13      	25B3      	M_F_CPU0_SB_DQ<19>  
          	               	ER15      	39B4      	GND                 
          	               	ER17      	24B3      	M_E_CPU0_SB_DQ<30>  
          	               	ER19      	24B3      	M_E_CPU0_SB_DQ<27>  
          	               	ER21      	39B4      	GND                 
          	               	ER23      	24B3      	M_E_CPU0_SB_DQ<22>  
          	               	ER25      	24B3      	M_E_CPU0_SB_DQ<19>  
          	               	ER27      	39B4      	GND                 
          	               	ER29      	24B3      	M_E_CPU0_SB_DQ<14>  
          	               	ER31      	24B3      	M_E_CPU0_SB_DQ<11>  
          	               	ER33      	39B4      	GND                 
          	               	ER35      	24A3      	M_E_CPU0_SB_CB<2>   
          	               	ER37      	24A3      	M_E_CPU0_SB_CB<7>   
          	               	ER39      	39B4      	GND                 
          	               	ER41      	39B4      	GND                 
          	               	ER43      	39B4      	GND                 
          	               	ER48      	39B4      	GND                 
          	               	ER50      	39B4      	GND                 
          	               	ER52      	39B4      	GND                 
          	               	ER54      	24B3      	M_E_CPU0_SA_CB<6>   
          	               	ER56      	24B3      	M_E_CPU0_SA_CB<3>   
          	               	ER58      	39B4      	GND                 
          	               	ER60      	24B3      	M_E_CPU0_SA_DQ<30>  
          	               	ER62      	24B3      	M_E_CPU0_SA_DQ<27>  
          	               	ER64      	39B4      	GND                 
          	               	ER66      	24B3      	M_E_CPU0_SA_DQ<20>  
          	               	ER68      	24B3      	M_E_CPU0_SA_DQ<19>  
          	               	ER70      	39B4      	GND                 
          	               	ER72      	24B3      	M_E_CPU0_SA_DQ<7>   
          	               	ER74      	39B4      	GND                 
          	               	ER76      	24B3      	M_E_CPU0_SA_DQ<3>   
          	               	ER78      	39B4      	GND                 
          	               	ER80      	39B4      	GND                 
          	               	ER82      	35B3      	GND                 
          	               	ER84      	39B4      	GND                 
          	               	ER86      	39B4      	GND                 
          	               	ET8       	26B3      	M_G_CPU0_SB_DQ<27>  
          	               	ET10      	39B4      	GND                 
          	               	ET12      	25B2      	M_F_CPU0_SB_DQS_DN<7>
          	               	ET14      	39B4      	GND                 
          	               	ET16      	39B4      	GND                 
          	               	ET18      	24B2      	M_E_CPU0_SB_DQS_DN<8>
          	               	ET20      	39B4      	GND                 
          	               	ET22      	39B4      	GND                 
          	               	ET24      	24B2      	M_E_CPU0_SB_DQS_DN<7>
          	               	ET26      	39B4      	GND                 
          	               	ET28      	39B4      	GND                 
          	               	ET30      	24B2      	M_E_CPU0_SB_DQS_DN<6>
          	               	ET32      	39B4      	GND                 
          	               	ET34      	39B4      	GND                 
          	               	ET36      	24B2      	M_E_CPU0_SB_DQS_DN<4>
          	               	ET38      	39B4      	GND                 
          	               	ET40      	24A2      	M_E_CPU0_SB_CS_N<1> 
          	               	ET42      	24B2      	M_E_CPU0_SB_CA<5>   
          	               	ET49      	24B2      	M_E_CPU0_SA_CA<1>   
          	               	ET51      	24A2      	M_E_CPU0_SA_CS_N<1> 
          	               	ET53      	39B4      	GND                 
          	               	ET55      	24B2      	M_E_CPU0_SA_DQS_DN<9>
          	               	ET57      	39B4      	GND                 
          	               	ET59      	39B4      	GND                 
          	               	ET61      	24B2      	M_E_CPU0_SA_DQS_DN<8>
          	               	F4        	42A2      	GND                 
          	               	F6        	42A2      	GND                 
          	               	F8        	20B3      	M_A_CPU0_SB_DQ<30>  
          	               	F10       	20B3      	M_A_CPU0_SB_DQ<27>  
          	               	F12       	42A2      	GND                 
          	               	F14       	21B3      	M_B_CPU0_SB_DQ<31>  
          	               	F16       	21B3      	M_B_CPU0_SB_DQ<27>  
          	               	F18       	42A2      	GND                 
          	               	F20       	20B3      	M_A_CPU0_SB_DQ<22>  
          	               	F22       	20B3      	M_A_CPU0_SB_DQ<19>  
          	               	F24       	42A2      	GND                 
          	               	F26       	20B3      	M_A_CPU0_SB_DQ<14>  
          	               	F28       	20B3      	M_A_CPU0_SB_DQ<11>  
          	               	F30       	42A2      	GND                 
          	               	F32       	20A3      	M_A_CPU0_SB_CB<2>   
          	               	F34       	20A3      	M_A_CPU0_SB_CB<7>   
          	               	F36       	42A2      	GND                 
          	               	F38       	20A2      	M_A_CPU0_SB_CS_N<2> 
          	               	F40       	20B2      	M_A_CPU0_SB_CA<5>   
          	               	F42       	42A2      	GND                 
          	               	F44       	20A2      	M_A_CPU0_SB_CA<1>   
          	               	F47       	14B3      	PWRGD_DRAMPWRGD_CPU0_CD_LVC1_R
          	               	F49       	42A2      	GND                 
          	               	F51       	20B2      	M_A_CPU0_SA_CA<3>   
          	               	F53       	20A2      	M_A_CPU0_SA_CS_N<3> 
          	               	F55       	42A2      	GND                 
          	               	F57       	20B3      	M_A_CPU0_SA_CB<6>   
          	               	F59       	20B3      	M_A_CPU0_SA_CB<3>   
          	               	F61       	42A2      	GND                 
          	               	F63       	20B3      	M_A_CPU0_SA_DQ<30>  
          	               	F65       	20B3      	M_A_CPU0_SA_DQ<27>  
          	               	F67       	42A2      	GND                 
          	               	F69       	20B3      	M_A_CPU0_SA_DQ<22>  
          	               	F71       	20B3      	M_A_CPU0_SA_DQ<19>  
          	               	F73       	42A2      	GND                 
          	               	F75       	20B3      	M_A_CPU0_SA_DQ<7>   
          	               	F77       	20B2      	M_A_CPU0_SA_DQS_DP<5>
          	               	F79       	42B2      	GND                 
          	               	F81       	34B3      	UPI_CPU1_CPU0_P2P2_DP<22>
          	               	F83       	42B2      	GND                 
          	               	F85       	34B2      	UPI_CPU0_CPU1_P2P2_DP<22>
          	               	F87       	34B2      	UPI_CPU0_CPU1_P2P2_DN<20>
          	               	F89       	42B2      	GND                 
          	               	G3        	42B2      	GND                 
          	               	G5        	13B3      	NC_XTAL_CPU0_25M_IN 
          	               	G7        	42B2      	GND                 
          	               	G9        	20B2      	M_A_CPU0_SB_DQS_DN<8>
          	               	G11       	42B2      	GND                 
          	               	G13       	42B2      	GND                 
          	               	G15       	21B2      	M_B_CPU0_SB_DQS_DP<8>
          	               	G17       	42B2      	GND                 
          	               	G19       	42B2      	GND                 
          	               	G21       	20B2      	M_A_CPU0_SB_DQS_DN<7>
          	               	G23       	42B2      	GND                 
          	               	G25       	42B2      	GND                 
          	               	G27       	20B2      	M_A_CPU0_SB_DQS_DN<6>
          	               	G29       	42B2      	GND                 
          	               	G31       	42B2      	GND                 
          	               	G33       	20B2      	M_A_CPU0_SB_DQS_DN<4>
          	               	G35       	42B2      	GND                 
          	               	G37       	42B2      	GND                 
          	               	G39       	20A2      	M_A_CPU0_SB_PAR     
          	               	G41       	42B2      	GND                 
          	               	G43       	42B2      	GND                 
          	               	G45       	20A3      	M_A_CPU0_CLK_DN<1>  
          	               	G48       	42B2      	GND                 
          	               	G50       	42B2      	GND                 
          	               	G52       	20B2      	M_A_CPU0_SA_CA<1>   
          	               	G54       	42B2      	GND                 
          	               	G56       	42B2      	GND                 
          	               	G58       	20B2      	M_A_CPU0_SA_DQS_DN<9>
          	               	G60       	42B2      	GND                 
          	               	G62       	42B2      	GND                 
          	               	G64       	20B2      	M_A_CPU0_SA_DQS_DN<8>
          	               	G66       	42B2      	GND                 
          	               	G68       	42B2      	GND                 
          	               	G70       	20B2      	M_A_CPU0_SA_DQS_DN<7>
          	               	G72       	42B2      	GND                 
          	               	G74       	42B2      	GND                 
          	               	G76       	20B3      	M_A_CPU0_SA_DQ<6>   
          	               	G78       	20B3      	M_A_CPU0_SA_DQ<3>   
          	               	G80       	34B3      	UPI_CPU1_CPU0_P2P2_DP<23>
          	               	G82       	34B3      	UPI_CPU1_CPU0_P2P2_DN<21>
          	               	G84       	42B2      	GND                 
          	               	G86       	34B2      	UPI_CPU0_CPU1_P2P2_DP<19>
          	               	G88       	42B2      	GND                 
          	               	G90       	42B2      	GND                 
          	               	H2        	42B2      	GND                 
          	               	H4        	42B2      	GND                 
          	               	H6        	42B2      	GND                 
          	               	H8        	42B2      	GND                 
          	               	H10       	42B2      	GND                 
          	               	H12       	16B3      	TP_CPU0_A0_DEBUG_EN 
          	               	H14       	42B2      	GND                 
          	               	H16       	42B2      	GND                 
          	               	H18       	21B2      	M_B_CPU0_SB_DQS_DN<2>
          	               	H20       	42B2      	GND                 
          	               	H22       	42B2      	GND                 
          	               	H24       	21B2      	M_B_CPU0_SB_DQS_DN<1>
          	               	H26       	42B2      	GND                 
          	               	H28       	42B2      	GND                 
          	               	H30       	20B2      	M_A_CPU0_SB_DQS_DN<0>
          	               	H32       	42B2      	GND                 
          	               	H34       	42B2      	GND                 
          	               	H36       	21B2      	M_B_CPU0_SB_DQS_DP<9>
          	               	H38       	42B2      	GND                 
          	               	H40       	42B2      	GND                 
          	               	H42       	21B2      	M_B_CPU0_SB_CA<6>   
          	               	H44       	42B2      	GND                 
          	               	H47       	42B2      	GND                 
          	               	H49       	21B2      	M_B_CPU0_SA_CA<0>   
          	               	H51       	42B2      	GND                 
          	               	H53       	42B2      	GND                 
          	               	H55       	21B2      	M_B_CPU0_SA_DQS_DN<4>
          	               	H57       	42B2      	GND                 
          	               	H59       	42B2      	GND                 
          	               	H61       	21B2      	M_B_CPU0_SA_DQS_DN<2>
          	               	H63       	42B2      	GND                 
          	               	H65       	42B2      	GND                 
          	               	H67       	20B2      	M_A_CPU0_SA_DQS_DN<1>
          	               	H69       	42B2      	GND                 
          	               	H71       	42B2      	GND                 
          	               	H73       	21B2      	M_B_CPU0_SA_DQS_DN<0>
          	               	H75       	42B2      	GND                 
          	               	H77       	20B2      	M_A_CPU0_SA_DQS_DN<5>
          	               	H79       	42B2      	GND                 
          	               	H81       	42B2      	GND                 
          	               	H83       	34B3      	UPI_CPU1_CPU0_P2P2_DP<21>
          	               	H85       	34B2      	UPI_CPU0_CPU1_P2P2_DN<19>
          	               	H87       	34B2      	UPI_CPU0_CPU1_P2P2_DP<20>
          	               	H89       	38A2      	PVCCFA_EHV_FIVRA_CPU0
          	               	J3        	32B2      	UPI_CPU0_CPU1_P0P1_DP<0>
          	               	J5        	42A3      	GND                 
          	               	J7        	38A2      	PVCCFA_EHV_FIVRA_CPU0
          	               	J9        	42A3      	GND                 
          	               	J11       	38A2      	PVCCFA_EHV_FIVRA_CPU0
          	               	J13       	18B3      	TP_CPU0_PPD         
          	               	J15       	42A3      	GND                 
          	               	J17       	21B3      	M_B_CPU0_SB_DQ<20>  
          	               	J19       	21B3      	M_B_CPU0_SB_DQ<17>  
          	               	J21       	42A3      	GND                 
          	               	J23       	21B3      	M_B_CPU0_SB_DQ<12>  
          	               	J25       	21A3      	M_B_CPU0_SB_DQ<9>   
          	               	J27       	42A3      	GND                 
          	               	J29       	20A3      	M_A_CPU0_SB_DQ<4>   
          	               	J31       	20A3      	M_A_CPU0_SB_DQ<1>   
          	               	J33       	42A3      	GND                 
          	               	J35       	21A3      	M_B_CPU0_SB_CB<0>   
          	               	J37       	21A3      	M_B_CPU0_SB_CB<5>   
          	               	J39       	42A3      	GND                 
          	               	J41       	21A2      	M_B_CPU0_SB_CS_N<0> 
          	               	J43       	21B2      	M_B_CPU0_SB_CA<4>   
          	               	J45       	42A3      	GND                 
          	               	J48       	21B2      	M_B_CPU0_SA_CA<2>   
          	               	J50       	21A2      	M_B_CPU0_SA_CS_N<1> 
          	               	J52       	42A3      	GND                 
          	               	J54       	21B3      	M_B_CPU0_SA_CB<4>   
          	               	J56       	21B3      	M_B_CPU0_SA_CB<1>   
          	               	J58       	42A3      	GND                 
          	               	J60       	21B3      	M_B_CPU0_SA_DQ<20>  
          	               	J62       	21B3      	M_B_CPU0_SA_DQ<17>  
          	               	J64       	42A3      	GND                 
          	               	J66       	20B3      	M_A_CPU0_SA_DQ<12>  
          	               	J68       	20B3      	M_A_CPU0_SA_DQ<9>   
          	               	J70       	42A3      	GND                 
          	               	J72       	21B3      	M_B_CPU0_SA_DQ<4>   
          	               	J74       	21B3      	M_B_CPU0_SA_DQ<1>   
          	               	J76       	42A3      	GND                 
          	               	J78       	42A3      	GND                 
          	               	J80       	38A2      	PVCCFA_EHV_FIVRA_CPU0
          	               	J82       	34B3      	UPI_CPU1_CPU0_P2P2_DN<19>
          	               	J84       	42A3      	GND                 
          	               	J86       	42A3      	GND                 
          	               	J88       	42A3      	GND                 
          	               	J90       	31B3      	P5E_CPU0_PE4_RX_DN<0>
          	               	K2        	42A3      	GND                 
          	               	K4        	32B2      	UPI_CPU0_CPU1_P0P1_DN<0>
          	               	K6        	32B3      	UPI_CPU1_CPU0_P1P0_DN<0>
          	               	K8        	42A3      	GND                 
          	               	K10       	29B3      	P5E_CPU0_PE0_RX_DN<0>
          	               	K12       	42A3      	GND                 
          	               	K14       	42A3      	GND                 
          	               	K16       	21B3      	M_B_CPU0_SB_DQ<21>  
          	               	K18       	21B2      	M_B_CPU0_SB_DQS_DP<2>
          	               	K20       	21B3      	M_B_CPU0_SB_DQ<16>  
          	               	K22       	21B3      	M_B_CPU0_SB_DQ<13>  
          	               	K24       	21B2      	M_B_CPU0_SB_DQS_DP<1>
          	               	K26       	21A3      	M_B_CPU0_SB_DQ<8>   
          	               	K28       	20A3      	M_A_CPU0_SB_DQ<5>   
          	               	K30       	20B2      	M_A_CPU0_SB_DQS_DP<0>
          	               	K32       	20A3      	M_A_CPU0_SB_DQ<0>   
          	               	K34       	21A3      	M_B_CPU0_SB_CB<1>   
          	               	K36       	21B2      	M_B_CPU0_SB_DQS_DN<9>
          	               	K38       	21A3      	M_B_CPU0_SB_CB<4>   
          	               	K40       	21A2      	M_B_CPU0_SB_CS_N<1> 
          	               	K42       	42A3      	GND                 
          	               	K44       	21B2      	M_B_CPU0_SB_CA<2>   
          	               	K47       	21B2      	M_B_CPU0_SA_CA<4>   
          	               	K49       	42B3      	GND                 
          	               	K51       	21A2      	M_B_CPU0_SA_CS_N<0> 
          	               	K53       	21B3      	M_B_CPU0_SA_CB<5>   
          	               	K55       	21B2      	M_B_CPU0_SA_DQS_DP<4>
          	               	K57       	21B3      	M_B_CPU0_SA_CB<0>   
          	               	K59       	21B3      	M_B_CPU0_SA_DQ<21>  
          	               	K61       	21B2      	M_B_CPU0_SA_DQS_DP<2>
          	               	K63       	21B3      	M_B_CPU0_SA_DQ<16>  
          	               	K65       	20B3      	M_A_CPU0_SA_DQ<13>  
          	               	K67       	20B2      	M_A_CPU0_SA_DQS_DP<1>
          	               	K69       	20B3      	M_A_CPU0_SA_DQ<8>   
          	               	K71       	21B3      	M_B_CPU0_SA_DQ<5>   
          	               	K73       	21B2      	M_B_CPU0_SA_DQS_DP<0>
          	               	K75       	21B3      	M_B_CPU0_SA_DQ<0>   
          	               	K77       	42B3      	GND                 
          	               	K79       	34B3      	UPI_CPU1_CPU0_P2P2_DN<20>
          	               	K81       	34B3      	UPI_CPU1_CPU0_P2P2_DP<18>
          	               	K83       	42B3      	GND                 
          	               	K85       	42B3      	GND                 
          	               	K87       	38B2      	PVCCFA_EHV_FIVRA_CPU0
          	               	K89       	31B3      	P5E_CPU0_PE4_RX_DP<0>
          	               	L3        	32B2      	UPI_CPU0_CPU1_P0P1_DP<1>
          	               	L5        	42B3      	GND                 
          	               	L7        	32B3      	UPI_CPU1_CPU0_P1P0_DP<0>
          	               	L9        	42B3      	GND                 
          	               	L11       	29B3      	P5E_CPU0_PE0_RX_DP<0>
          	               	L13       	42B3      	GND                 
          	               	L15       	42B3      	GND                 
          	               	L17       	42B3      	GND                 
          	               	L19       	42B3      	GND                 
          	               	L21       	42B3      	GND                 
          	               	L23       	42B3      	GND                 
          	               	L25       	42B3      	GND                 
          	               	L27       	42B3      	GND                 
          	               	L29       	42B3      	GND                 
          	               	L31       	42B3      	GND                 
          	               	L33       	42B3      	GND                 
          	               	L35       	42B3      	GND                 
          	               	L37       	42B3      	GND                 
          	               	L39       	42B3      	GND                 
          	               	L41       	42B3      	GND                 
          	               	L43       	42B3      	GND                 
          	               	L45       	42B3      	GND                 
          	               	L48       	42B3      	GND                 
          	               	L50       	42B3      	GND                 
          	               	L52       	42B3      	GND                 
          	               	L54       	42B3      	GND                 
          	               	L56       	42B3      	GND                 
          	               	L58       	42B3      	GND                 
          	               	L60       	42B3      	GND                 
          	               	L62       	42B3      	GND                 
          	               	L64       	42B3      	GND                 
          	               	L66       	42B3      	GND                 
          	               	L68       	42B3      	GND                 
          	               	L70       	42B3      	GND                 
          	               	L72       	42B3      	GND                 
          	               	L74       	42B3      	GND                 
          	               	L76       	42B3      	GND                 
          	               	L78       	42B3      	GND                 
          	               	L80       	34B3      	UPI_CPU1_CPU0_P2P2_DN<18>
          	               	L82       	34B3      	UPI_CPU1_CPU0_P2P2_DP<19>
          	               	L84       	38B2      	PVCCFA_EHV_FIVRA_CPU0
          	               	L86       	31B2      	P5E_CPU0_PE4_TX_DN<0>
          	               	L88       	42B3      	GND                 
          	               	L90       	42B3      	GND                 
          	               	M2        	32B2      	UPI_CPU0_CPU1_P0P1_DN<1>
          	               	M4        	42B3      	GND                 
          	               	M6        	32B3      	UPI_CPU1_CPU0_P1P0_DP<1>
          	               	M8        	42B3      	GND                 
          	               	M10       	29B3      	P5E_CPU0_PE0_RX_DN<1>
          	               	M12       	42B3      	GND                 
          	               	M14       	29B2      	P5E_CPU0_PE0_TX_DP<0>
          	               	M16       	21B3      	M_B_CPU0_SB_DQ<23>  
          	               	M18       	21B2      	M_B_CPU0_SB_DQS_DN<7>
          	               	M20       	21B3      	M_B_CPU0_SB_DQ<18>  
          	               	M22       	21B3      	M_B_CPU0_SB_DQ<15>  
          	               	M24       	21B2      	M_B_CPU0_SB_DQS_DN<6>
          	               	M26       	21A3      	M_B_CPU0_SB_DQ<10>  
          	               	M28       	20A3      	M_A_CPU0_SB_DQ<7>   
          	               	M30       	20B2      	M_A_CPU0_SB_DQS_DN<5>
          	               	M32       	20A3      	M_A_CPU0_SB_DQ<2>   
          	               	M34       	21A3      	M_B_CPU0_SB_CB<3>   
          	               	M36       	21B2      	M_B_CPU0_SB_DQS_DP<4>
          	               	M38       	21A3      	M_B_CPU0_SB_CB<6>   
          	               	M40       	21A2      	M_B_CPU0_SB_CS_N<3> 
          	               	M42       	42B3      	GND                 
          	               	M44       	21B2      	M_B_CPU0_SB_CA<3>   
          	               	M47       	21B2      	M_B_CPU0_SA_CA<5>   
          	               	M49       	42B3      	GND                 
          	               	M51       	21A2      	M_B_CPU0_SA_CS_N<2> 
          	               	M53       	21B3      	M_B_CPU0_SA_CB<7>   
          	               	M55       	21B2      	M_B_CPU0_SA_DQS_DN<9>
          	               	M57       	21B3      	M_B_CPU0_SA_CB<2>   
          	               	M59       	21B3      	M_B_CPU0_SA_DQ<23>  
          	               	M61       	21B2      	M_B_CPU0_SA_DQS_DN<7>
          	               	M63       	21B3      	M_B_CPU0_SA_DQ<18>  
          	               	M65       	20B3      	M_A_CPU0_SA_DQ<15>  
          	               	M67       	20B2      	M_A_CPU0_SA_DQS_DP<6>
          	               	M69       	20B3      	M_A_CPU0_SA_DQ<10>  
          	               	M71       	21B3      	M_B_CPU0_SA_DQ<7>   
          	               	M73       	21B2      	M_B_CPU0_SA_DQS_DN<5>
          	               	M75       	21B3      	M_B_CPU0_SA_DQ<2>   
          	               	M77       	20B3      	M_A_CPU0_SA_DQ<2>   
          	               	M79       	34B3      	UPI_CPU1_CPU0_P2P2_DP<20>
          	               	M81       	42B3      	GND                 
          	               	M83       	42B3      	GND                 
          	               	M85       	38B2      	PVCCFA_EHV_FIVRA_CPU0
          	               	M87       	31B2      	P5E_CPU0_PE4_TX_DP<0>
          	               	M89       	38B2      	PVCCFA_EHV_FIVRA_CPU0
          	               	N1        	32B2      	UPI_CPU0_CPU1_P0P1_DN<2>
          	               	N3        	37A1      	PVCCFA_EHV_CPU0     
          	               	N5        	32B3      	UPI_CPU1_CPU0_P1P0_DN<1>
          	               	N7        	38B2      	PVCCFA_EHV_FIVRA_CPU0
          	               	N9        	29B3      	P5E_CPU0_PE0_RX_DP<1>
          	               	N11       	38B2      	PVCCFA_EHV_FIVRA_CPU0
          	               	N13       	29B2      	P5E_CPU0_PE0_TX_DN<0>
          	               	N15       	42B3      	GND                 
          	               	N17       	21B3      	M_B_CPU0_SB_DQ<22>  
          	               	N19       	21B3      	M_B_CPU0_SB_DQ<19>  
          	               	N21       	42B3      	GND                 
          	               	N23       	21B3      	M_B_CPU0_SB_DQ<14>  
          	               	N25       	21B3      	M_B_CPU0_SB_DQ<11>  
          	               	N27       	42B3      	GND                 
          	               	N29       	20A3      	M_A_CPU0_SB_DQ<6>   
          	               	N31       	20A3      	M_A_CPU0_SB_DQ<3>   
          	               	N33       	42B3      	GND                 
          	               	N35       	21A3      	M_B_CPU0_SB_CB<2>   
          	               	N37       	21A3      	M_B_CPU0_SB_CB<7>   
          	               	N39       	42B3      	GND                 
          	               	N41       	21A2      	M_B_CPU0_SB_CS_N<2> 
          	               	N43       	21B2      	M_B_CPU0_SB_CA<5>   
          	               	N45       	42B3      	GND                 
          	               	N48       	21B2      	M_B_CPU0_SA_CA<3>   
          	               	N50       	21A2      	M_B_CPU0_SA_CS_N<3> 
          	               	N52       	42B3      	GND                 
          	               	N54       	21B3      	M_B_CPU0_SA_CB<6>   
          	               	N56       	21B3      	M_B_CPU0_SA_CB<3>   
          	               	N58       	42B3      	GND                 
          	               	N60       	21B3      	M_B_CPU0_SA_DQ<22>  
          	               	N62       	21B3      	M_B_CPU0_SA_DQ<19>  
          	               	N64       	42B3      	GND                 
          	               	N66       	20B3      	M_A_CPU0_SA_DQ<14>  
          	               	N68       	20B3      	M_A_CPU0_SA_DQ<11>  
          	               	N70       	42B3      	GND                 
          	               	N72       	21B3      	M_B_CPU0_SA_DQ<6>   
          	               	N74       	21B3      	M_B_CPU0_SA_DQ<3>   
          	               	N76       	42A4      	GND                 
          	               	N78       	42A4      	GND                 
          	               	N80       	42A4      	GND                 
          	               	N82       	42A4      	GND                 
          	               	N84       	42A4      	GND                 
          	               	N86       	31B2      	P5E_CPU0_PE4_TX_DP<1>
          	               	N88       	42A4      	GND                 
          	               	N90       	31B3      	P5E_CPU0_PE4_RX_DP<1>
          	               	P2        	32B2      	UPI_CPU0_CPU1_P0P1_DP<2>
          	               	P4        	42A4      	GND                 
          	               	P6        	32B3      	UPI_CPU1_CPU0_P1P0_DN<2>
          	               	P8        	42A4      	GND                 
          	               	P10       	29B3      	P5E_CPU0_PE0_RX_DN<2>
          	               	P12       	42A4      	GND                 
          	               	P14       	29B2      	P5E_CPU0_PE0_TX_DN<1>
          	               	P16       	42A4      	GND                 
          	               	P18       	21B2      	M_B_CPU0_SB_DQS_DP<7>
          	               	P20       	42A4      	GND                 
          	               	P22       	42A4      	GND                 
          	               	P24       	21B2      	M_B_CPU0_SB_DQS_DP<6>
          	               	P26       	42A4      	GND                 
          	               	P28       	42A4      	GND                 
          	               	P30       	20B2      	M_A_CPU0_SB_DQS_DP<5>
          	               	P32       	42A4      	GND                 
          	               	P34       	42A4      	GND                 
          	               	P36       	21B2      	M_B_CPU0_SB_DQS_DN<4>
          	               	P38       	42A4      	GND                 
          	               	P40       	42A4      	GND                 
          	               	P42       	21A2      	M_B_CPU0_SB_PAR     
          	               	P44       	42A4      	GND                 
          	               	P47       	42A4      	GND                 
          	               	P49       	21B2      	M_B_CPU0_SA_CA<1>   
          	               	P51       	42A4      	GND                 
          	               	P53       	42A4      	GND                 
          	               	P55       	21B2      	M_B_CPU0_SA_DQS_DP<9>
          	               	P57       	42B4      	GND                 
          	               	P59       	42B4      	GND                 
          	               	P61       	21B2      	M_B_CPU0_SA_DQS_DP<7>
          	               	P63       	42B4      	GND                 
          	               	P65       	42B4      	GND                 
          	               	P67       	20B2      	M_A_CPU0_SA_DQS_DN<6>
          	               	P69       	42B4      	GND                 
          	               	P71       	42B4      	GND                 
          	               	P73       	21B2      	M_B_CPU0_SA_DQS_DP<5>
          	               	P75       	42B4      	GND                 
          	               	P77       	42B4      	GND                 
          	               	P79       	38B2      	PVCCFA_EHV_FIVRA_CPU0
          	               	P81       	34B2      	UPI_CPU0_CPU1_P2P2_DN<18>
          	               	P83       	34B2      	UPI_CPU0_CPU1_P2P2_DP<17>
          	               	P85       	31B2      	P5E_CPU0_PE4_TX_DN<1>
          	               	P87       	42B4      	GND                 
          	               	P89       	31B3      	P5E_CPU0_PE4_RX_DN<1>
          	               	P91       	42B4      	GND                 
          	               	R1        	42B4      	GND                 
          	               	R3        	32B2      	UPI_CPU0_CPU1_P0P1_DP<3>
          	               	R5        	42B4      	GND                 
          	               	R7        	32B3      	UPI_CPU1_CPU0_P1P0_DP<2>
          	               	R9        	42B4      	GND                 
          	               	R11       	29B3      	P5E_CPU0_PE0_RX_DP<2>
          	               	R13       	42B4      	GND                 
          	               	R15       	29B2      	P5E_CPU0_PE0_TX_DP<1>
          	               	R17       	42B4      	GND                 
          	               	R19       	42B4      	GND                 
          	               	R21       	22B2      	M_C_CPU0_SB_DQS_DN<2>
          	               	R23       	42B4      	GND                 
          	               	R25       	42B4      	GND                 
          	               	R27       	21B2      	M_B_CPU0_SB_DQS_DN<0>
          	               	R29       	42B4      	GND                 
          	               	R31       	42B4      	GND                 
          	               	R33       	22B2      	M_C_CPU0_SB_DQS_DN<9>
          	               	R35       	42B4      	GND                 
          	               	R37       	42B4      	GND                 
          	               	R39       	22B2      	M_C_CPU0_SB_CA<6>   
          	               	R41       	42B4      	GND                 
          	               	R43       	42B4      	GND                 
          	               	R45       	21A3      	M_B_CPU0_CLK_DN<0>  
          	               	R48       	42B4      	GND                 
          	               	R50       	42B4      	GND                 
          	               	R52       	22B2      	M_C_CPU0_SA_CA<0>   
          	               	R54       	42B4      	GND                 
          	               	R56       	42B4      	GND                 
          	               	R58       	21B2      	M_B_CPU0_SA_DQS_DN<3>
          	               	R60       	42B4      	GND                 
          	               	R62       	42B4      	GND                 
          	               	R64       	22B2      	M_C_CPU0_SA_DQS_DN<2>
          	               	R66       	42B4      	GND                 
          	               	R68       	42B4      	GND                 
          	               	R70       	21B2      	M_B_CPU0_SA_DQS_DN<1>
          	               	R72       	42B4      	GND                 
          	               	R74       	42B4      	GND                 
          	               	R76       	22B2      	M_C_CPU0_SA_DQS_DN<0>
          	               	R78       	42B4      	GND                 
          	               	R80       	38B2      	PVCCFA_EHV_FIVRA_CPU0
          	               	R82       	34B2      	UPI_CPU0_CPU1_P2P2_DN<17>
          	               	R84       	42B4      	GND                 
          	               	R86       	31B2      	P5E_CPU0_PE4_TX_DN<2>
          	               	R88       	42B4      	GND                 
          	               	R90       	31B3      	P5E_CPU0_PE4_RX_DP<2>
          	               	T2        	32B2      	UPI_CPU0_CPU1_P0P1_DN<3>
          	               	T4        	42B4      	GND                 
          	               	T6        	32B3      	UPI_CPU1_CPU0_P1P0_DN<3>
          	               	T8        	42B4      	GND                 
          	               	T10       	29B3      	P5E_CPU0_PE0_RX_DN<3>
          	               	T12       	42B4      	GND                 
          	               	T14       	29B2      	P5E_CPU0_PE0_TX_DP<2>
          	               	T16       	42B4      	GND                 
          	               	T18       	42B4      	GND                 
          	               	T20       	22B3      	M_C_CPU0_SB_DQ<20>  
          	               	T22       	22B3      	M_C_CPU0_SB_DQ<17>  
          	               	T24       	42B4      	GND                 
          	               	T26       	21A3      	M_B_CPU0_SB_DQ<4>   
          	               	T28       	21A3      	M_B_CPU0_SB_DQ<1>   
          	               	T30       	42B4      	GND                 
          	               	T32       	22A3      	M_C_CPU0_SB_CB<0>   
          	               	T34       	22A3      	M_C_CPU0_SB_CB<5>   
          	               	T36       	42B4      	GND                 
          	               	T38       	22A2      	M_C_CPU0_SB_CS_N<0> 
          	               	T40       	22B2      	M_C_CPU0_SB_CA<4>   
          	               	T42       	42B4      	GND                 
          	               	T44       	21A2      	M_B_CPU0_SB_CA<0>   
          	               	T47       	22B2      	M_C_CPU0_SA_PAR     
          	               	T49       	42B4      	GND                 
          	               	T51       	22B2      	M_C_CPU0_SA_CA<2>   
          	               	T53       	22A2      	M_C_CPU0_SA_CS_N<1> 
          	               	T55       	42B4      	GND                 
          	               	T57       	21B3      	M_B_CPU0_SA_DQ<28>  
          	               	T59       	21B3      	M_B_CPU0_SA_DQ<25>  
          	               	T61       	42B4      	GND                 
          	               	T63       	22B3      	M_C_CPU0_SA_DQ<20>  
          	               	T65       	22B3      	M_C_CPU0_SA_DQ<17>  
          	               	T67       	42B4      	GND                 
          	               	T69       	21B3      	M_B_CPU0_SA_DQ<12>  
          	               	T71       	21B3      	M_B_CPU0_SA_DQ<9>   
          	               	T73       	42B4      	GND                 
          	               	T75       	22B3      	M_C_CPU0_SA_DQ<4>   
          	               	T77       	22B3      	M_C_CPU0_SA_DQ<1>   
          	               	T79       	42B4      	GND                 
          	               	T81       	34B2      	UPI_CPU0_CPU1_P2P2_DP<18>
          	               	T83       	42B4      	GND                 
          	               	T85       	38B2      	PVCCFA_EHV_FIVRA_CPU0
          	               	T87       	31B2      	P5E_CPU0_PE4_TX_DP<2>
          	               	T89       	38B2      	PVCCFA_EHV_FIVRA_CPU0
          	               	T91       	31B3      	P5E_CPU0_PE4_RX_DN<2>
          	               	U1        	32B2      	UPI_CPU0_CPU1_P0P1_DN<4>
          	               	U3        	37A1      	PVCCFA_EHV_CPU0     
          	               	U5        	32B3      	UPI_CPU1_CPU0_P1P0_DP<3>
          	               	U7        	38B2      	PVCCFA_EHV_FIVRA_CPU0
          	               	U9        	29B3      	P5E_CPU0_PE0_RX_DP<3>
          	               	U11       	38B2      	PVCCFA_EHV_FIVRA_CPU0
          	               	U13       	29B2      	P5E_CPU0_PE0_TX_DN<2>
          	               	U15       	38B2      	PVCCFA_EHV_FIVRA_CPU0
          	               	U17       	17B3      	NC_CPU0_HBM0_VIEWDIG0
          	               	U19       	22B3      	M_C_CPU0_SB_DQ<21>  
          	               	U21       	22B2      	M_C_CPU0_SB_DQS_DP<2>
          	               	U23       	22B3      	M_C_CPU0_SB_DQ<16>  
          	               	U25       	21A3      	M_B_CPU0_SB_DQ<5>   
          	               	U27       	21B2      	M_B_CPU0_SB_DQS_DP<0>
          	               	U29       	21A3      	M_B_CPU0_SB_DQ<0>   
          	               	U31       	22A3      	M_C_CPU0_SB_CB<1>   
          	               	U33       	22B2      	M_C_CPU0_SB_DQS_DP<9>
          	               	U35       	22A3      	M_C_CPU0_SB_CB<4>   
          	               	U37       	22A2      	M_C_CPU0_SB_CS_N<1> 
          	               	U39       	42B4      	GND                 
          	               	U41       	22B2      	M_C_CPU0_SB_CA<2>   
          	               	U43       	21A2      	M_B_CPU0_SB_CA<1>   
          	               	U45       	21A3      	M_B_CPU0_CLK_DP<0>  
          	               	U48       	22B2      	M_C_CPU0_SA_CA<6>   
          	               	U50       	22B2      	M_C_CPU0_SA_CA<4>   
          	               	U52       	42B4      	GND                 
          	               	U54       	22A2      	M_C_CPU0_SA_CS_N<0> 
          	               	U56       	21B3      	M_B_CPU0_SA_DQ<29>  
          	               	U58       	21B2      	M_B_CPU0_SA_DQS_DP<3>
          	               	U60       	21B3      	M_B_CPU0_SA_DQ<24>  
          	               	U62       	22B3      	M_C_CPU0_SA_DQ<21>  
          	               	U64       	22B2      	M_C_CPU0_SA_DQS_DP<2>
          	               	U66       	22B3      	M_C_CPU0_SA_DQ<16>  
          	               	U68       	21B3      	M_B_CPU0_SA_DQ<13>  
          	               	U70       	21B2      	M_B_CPU0_SA_DQS_DP<1>
          	               	U72       	21B3      	M_B_CPU0_SA_DQ<8>   
          	               	U74       	22B3      	M_C_CPU0_SA_DQ<5>   
          	               	U76       	22B2      	M_C_CPU0_SA_DQS_DP<0>
          	               	U78       	22B3      	M_C_CPU0_SA_DQ<0>   
          	               	U80       	34B2      	UPI_CPU0_CPU1_P2P2_DN<16>
          	               	U82       	42B4      	GND                 
          	               	U84       	42B4      	GND                 
          	               	U86       	31B2      	P5E_CPU0_PE4_TX_DN<3>
          	               	U88       	42B4      	GND                 
          	               	U90       	31B3      	P5E_CPU0_PE4_RX_DP<3>
          	               	V2        	32B2      	UPI_CPU0_CPU1_P0P1_DP<4>
          	               	V4        	42A4      	GND                 
          	               	V6        	32B3      	UPI_CPU1_CPU0_P1P0_DN<4>
          	               	V8        	42A4      	GND                 
          	               	V10       	29B3      	P5E_CPU0_PE0_RX_DN<4>
          	               	V12       	42A4      	GND                 
          	               	V14       	29B2      	P5E_CPU0_PE0_TX_DN<3>
          	               	V16       	42A4      	GND                 
          	               	V18       	42A4      	GND                 
          	               	V20       	42A4      	GND                 
          	               	V22       	42A4      	GND                 
          	               	V24       	42A4      	GND                 
          	               	V26       	42A4      	GND                 
          	               	V28       	42A4      	GND                 
          	               	V30       	42A4      	GND                 
          	               	V32       	42A4      	GND                 
          	               	V34       	42A4      	GND                 
          	               	V36       	42A4      	GND                 
          	               	V38       	42A4      	GND                 
          	               	V40       	42A4      	GND                 
          	               	V42       	42A4      	GND                 
          	               	V44       	42A4      	GND                 
          	               	V47       	42A4      	GND                 
          	               	V49       	42A4      	GND                 
          	               	V51       	42A4      	GND                 
          	               	V53       	42A4      	GND                 
          	               	V55       	42B4      	GND                 
          	               	V57       	42B4      	GND                 
          	               	V59       	42B4      	GND                 
          	               	V61       	42B4      	GND                 
          	               	V63       	42B4      	GND                 
          	               	V65       	42B4      	GND                 
          	               	V67       	42B4      	GND                 
          	               	V69       	42B4      	GND                 
          	               	V71       	42B4      	GND                 
          	               	V73       	42B4      	GND                 
          	               	V75       	42B4      	GND                 
          	               	V77       	42B4      	GND                 
          	               	V79       	42B4      	GND                 
          	               	V81       	34B2      	UPI_CPU0_CPU1_P2P2_DP<16>
          	               	V83       	34B2      	UPI_CPU0_CPU1_P2P2_DN<15>
          	               	V85       	31B2      	P5E_CPU0_PE4_TX_DP<3>
          	               	V87       	42B4      	GND                 
          	               	V89       	31B3      	P5E_CPU0_PE4_RX_DN<3>
          	               	V91       	42B4      	GND                 
          	               	W1        	42B4      	GND                 
          	               	W3        	32B2      	UPI_CPU0_CPU1_P0P1_DP<5>
          	               	W5        	42B4      	GND                 
          	               	W7        	32B3      	UPI_CPU1_CPU0_P1P0_DP<4>
          	               	W9        	42B4      	GND                 
          	               	W11       	29B3      	P5E_CPU0_PE0_RX_DP<4>
          	               	W13       	42B4      	GND                 
          	               	W15       	29B2      	P5E_CPU0_PE0_TX_DP<3>
          	               	W17       	17B3      	NC_CPU0_HBM1_VIEWDIG0
          	               	W19       	22B3      	M_C_CPU0_SB_DQ<23>  
          	               	W21       	22B2      	M_C_CPU0_SB_DQS_DN<7>
          	               	W23       	22B3      	M_C_CPU0_SB_DQ<18>  
          	               	W25       	21A3      	M_B_CPU0_SB_DQ<7>   
          	               	W27       	21B2      	M_B_CPU0_SB_DQS_DN<5>
          	               	W29       	21A3      	M_B_CPU0_SB_DQ<2>   
          	               	W31       	22A3      	M_C_CPU0_SB_CB<3>   
          	               	W33       	22B2      	M_C_CPU0_SB_DQS_DN<4>
          	               	W35       	22A3      	M_C_CPU0_SB_CB<6>   
          	               	W37       	22A2      	M_C_CPU0_SB_CS_N<3> 
          	               	W39       	42B4      	GND                 
          	               	W41       	22B2      	M_C_CPU0_SB_CA<3>   
          	               	W43       	21B2      	M_B_CPU0_SA_PAR     
          	               	W45       	21A3      	M_B_CPU0_CLK_DN<1>  
          	               	W48       	22A2      	M_C_CPU0_SB_CA<0>   
          	               	W50       	22B2      	M_C_CPU0_SA_CA<5>   
          	               	W52       	42B4      	GND                 
          	               	W54       	22A2      	M_C_CPU0_SA_CS_N<2> 
          	               	W56       	21B3      	M_B_CPU0_SA_DQ<31>  
          	               	W58       	21B2      	M_B_CPU0_SA_DQS_DP<8>
          	               	W60       	21B3      	M_B_CPU0_SA_DQ<26>  
          	               	W62       	22B3      	M_C_CPU0_SA_DQ<23>  
          	               	W64       	22B2      	M_C_CPU0_SA_DQS_DP<7>
          	               	W66       	22B3      	M_C_CPU0_SA_DQ<18>  
          	               	W68       	21B3      	M_B_CPU0_SA_DQ<15>  
          	               	W70       	21B2      	M_B_CPU0_SA_DQS_DP<6>
          	               	W72       	21B3      	M_B_CPU0_SA_DQ<10>  
          	               	W74       	22B3      	M_C_CPU0_SA_DQ<7>   
          	               	W76       	22B2      	M_C_CPU0_SA_DQS_DN<5>
          	               	W78       	22B3      	M_C_CPU0_SA_DQ<2>   
          	               	W80       	38B2      	PVCCFA_EHV_FIVRA_CPU0
          	               	W82       	34B2      	UPI_CPU0_CPU1_P2P2_DP<14>
          	               	W84       	42B4      	GND                 
          	               	W86       	31B2      	P5E_CPU0_PE4_TX_DN<4>
          	               	W88       	42B4      	GND                 
          	               	W90       	31B3      	P5E_CPU0_PE4_RX_DP<4>
          	               	Y2        	32B2      	UPI_CPU0_CPU1_P0P1_DN<5>
          	               	Y4        	42B4      	GND                 
          	               	Y6        	32B3      	UPI_CPU1_CPU0_P1P0_DN<5>
          	               	Y8        	42B4      	GND                 
          	               	Y10       	29B3      	P5E_CPU0_PE0_RX_DP<5>
          	               	Y12       	42B4      	GND                 
          	               	Y14       	29B2      	P5E_CPU0_PE0_TX_DP<4>
          	               	Y16       	42B4      	GND                 
          	               	Y18       	42B4      	GND                 
          	               	Y20       	22B3      	M_C_CPU0_SB_DQ<22>  
          	               	Y22       	22B3      	M_C_CPU0_SB_DQ<19>  
          	               	Y24       	42B4      	GND                 
          	               	Y26       	21A3      	M_B_CPU0_SB_DQ<6>   
          	               	Y28       	21A3      	M_B_CPU0_SB_DQ<3>   
          	               	Y30       	42B4      	GND                 
          	               	Y32       	22A3      	M_C_CPU0_SB_CB<2>   
          	               	Y34       	22A3      	M_C_CPU0_SB_CB<7>   
          	               	Y36       	42B4      	GND                 
          	               	Y38       	22A2      	M_C_CPU0_SB_CS_N<2> 
          	               	Y40       	22B2      	M_C_CPU0_SB_CA<5>   
          	               	Y42       	42B4      	GND                 
          	               	Y44       	21B2      	M_B_CPU0_SA_CA<6>   
          	               	Y47       	22A2      	M_C_CPU0_SB_CA<1>   
          	               	Y49       	42B4      	GND                 
          	               	Y51       	22B2      	M_C_CPU0_SA_CA<3>   
          	               	Y53       	22A2      	M_C_CPU0_SA_CS_N<3> 
          	               	Y55       	42B4      	GND                 
          	               	Y57       	21B3      	M_B_CPU0_SA_DQ<30>  
          	               	Y59       	21B3      	M_B_CPU0_SA_DQ<27>  
          	               	Y61       	42B4      	GND                 
          	               	Y63       	22B3      	M_C_CPU0_SA_DQ<22>  
          	               	Y65       	22B3      	M_C_CPU0_SA_DQ<19>  
          	               	Y67       	42B4      	GND                 
          	               	Y69       	21B3      	M_B_CPU0_SA_DQ<14>  
          	               	Y71       	21B3      	M_B_CPU0_SA_DQ<11>  
          	               	Y73       	42B4      	GND                 
          	               	Y75       	22B3      	M_C_CPU0_SA_DQ<6>   
          	               	Y77       	22B3      	M_C_CPU0_SA_DQ<3>   
          	               	Y79       	38B2      	PVCCFA_EHV_FIVRA_CPU0
          	               	Y81       	34B2      	UPI_CPU0_CPU1_P2P2_DN<14>
          	               	Y83       	34B2      	UPI_CPU0_CPU1_P2P2_DP<15>
          	               	Y85       	38B2      	PVCCFA_EHV_FIVRA_CPU0
          	               	Y87       	31B2      	P5E_CPU0_PE4_TX_DP<4>
          	               	Y89       	38B2      	PVCCFA_EHV_FIVRA_CPU0
          	               	Y91       	31B3      	P5E_CPU0_PE4_RX_DN<4>

U2_BL     	TP_TP_BOM ONLY 	          	          	                    
          	               	1         	311A3     	NC                  

U2_BP     	TP_TP_BOM ONLY 	          	          	                    
          	               	1         	311A3     	NC                  

U2_DC     	TP_TP_BOM ONLY 	          	          	                    
          	               	1         	311A3     	NC                  

U4        	EMMITSBURG_REV0P9	          	          	                    
          	               	A4        	187B2     	TP_PCH_RSVD<2>      
          	               	A6        	188A1     	GND                 
          	               	A8        	179B2     	TP_CLK_100M_PCH_13_DN
          	               	A10       	179B2     	TP_CLK_100M_PCH_12_DN
          	               	A12       	179B2     	TP_CLK_100M_PCH_5_DN
          	               	A14       	179B2     	TP_CLK_100M_PCH_7_DN
          	               	A16       	179B2     	TP_CLK_100M_PCH_0_DN
          	               	A18       	179B2     	TP_CLK_100M_PCH_16_DN
          	               	A20       	188B1     	GND                 
          	               	A22       	188B1     	GND                 
          	               	A24       	188B1     	GND                 
          	               	A26       	188B1     	GND                 
          	               	A28       	179B2     	CLK_25M_PCH_CPU1_DP 
          	               	A30       	181B4     	DMI_CPU0_PCH_TX_C_DN<0>
          	               	A32       	181B4     	DMI_CPU0_PCH_TX_C_DN<2>
          	               	A34       	181B4     	DMI_CPU0_PCH_TX_C_DN<4>
          	               	A36       	181B4     	DMI_CPU0_PCH_TX_C_DN<6>
          	               	A38       	188A1     	GND                 
          	               	A40       	188A1     	GND                 
          	               	A41       	185B3     	FM_PCH_PRSNT_N      
          	               	AA1       	183B2     	FM_PCH_GLB_RST_WARN_N
          	               	AA3       	183B2     	FM_BIOS_DEBUG_EN_R_N
          	               	AA5       	188B1     	GND                 
          	               	AA7       	184B2     	FAB_REV_ID2         
          	               	AA10      	184B2     	FM_BOARD_SKU_ID0    
          	               	AA13      	184B2     	FAB_REV_ID1         
          	               	AA17      	188B1     	GND                 
          	               	AA19      	188B1     	GND                 
          	               	AA20      	188B1     	GND                 
          	               	AA22      	188B1     	GND                 
          	               	AA24      	188B1     	GND                 
          	               	AA25      	188B1     	GND                 
          	               	AA27      	188B1     	GND                 
          	               	AA29      	186B4     	P1V05_PCH_PLL_AUX   
          	               	AA32      	188B1     	GND                 
          	               	AA36      	188B1     	GND                 
          	               	AA39      	188B1     	GND                 
          	               	AA41      	181B4     	P3E_PCH_E1S_RX_DN<0>
          	               	AA43      	181B4     	P3E_PCH_E1S_RX_DP<0>
          	               	AB2       	183B2     	IRQ_PCH_SCI_WHEA_N  
          	               	AB4       	183B2     	RST_PLTRST_N        
          	               	AB8       	184B2     	FM_PASSWORD_CLEAR_N 
          	               	AB11      	184B2     	FM_BOARD_SKU_ID4    
          	               	AB15      	188B1     	GND                 
          	               	AB17      	188B1     	GND                 
          	               	AB19      	186B4     	P1V05_PCH_AUX       
          	               	AB20      	186B4     	P1V05_PCH_AUX       
          	               	AB22      	186B4     	P1V05_PCH_AUX       
          	               	AB24      	186B4     	P1V05_PCH_AUX       
          	               	AB25      	188B1     	GND                 
          	               	AB27      	186B4     	P1V05_PCH_PLL_AUX   
          	               	AB31      	186B2     	P1V8_PCH_PLL_AUX    
          	               	AB34      	186B2     	P1V8_PCH_PLL_AUX    
          	               	AB37      	188B1     	GND                 
          	               	AB40      	181B4     	P3E_PCH_M2_RX_DN<3> 
          	               	AB42      	181B4     	P3E_PCH_M2_RX_DP<3> 
          	               	AC1       	183B2     	FM_ADR_COMPLETE     
          	               	AC3       	183B2     	PU_PCH_VRALERT_N    
          	               	AC5       	188B1     	GND                 
          	               	AC7       	184B2     	TP_GPP_L_7          
          	               	AC10      	184B2     	TP_GPP_L_2          
          	               	AC13      	187B2     	PD_RCOMP_1P8_3P3    
          	               	AC29      	188B1     	GND                 
          	               	AC32      	188B1     	GND                 
          	               	AC36      	188B1     	GND                 
          	               	AC39      	188B1     	GND                 
          	               	AC41      	181B4     	P3E_PCH_M2_RX_DN<2> 
          	               	AC43      	181B4     	P3E_PCH_M2_RX_DP<2> 
          	               	AD2       	183B2     	TP_PCH_GPP_D_2      
          	               	AD4       	183B2     	FM_ADR_ACK          
          	               	AD8       	188B1     	GND                 
          	               	AD11      	188B1     	GND                 
          	               	AD15      	186B2     	P3V3_AUX            
          	               	AD17      	186B2     	P3V3_AUX            
          	               	AD19      	188B1     	GND                 
          	               	AD20      	188B1     	GND                 
          	               	AD22      	188B1     	GND                 
          	               	AD24      	188B1     	GND                 
          	               	AD25      	186B4     	P1V05_PCH_AUX       
          	               	AD27      	186B4     	P1V05_PCH_AUX       
          	               	AD31      	188B1     	GND                 
          	               	AD34      	188B1     	GND                 
          	               	AD37      	181B2     	P3E_PCH_BMC_TX_DP   
          	               	AD40      	181B4     	P3E_PCH_M2_RX_DN<1> 
          	               	AD42      	181B4     	P3E_PCH_M2_RX_DP<1> 
          	               	AE1       	183B2     	SMB_HOST_BMC_3V3AUX_SDA
          	               	AE3       	183B2     	FM_PCH_CRASHLOG_TRIG_N
          	               	AE5       	188B1     	GND                 
          	               	AE7       	184B2     	H_CPU0_PMDOWN_PCH   
          	               	AE10      	184B2     	TP_GPP_L_8          
          	               	AE13      	188B1     	GND                 
          	               	AE29      	186B4     	P1V05_PCH_PLL_AUX   
          	               	AE32      	181B2     	USB3_PCH_TX_DN<4>   
          	               	AE36      	181B2     	P3E_PCH_BMC_TX_DN   
          	               	AE39      	188B1     	GND                 
          	               	AE41      	181B4     	P3E_PCH_M2_RX_DN<0> 
          	               	AE43      	181B4     	P3E_PCH_M2_RX_DP<0> 
          	               	AF2       	183B2     	SMB_HOST_BMC_3V3AUX_SCL
          	               	AF4       	183B2     	FM_CPU_RMCA_CATERR_DLY_N
          	               	AF8       	184B2     	H_CPU0_PMSYNC_PCH_R2
          	               	AF11      	184B2     	FM_BIOS_ADV_FUNCTIONS
          	               	AF15      	186B4     	TP_PCH_RSVD<16>     
          	               	AF17      	186B2     	P3V3_AUX            
          	               	AF19      	188B1     	GND                 
          	               	AF20      	186B2     	P1V05_PCH_AUX       
          	               	AF22      	186B2     	P1V05_PCH_AUX       
          	               	AF24      	188B1     	GND                 
          	               	AF25      	186B4     	P1V05_PCH_AUX       
          	               	AF27      	186B4     	P1V05_PCH_AUX       
          	               	AF31      	188A2     	GND                 
          	               	AF34      	181B2     	P3E_PCH_E1S_TX_DN<3>
          	               	AF37      	181B2     	P3E_PCH_E1S_TX_DN<2>
          	               	AF40      	188A2     	GND                 
          	               	AF42      	188A2     	GND                 
          	               	AG1       	183B2     	FM_ESPI_FLASH_MODE  
          	               	AG3       	183B2     	TP_PCH_GPP_D_20     
          	               	AG5       	188A2     	GND                 
          	               	AG7       	184B2     	FM_ME_RCVR_N        
          	               	AG10      	184B2     	FM_MFG_MODE         
          	               	AG13      	188A2     	GND                 
          	               	AG17      	186B2     	P3V3_AUX            
          	               	AG19      	188A2     	GND                 
          	               	AG20      	186B2     	P1V05_PCH_AUX       
          	               	AG22      	186B2     	P1V05_PCH_AUX       
          	               	AG24      	188A2     	GND                 
          	               	AG25      	186B4     	P1V05_PCH_AUX       
          	               	AG27      	186B4     	P1V05_PCH_AUX       
          	               	AG29      	186B4     	P1V05_PCH_PLL_AUX   
          	               	AG32      	181B2     	USB3_PCH_TX_DP<4>   
          	               	AG36      	181B2     	P3E_PCH_E1S_TX_DP<3>
          	               	AG39      	188A2     	GND                 
          	               	AG41      	180B3     	TP_USB2_13_DP       
          	               	AG43      	180B3     	TP_USB2_13_DN       
          	               	AH2       	183B2     	FM_PCHHOT_N         
          	               	AH4       	183B2     	FM_ADR_TRIGGER_R_N  
          	               	AH8       	188A2     	GND                 
          	               	AH11      	182B3     	IRQ_LVC3_WAKE_N     
          	               	AH15      	186B2     	P3V3_RTC_AUX        
          	               	AH31      	188A2     	GND                 
          	               	AH34      	181B2     	P3E_PCH_E1S_TX_DN<1>
          	               	AH37      	181B2     	P3E_PCH_E1S_TX_DP<2>
          	               	AH40      	180B3     	TP_USB2_11_DP       
          	               	AH42      	180B3     	TP_USB2_11_DN       
          	               	AJ1       	183B2     	FM_FLASH_SECURITY_STRAP
          	               	AJ3       	183B2     	PU_LPC_PME_N        
          	               	AJ5       	188B2     	GND                 
          	               	AJ7       	182B3     	TP_PCH_GPP_O_11     
          	               	AJ10      	182B3     	RST_PCH_RSTBTN_R_N  
          	               	AJ13      	182B3     	TP_PCH_SLP_S5_N     
          	               	AJ17      	186B2     	P3V3_AUX            
          	               	AJ19      	188B2     	GND                 
          	               	AJ20      	186B2     	P1V05_PCH_AUX       
          	               	AJ22      	186B2     	P1V05_PCH_AUX       
          	               	AJ24      	188B2     	GND                 
          	               	AJ25      	186B4     	P1V05_PCH_AUX       
          	               	AJ27      	186B4     	P1V05_PCH_AUX       
          	               	AJ29      	188B2     	GND                 
          	               	AJ32      	181B2     	P3E_PCH_E1S_TX_DP<1>
          	               	AJ36      	188B2     	GND                 
          	               	AJ39      	188B2     	GND                 
          	               	AJ41      	180B3     	TP_USB2_9_DP        
          	               	AJ43      	180B3     	TP_USB2_9_DN        
          	               	AK2       	188B2     	GND                 
          	               	AK4       	188B2     	GND                 
          	               	AK8       	182B3     	TP_SLP_LAN_N        
          	               	AK11      	188B2     	GND                 
          	               	AK15      	186B2     	P3V3_AUX            
          	               	AK31      	181B2     	P3E_PCH_M2_TX_DP<0> 
          	               	AK34      	181B2     	P3E_PCH_M2_TX_DN<3> 
          	               	AK37      	188B2     	GND                 
          	               	AK40      	180B3     	USB2_7_DP           
          	               	AK42      	180B3     	USB2_7_DN           
          	               	AL1       	183B2     	PU_SMB_PCH_PLD_3V3AUX_SCL
          	               	AL3       	183B2     	FM_BIOS_POST_CMPLT_N
          	               	AL5       	183B2     	FM_ADR_MODE1        
          	               	AL7       	182B3     	FM_PCH_SLP_SUS_N    
          	               	AL10      	182B3     	PWRGD_SYS_PWROK     
          	               	AL13      	182B3     	FM_PCH_SLP_S4_N     
          	               	AL17      	186B2     	P3V3_AUX            
          	               	AL19      	188B2     	GND                 
          	               	AL20      	186B2     	P1V05_PCH_AUX       
          	               	AL22      	186B2     	P1V05_PCH_AUX       
          	               	AL24      	188B2     	GND                 
          	               	AL25      	186B4     	P1V05_PCH_PLL_AUX   
          	               	AL27      	188B2     	GND                 
          	               	AL29      	188B2     	GND                 
          	               	AL32      	181B2     	P3E_PCH_M2_TX_DN<0> 
          	               	AL36      	181B2     	P3E_PCH_E1S_TX_DN<0>
          	               	AL39      	188B2     	GND                 
          	               	AL41      	180B3     	USB2_5_DP           
          	               	AL43      	180B3     	USB2_5_DN           
          	               	AM8       	188B2     	GND                 
          	               	AM11      	182B3     	TP_PCH_SLP_A_N      
          	               	AM15      	188B2     	GND                 
          	               	AM31      	188B2     	GND                 
          	               	AM34      	181B2     	P3E_PCH_M2_TX_DP<3> 
          	               	AM37      	181B2     	P3E_PCH_E1S_TX_DP<0>
          	               	AN2       	183B2     	PU_PCH_PLD_3V3AUX_ALERT_N
          	               	AN4       	183B2     	PU_SMB_SML3_3V3AUX_PCH_SCL
          	               	AN7       	182B3     	PU_ACPRESENT        
          	               	AN10      	182B3     	FM_PCH_SPARE0       
          	               	AN13      	188B2     	GND                 
          	               	AN16      	188B2     	GND                 
          	               	AN20      	186B2     	P3V3_AUX            
          	               	AN23      	186B2     	P1V05_PCH_AUX       
          	               	AN26      	186B4     	TP_PCH_RSVD<15>     
          	               	AN29      	188B2     	GND                 
          	               	AN32      	188B2     	GND                 
          	               	AN36      	181B2     	P3E_PCH_M2_TX_DN<1> 
          	               	AN40      	180B3     	USB2_3_DP           
          	               	AN42      	180B3     	USB2_3_DN           
          	               	AP1       	183B2     	SMB_SML1_PMBUS_3V3AUX_PCH_SCL_1
          	               	AP3       	183B2     	PD_PCH_GPPC_C10     
          	               	AP5       	188B2     	GND                 
          	               	AP8       	182B3     	FM_PCH_SLP_S3_N     
          	               	AP11      	188B2     	GND                 
          	               	AP15      	185B3     	IRQ_PCH_CPU_NMI_EVENT_R_N
          	               	AP18      	188B2     	GND                 
          	               	AP21      	186B2     	P1V05_PCH_AUX       
          	               	AP24      	188B2     	GND                 
          	               	AP28      	188B2     	GND                 
          	               	AP31      	181B4     	PCH_PCIEUP_RCOMPN   
          	               	AP34      	181B2     	P3E_PCH_M2_TX_DP<1> 
          	               	AP37      	188B2     	GND                 
          	               	AP39      	188B2     	GND                 
          	               	AP41      	180B3     	TP_USB2_1_DP        
          	               	AP43      	180B3     	TP_USB2_1_DN        
          	               	AR2       	183B2     	PD_PCH_GPPC_C9      
          	               	AR4       	183B2     	IRQ_SML1_PMBUS_ALERT_N
          	               	AR7       	182B3     	PD_SUSCLK           
          	               	AR10      	182B3     	FM_BMC_PWRBTN_N     
          	               	AR13      	185B3     	FM_EUP_LOT6_N       
          	               	AR16      	185B3     	FM_XTAL_INPUT_FREQUENCY_1_MGPIO
          	               	AR20      	188B2     	GND                 
          	               	AR23      	186B2     	P1V05_PCH_AUX       
          	               	AR26      	186B4     	P1V05_PCH_AUX       
          	               	AR29      	181B4     	PCH_PCIEUP_RCOMPP   
          	               	AR32      	188B2     	GND                 
          	               	AR36      	181B2     	P3E_PCH_M2_TX_DN<2> 
          	               	AR40      	180B3     	USB2_0_DP           
          	               	AR42      	180B3     	USB2_0_DN           
          	               	AT1       	183B2     	PU_SMB_PCH_PLD_3V3AUX_SDA
          	               	AT3       	183B2     	PD_PCH_GPPC_C5      
          	               	AT5       	188B2     	GND                 
          	               	AT8       	188B2     	GND                 
          	               	AT11      	188B2     	GND                 
          	               	AT15      	188B2     	GND                 
          	               	AT18      	185B3     	FM_PCH_CONSENT_STRAP_N
          	               	AT21      	188B2     	GND                 
          	               	AT24      	188B2     	GND                 
          	               	AT28      	188B2     	GND                 
          	               	AT31      	188B2     	GND                 
          	               	AT34      	188B2     	GND                 
          	               	AT37      	181B2     	P3E_PCH_M2_TX_DP<2> 
          	               	AT39      	188B2     	GND                 
          	               	AT41      	180B3     	TP_USB2_2_DP        
          	               	AT43      	180B3     	TP_USB2_2_DN        
          	               	AU2       	183B2     	IRQ_SML0_ALERT_N    
          	               	AU4       	183B2     	SMB_SML0B_3V3AUX_SDA
          	               	AU7       	182B3     	PU_LAN_WAKE_N       
          	               	AU10      	182B3     	FM_PCH_SKIP_RTC_CLOCK
          	               	AU13      	185B3     	FM_SPI_3V3_1V8_VOLTAGE
          	               	AU16      	185B3     	FM_PCH_SPKR         
          	               	AU20      	188B2     	GND                 
          	               	AU23      	188B2     	GND                 
          	               	AU26      	188B2     	GND                 
          	               	AU29      	188B2     	GND                 
          	               	AU32      	188B2     	GND                 
          	               	AU36      	188B2     	GND                 
          	               	AU40      	180B3     	TP_USB2_4_DP        
          	               	AU42      	180B3     	TP_USB2_4_DN        
          	               	AV1       	183B2     	PU_SMB_SML4_3V3AUX_PCH_SDA
          	               	AV3       	183B2     	FM_PMBUS_ALERT_B_EN 
          	               	AV5       	188B2     	GND                 
          	               	AV8       	188B2     	GND                 
          	               	AV11      	185B3     	FM_ADR_MODE0        
          	               	AV15      	185B3     	SPI_PCH_IO2         
          	               	AV18      	185B3     	IRQ_SMI_ACTIVE_N    
          	               	AV21      	182B2     	NC_PCH_RSVD<4>      
          	               	AV24      	184B4     	TP_EDSFF1A_TYPE_ID  
          	               	AV28      	184B4     	TP_EDSFF1B_TYPE_ID  
          	               	AV31      	184B4     	PD_PCH_GPP_E_10     
          	               	AV34      	184B4     	PD_PCH_GPP_E_11     
          	               	AV37      	188B2     	GND                 
          	               	AV39      	188B2     	GND                 
          	               	AV41      	180B3     	TP_USB2_6_DP        
          	               	AV43      	180B3     	TP_USB2_6_DN        
          	               	AW2       	183B2     	FM_THROTTLE_N       
          	               	AW4       	183B2     	SMB_SML1_PMBUS_3V3AUX_PCH_SDA_1
          	               	AW7       	188B2     	GND                 
          	               	AW10      	185B3     	FM_JTAG_ODT_DISABLE 
          	               	AW13      	185B3     	SPI_PCH_CS0_R_N     
          	               	AW16      	185B3     	SPI_PCH_IO1         
          	               	AW20      	184B4     	FM_ME_AUTHN_FAIL    
          	               	AW23      	184B4     	TP_PCH_GPP_E_2      
          	               	AW26      	182B2     	NC_PCH_RSVD<3>      
          	               	AW29      	184B4     	FM_ME_BT_DONE       
          	               	AW32      	184B4     	FM_M2_SSD0_E7_PEDET 
          	               	AW36      	184B4     	PD_PCH_GPP_E_8      
          	               	AW40      	180B3     	USB2_8_DP           
          	               	AW42      	180B3     	USB2_8_DN           
          	               	AY1       	183B2     	PU_SMB_SML3_3V3AUX_PCH_SDA
          	               	AY3       	188A3     	GND                 
          	               	AY5       	188A3     	GND                 
          	               	AY8       	188A3     	GND                 
          	               	AY11      	188B2     	GND                 
          	               	AY15      	188B2     	GND                 
          	               	AY18      	188B2     	GND                 
          	               	AY21      	188B2     	GND                 
          	               	AY24      	188B2     	GND                 
          	               	AY28      	188A3     	GND                 
          	               	AY31      	188A3     	GND                 
          	               	AY34      	188A3     	GND                 
          	               	AY37      	188A3     	GND                 
          	               	AY39      	188A3     	GND                 
          	               	AY41      	180B3     	TP_USB2_10_DP       
          	               	AY43      	180B3     	TP_USB2_10_DN       
          	               	B5        	179B2     	TP_CLK_100M_PCH_15_DN
          	               	B7        	179B2     	TP_CLK_100M_PCH_14_DN
          	               	B9        	188A3     	GND                 
          	               	B11       	179B2     	CLK_100M_BMC_P3E_DN 
          	               	B13       	188A3     	GND                 
          	               	B15       	179B2     	TP_CLK_100M_PCH_9_DN
          	               	B17       	179B2     	CLK_100M_E1S_0_R_DN 
          	               	B19       	179B2     	TP_CLK_100M_PCH_4_DN
          	               	B21       	179B3     	CLK_100M_CK440_PCH_EXTCLK_DP
          	               	B23       	179B3     	XTAL_PCH_25M_IN     
          	               	B25       	179B3     	CLK_25M_PCH_REF_NS_DP
          	               	B27       	179B2     	CLK_25M_PCH_CPU0_DP 
          	               	B29       	188A3     	GND                 
          	               	B31       	181B4     	DMI_CPU0_PCH_TX_C_DN<1>
          	               	B33       	181B4     	DMI_CPU0_PCH_TX_C_DN<3>
          	               	B35       	181B4     	DMI_CPU0_PCH_TX_C_DN<5>
          	               	B37       	181B4     	DMI_CPU0_PCH_TX_C_DN<7>
          	               	B39       	188A3     	GND                 
          	               	BA2       	183B2     	PU_SMB_SML4_3V3AUX_PCH_SCL
          	               	BA4       	183B2     	SMB_SML0_3V3AUX_PCH_SDA
          	               	BA7       	185B3     	FM_SUSACK_N         
          	               	BA10      	185B3     	TP_SPI_PCH_CS1_R_N  
          	               	BA13      	185B3     	SPI_PCH_IO0         
          	               	BA16      	185B3     	SPI_PCH_IO3         
          	               	BA20      	184B4     	FM_PS_PWROK_DLY_R_SEL
          	               	BA23      	184B4     	TP_PCH_GPP_E_1      
          	               	BA26      	184B4     	TP_PCH_GPP_E_0      
          	               	BA29      	184B4     	PD_PCH_GPP_E_9      
          	               	BA32      	184B4     	PD_PCH_GPP_E_13     
          	               	BA36      	184B4     	FM_DEBUG_PORT_PRSNT_R_N
          	               	BA40      	180B3     	TP_USB2_12_DP       
          	               	BA42      	180B3     	TP_USB2_12_DN       
          	               	BB1       	188A1     	GND                 
          	               	BB3       	183B2     	SMB_SML0B_3V3AUX_SCL
          	               	BB5       	188B3     	GND                 
          	               	BB8       	185B3     	FM_ESPI_CS_SWIZZLE  
          	               	BB11      	185B3     	SPI_PCH_TPM_CS_N    
          	               	BB15      	185B3     	SPI_PCH_CLK         
          	               	BB18      	185B3     	FM_XTAL_INPUT_FREQUENCY_0_MGPIO
          	               	BB21      	184B4     	PD_PCH_GPP_E_3      
          	               	BB24      	184B4     	FM_M2_E1S_E6_PEDET  
          	               	BB28      	184B4     	PD_PCH_GPP_E_12     
          	               	BB31      	184B4     	FM_TPM_PRSNT_N      
          	               	BB34      	184B4     	PD_PCH_GPP_E_14     
          	               	BB37      	182B3     	H_DBP_PRDY_N_PCH    
          	               	BB39      	188A3     	GND                 
          	               	BB41      	180B4     	PD_PCH_USB2_COMP    
          	               	BB43      	187B2     	TP_PCH_RSVD<7>      
          	               	BC2       	188B1     	GND                 
          	               	BC4       	183B2     	SMB_SML0_3V3AUX_PCH_SCL
          	               	BC6       	188B3     	GND                 
          	               	BC8       	188B3     	GND                 
          	               	BC10      	188B3     	GND                 
          	               	BC12      	188B3     	GND                 
          	               	BC14      	188B3     	GND                 
          	               	BC16      	188B3     	GND                 
          	               	BC18      	188B3     	GND                 
          	               	BC20      	188B3     	GND                 
          	               	BC22      	188B3     	GND                 
          	               	BC24      	188B3     	GND                 
          	               	BC26      	188B3     	GND                 
          	               	BC28      	188B3     	GND                 
          	               	BC30      	188B3     	GND                 
          	               	BC32      	188B3     	GND                 
          	               	BC34      	188B3     	GND                 
          	               	BC36      	188B3     	GND                 
          	               	BC38      	188B3     	GND                 
          	               	BC40      	180B4     	NC_PCH_RSVD<14>     
          	               	BC42      	188B1     	GND                 
          	               	BD1       	188A1     	GND                 
          	               	BD3       	188B1     	GND                 
          	               	BD5       	188B3     	GND                 
          	               	BD7       	185B3     	RST_RTCRST_N        
          	               	BD9       	182B2     	RST_RSMRST_PCH_N    
          	               	BD11      	183B4     	FM_PCH_SATA_RAID_KEY
          	               	BD13      	183B4     	CLK_24M_66M_LPC0_ESPI
          	               	BD15      	183B4     	ESPI_ALERT1_N_LPC_RCIN_N
          	               	BD17      	183B4     	PD_PCH_GPPC_A_10    
          	               	BD19      	183B4     	ESPI_LAD0_DATA_IO3  
          	               	BD21      	188B3     	GND                 
          	               	BD23      	183B4     	JTAG_TRC_PCH_PTI1_CLK
          	               	BD25      	183B4     	JTAG_TRC_PCH_PTI<11>
          	               	BD27      	183B4     	JTAG_TRC_PCH_PTI<8> 
          	               	BD29      	183B4     	JTAG_TRC_PCH_PTI<5> 
          	               	BD31      	183B4     	JTAG_TRC_PCH_PTI<2> 
          	               	BD33      	183B4     	JTAG_TRC_PCH_PTI0_CLK
          	               	BD35      	182B3     	JTAG_DBP_CPU_GTL_TCK
          	               	BD37      	182B3     	JTAG_DBP_TMS_PCH    
          	               	BD39      	188B3     	GND                 
          	               	BD41      	188B1     	GND                 
          	               	BD43      	188A1     	GND                 
          	               	BE1       	188B1     	GND                 
          	               	BE3       	188B1     	GND                 
          	               	BE4       	182B2     	PWRGD_PCH_PWROK     
          	               	BE6       	179B3     	XTAL_PCH_RTC1       
          	               	BE8       	182B2     	PWRGD_DSW_PWROK     
          	               	BE10      	188B3     	GND                 
          	               	BE12      	183B4     	PD_PCH_GPPC_A_14    
          	               	BE14      	183B4     	PD_PCH_GPPC_A_15    
          	               	BE16      	183B4     	IRQ_LPC_SERIRQ_ESPI_CS1_N
          	               	BE18      	183B4     	ESPI_LAD0_DATA_IO2  
          	               	BE20      	183B4     	ESPI_LFRAME_N_BMC_CS0_N
          	               	BE22      	183B4     	JTAG_TRC_PCH_PTI<15>
          	               	BE24      	183B4     	JTAG_TRC_PCH_PTI<13>
          	               	BE26      	183B4     	JTAG_TRC_PCH_PTI<9> 
          	               	BE28      	183B4     	JTAG_TRC_PCH_PTI<6> 
          	               	BE30      	183B4     	JTAG_TRC_PCH_PTI<3> 
          	               	BE32      	183B4     	JTAG_TRC_PCH_PTI<0> 
          	               	BE34      	188B3     	GND                 
          	               	BE36      	182B3     	JTAG_DBP_TDO_PCH    
          	               	BE38      	182B3     	JTAG_DBP_TDI_PCH    
          	               	BE40      	182B3     	JTAG_DBP_PMODE      
          	               	BE41      	188B1     	GND                 
          	               	BE43      	188B1     	GND                 
          	               	BF5       	179B3     	RTC_EXT_CAP         
          	               	BF7       	179B3     	XTAL_PCH_RTC2       
          	               	BF9       	185B3     	RST_SRTCRST_N       
          	               	BF11      	183B4     	PD_PCH_GPPC_A_18    
          	               	BF13      	183B4     	IRQ_BMC_PCH_NMI     
          	               	BF15      	183B4     	FM_BMC_READY_R_N    
          	               	BF17      	183B4     	RST_ESPI_RESET_N    
          	               	BF19      	183B4     	ESPI_LAD0_DATA_IO1  
          	               	BF21      	188B3     	GND                 
          	               	BF23      	183B4     	JTAG_TRC_PCH_PTI<14>
          	               	BF25      	183B4     	JTAG_TRC_PCH_PTI<12>
          	               	BF27      	183B4     	JTAG_TRC_PCH_PTI<10>
          	               	BF29      	183B4     	JTAG_TRC_PCH_PTI<7> 
          	               	BF31      	183B4     	JTAG_TRC_PCH_PTI<4> 
          	               	BF33      	183B4     	JTAG_TRC_PCH_PTI<1> 
          	               	BF35      	182B3     	JTAG_DBP_TCK_PCH    
          	               	BF37      	182B3     	H_DBP_PREQ_N_PCH    
          	               	BF39      	182B2     	NC_PCH_RSVD<5>      
          	               	BG3       	185B3     	TP_PCH_CGC_DUT_DETECTED
          	               	BG4       	188A1     	GND                 
          	               	BG6       	188A1     	GND                 
          	               	BG8       	182B2     	FM_INTRUDER_HDR_PCH_N
          	               	BG10      	188B3     	GND                 
          	               	BG12      	183B4     	ESPI_LAD0_DATA_IO0  
          	               	BG14      	183B4     	PD_PCH_GPPC_A_19    
          	               	BG16      	183B4     	M2_SSD0_CLKREQ_EN_N 
          	               	BG18      	183B4     	E1S_0_CLKREQ_N      
          	               	BG20      	183B4     	IRQ_LPC_PIRQA_N_ESPI_ALERT0_N
          	               	BG22      	183B4     	PU_OC6_USB_N        
          	               	BG24      	183B4     	PU_OC5_USB_N        
          	               	BG26      	183B4     	PU_OC4_USB_N        
          	               	BG28      	183B4     	PU_OC3_USB_N        
          	               	BG30      	183B4     	PU_OC2_USB_N        
          	               	BG32      	183B4     	USB_OC1_REAR_R_N    
          	               	BG34      	188B3     	GND                 
          	               	BG36      	182B2     	NC_PCH_RSVD<17>     
          	               	BG38      	188A1     	GND                 
          	               	BG40      	186B4     	GND                 
          	               	BG41      	188B1     	GND                 
          	               	C3        	188B1     	GND                 
          	               	C4        	188B3     	GND                 
          	               	C6        	179B2     	TP_CLK_100M_PCH_15_DP
          	               	C8        	179B2     	TP_CLK_100M_PCH_13_DP
          	               	C10       	179B2     	TP_CLK_100M_PCH_12_DP
          	               	C12       	179B2     	TP_CLK_100M_PCH_5_DP
          	               	C14       	179B2     	TP_CLK_100M_PCH_7_DP
          	               	C16       	179B2     	TP_CLK_100M_PCH_0_DP
          	               	C18       	179B2     	TP_CLK_100M_PCH_16_DP
          	               	C20       	188B3     	GND                 
          	               	C22       	188B3     	GND                 
          	               	C24       	188B3     	GND                 
          	               	C26       	188B3     	GND                 
          	               	C28       	179B2     	CLK_25M_PCH_CPU1_DN 
          	               	C30       	181B4     	DMI_CPU0_PCH_TX_C_DP<0>
          	               	C32       	181B4     	DMI_CPU0_PCH_TX_C_DP<2>
          	               	C34       	181B4     	DMI_CPU0_PCH_TX_C_DP<4>
          	               	C36       	181B4     	DMI_CPU0_PCH_TX_C_DP<6>
          	               	C38       	188B3     	GND                 
          	               	C40       	181B4     	NC_PCH_RSVD<8>      
          	               	C41       	188B1     	GND                 
          	               	C43       	188B1     	GND                 
          	               	D1        	188B1     	GND                 
          	               	D3        	188B1     	GND                 
          	               	D5        	188B3     	GND                 
          	               	D7        	179B2     	TP_CLK_100M_PCH_14_DP
          	               	D9        	188B3     	GND                 
          	               	D11       	179B2     	CLK_100M_BMC_P3E_DP 
          	               	D13       	188B3     	GND                 
          	               	D15       	179B2     	TP_CLK_100M_PCH_9_DP
          	               	D17       	179B2     	CLK_100M_E1S_0_R_DP 
          	               	D19       	179B2     	TP_CLK_100M_PCH_4_DP
          	               	D21       	179B3     	CLK_100M_CK440_PCH_EXTCLK_DN
          	               	D23       	179B3     	XTAL_PCH_25M_OUT    
          	               	D25       	179B3     	CLK_25M_PCH_REF_NS_DN
          	               	D27       	179B2     	CLK_25M_PCH_CPU0_DN 
          	               	D29       	188B3     	GND                 
          	               	D31       	181B4     	DMI_CPU0_PCH_TX_C_DP<1>
          	               	D33       	181B4     	DMI_CPU0_PCH_TX_C_DP<3>
          	               	D35       	181B4     	DMI_CPU0_PCH_TX_C_DP<5>
          	               	D37       	181B4     	DMI_CPU0_PCH_TX_C_DP<7>
          	               	D39       	181B4     	NC_PCH_RSVD<9>      
          	               	D41       	188B1     	GND                 
          	               	D43       	188B1     	GND                 
          	               	E2        	188B1     	GND                 
          	               	E4        	182B2     	TP_PCH_CPU_MEMTRIP_N
          	               	E6        	188B3     	GND                 
          	               	E8        	188B3     	GND                 
          	               	E10       	188B3     	GND                 
          	               	E12       	188B3     	GND                 
          	               	E14       	188B3     	GND                 
          	               	E16       	188B3     	GND                 
          	               	E18       	188B3     	GND                 
          	               	E20       	188B3     	GND                 
          	               	E22       	188B3     	GND                 
          	               	E24       	188B3     	GND                 
          	               	E26       	188B3     	GND                 
          	               	E28       	188B3     	GND                 
          	               	E30       	188B3     	GND                 
          	               	E32       	188B3     	GND                 
          	               	E34       	188B3     	GND                 
          	               	E36       	188B3     	GND                 
          	               	E38       	188B3     	GND                 
          	               	E40       	188B3     	GND                 
          	               	E42       	188B1     	GND                 
          	               	F1        	187B2     	TP_PCH_RSVD<1>      
          	               	F3        	182B2     	H_THERMTRIP_LVC1_N  
          	               	F5        	182B2     	FM_PCH_CPU_PWR_DEBUG_N
          	               	F8        	182B2     	FM_PCIE_EV_BIF_EN   
          	               	F11       	182B2     	TP_PCH_CPU_MSMI_N   
          	               	F15       	188B3     	GND                 
          	               	F18       	179B2     	TP_CLK_100M_PCH_8_DN
          	               	F21       	179B2     	TP_CLK_100M_PCH_1_DP
          	               	F24       	188B3     	GND                 
          	               	F28       	181B2     	DMI_CPU0_PCH_RX_DP<1>
          	               	F31       	188B3     	GND                 
          	               	F34       	188A4     	GND                 
          	               	F37       	181B2     	DMI_CPU0_PCH_RX_DN<7>
          	               	F39       	188A4     	GND                 
          	               	F41       	188A4     	GND                 
          	               	F43       	188A1     	GND                 
          	               	G2        	184B4     	FM_PCH_RING_OSC_BYPASS_MGPIO_TE
          	               	G4        	184B4     	FM_PCH_VISA_DEFAULT 
          	               	G7        	182B2     	H_CPU_ERR1_PCH_R_N  
          	               	G10       	182B2     	PWRGD_CPUPWRGD_GTL  
          	               	G13       	188A4     	GND                 
          	               	G16       	179B2     	TP_CLK_100M_PCH_11_DN
          	               	G20       	188A4     	GND                 
          	               	G23       	179B2     	TP_CLK_100M_PCH_1_DN
          	               	G26       	188A4     	GND                 
          	               	G29       	181B2     	DMI_CPU0_PCH_RX_DN<1>
          	               	G32       	181B2     	DMI_CPU0_PCH_RX_DP<4>
          	               	G36       	181B2     	DMI_CPU0_PCH_RX_DN<5>
          	               	G40       	181B4     	TP_P3E_PCH_15_RX_DN 
          	               	G42       	181B4     	TP_P3E_PCH_15_RX_DP 
          	               	H1        	187B2     	TP_PCH_RSVD<0>      
          	               	H3        	184B4     	FM_PCH_XTAL_INPUT_MODE_MGPIO_TE
          	               	H5        	188A4     	GND                 
          	               	H8        	188A4     	GND                 
          	               	H11       	182B2     	FM_PCH_TRIGGER0_R_N 
          	               	H15       	179B2     	TP_CLK_100M_PCH_11_DP
          	               	H18       	179B2     	TP_CLK_100M_PCH_8_DP
          	               	H21       	179B2     	CLK_100M_PE_M2_0_R_DN
          	               	H24       	179B3     	TP_PCH_RSVD<18>     
          	               	H28       	181B2     	DMI_CPU0_PCH_RX_DP<0>
          	               	H31       	181B2     	DMI_CPU0_PCH_RX_DP<2>
          	               	H34       	181B2     	DMI_CPU0_PCH_RX_DP<5>
          	               	H37       	181B2     	DMI_CPU0_PCH_RX_DP<7>
          	               	H39       	188A4     	GND                 
          	               	H41       	181B4     	TP_P3E_PCH_14_RX_DN 
          	               	H43       	181B4     	TP_P3E_PCH_14_RX_DP 
          	               	J2        	184B4     	TP_PCH_MGPIO_TEST1  
          	               	J4        	184B4     	PU_PCH_PMCALERT_N   
          	               	J7        	182B2     	H_CPU_ERR0_PCH_R_N  
          	               	J10       	182B2     	PECI_PCH            
          	               	J13       	188A4     	GND                 
          	               	J16       	179B2     	TP_CLK_100M_PCH_10_DN
          	               	J20       	188A4     	GND                 
          	               	J23       	179B3     	TP_PCH_RSVD<19>     
          	               	J26       	188A4     	GND                 
          	               	J29       	181B2     	DMI_CPU0_PCH_RX_DN<2>
          	               	J32       	181B2     	DMI_CPU0_PCH_RX_DN<4>
          	               	J36       	181B2     	DMI_CPU0_PCH_RX_DP<6>
          	               	J40       	181B4     	TP_P3E_PCH_13_RX_DN 
          	               	J42       	181B4     	TP_P3E_PCH_13_RX_DP 
          	               	K1        	184B4     	FM_PCH_IO_EXPANDER  
          	               	K3        	184B4     	FM_PCH_MCRO_LDO     
          	               	K5        	188B4     	GND                 
          	               	K8        	182B2     	FM_PCH_TRIGGER1_R_N 
          	               	K11       	188A4     	GND                 
          	               	K15       	188B4     	GND                 
          	               	K18       	179B2     	TP_CLK_100M_PCH_10_DP
          	               	K21       	179B2     	CLK_100M_PE_M2_0_R_DP
          	               	K24       	188B4     	GND                 
          	               	K28       	181B2     	DMI_CPU0_PCH_RX_DN<0>
          	               	K31       	181B2     	DMI_CPU0_PCH_RX_DP<3>
          	               	K34       	188B4     	GND                 
          	               	K37       	181B2     	DMI_CPU0_PCH_RX_DN<6>
          	               	K39       	188B4     	GND                 
          	               	K41       	181B4     	TP_P3E_PCH_12_RX_DN 
          	               	K43       	181B4     	TP_P3E_PCH_12_RX_DP 
          	               	L2        	184B4     	FM_PCH_EXTERNALCLKMODE
          	               	L4        	184B4     	FM_LT_KEY_DOWNGRADE_N
          	               	L7        	182B2     	H_CPU_ERR2_PCH_R_N  
          	               	L10       	188B4     	GND                 
          	               	L13       	187B3     	TP_PCH_RSVD<13>     
          	               	L16       	188B4     	GND                 
          	               	L20       	188B4     	GND                 
          	               	L23       	188B4     	GND                 
          	               	L26       	188B4     	GND                 
          	               	L29       	188B4     	GND                 
          	               	L32       	181B2     	DMI_CPU0_PCH_RX_DN<3>
          	               	L36       	188B4     	GND                 
          	               	L40       	181B4     	P3E_PCH_NVS_RX_DN<1>
          	               	L42       	181B4     	P3E_PCH_NVS_RX_DP<1>
          	               	M1        	188B4     	GND                 
          	               	M3        	188B4     	GND                 
          	               	M5        	188B4     	GND                 
          	               	M8        	182B2     	TP_PLTRST_N         
          	               	M11       	188B4     	GND                 
          	               	M15       	188B4     	GND                 
          	               	M18       	188B4     	GND                 
          	               	M21       	188B4     	GND                 
          	               	M24       	186B4     	P1V05_PCH_AUX       
          	               	M28       	188B4     	GND                 
          	               	M31       	188B4     	GND                 
          	               	M34       	188B4     	GND                 
          	               	M37       	188B4     	GND                 
          	               	M39       	188B4     	GND                 
          	               	M41       	181B4     	P3E_PCH_NVS_RX_DN<0>
          	               	M43       	181B4     	P3E_PCH_NVS_RX_DP<0>
          	               	N2        	184B2     	PD_GPP_I_13         
          	               	N4        	184B2     	IRQ_TPM_SPI_N       
          	               	N7        	184B2     	FAB_REV_ID0         
          	               	N10       	184B2     	PD_GPP_M_16         
          	               	N13       	187B3     	TP_PCH_RSVD<12>     
          	               	N16       	188B4     	GND                 
          	               	N20       	186B2     	P1V8_PCH_AUX        
          	               	N23       	186B4     	P1V05_PCH_AUX       
          	               	N26       	186B4     	P1V05_PCH_AUX       
          	               	N29       	179B3     	PD_PCH_XCLK_BIASREF 
          	               	N32       	188B4     	GND                 
          	               	N36       	181B2     	TP_P3E_PCH_15_TX_DP 
          	               	N40       	181B2     	NC_PCH_RSVD<10>     
          	               	N42       	181B2     	NC_PCH_RSVD<11>     
          	               	P1        	184B2     	PD_GPP_I_14         
          	               	P3        	184B2     	FM_PCH_DFXTESTMODE  
          	               	P5        	188B4     	GND                 
          	               	P8        	188B4     	GND                 
          	               	P11       	188B4     	GND                 
          	               	P15       	186B4     	P1V05_PCH_AUX       
          	               	P18       	187B2     	TP_PCH_RSVD<6>      
          	               	P21       	186B2     	P3V3_AUX            
          	               	P24       	188B4     	GND                 
          	               	P28       	188B4     	GND                 
          	               	P31       	188B4     	GND                 
          	               	P34       	181B2     	TP_P3E_PCH_15_TX_DN 
          	               	P37       	188B4     	GND                 
          	               	P39       	188B4     	GND                 
          	               	P41       	188B4     	GND                 
          	               	P43       	188B4     	GND                 
          	               	R2        	184B2     	PD_GPP_I_15         
          	               	R4        	184B2     	FM_PCH_XTALSEL      
          	               	R7        	184B2     	FM_PCH_BIOS_RCVR_MODE
          	               	R10       	184B2     	FM_BOARD_SKU_ID3    
          	               	R13       	188B4     	GND                 
          	               	R16       	188B4     	GND                 
          	               	R20       	188B4     	GND                 
          	               	R23       	186B4     	P1V05_PCH_PLL_AUX   
          	               	R26       	186B4     	P1V05_PCH_PLL_AUX   
          	               	R29       	186B4     	P1V05_PCH_PLL_AUX   
          	               	R32       	181B2     	TP_P3E_PCH_14_TX_DN 
          	               	R36       	188B4     	GND                 
          	               	R40       	181B4     	USB3_PCH_RX_BUF_DN<4>
          	               	R42       	181B4     	USB3_PCH_RX_BUF_DP<4>
          	               	T8        	184B2     	PD_GPP_M_15         
          	               	T11       	185B4     	TP_PCH_GPP_N_1      
          	               	T15       	186B2     	P3V3_AUX            
          	               	T31       	188B4     	GND                 
          	               	T34       	181B2     	TP_P3E_PCH_14_TX_DP 
          	               	T37       	181B2     	P3E_PCH_NVS_TX_DN<1>
          	               	U1        	184B2     	PD_GPP_I_16         
          	               	U3        	184B2     	FM_PCH_BMC_RST_R_N  
          	               	U5        	188B4     	GND                 
          	               	U7        	184B2     	TP_GPP_M_12         
          	               	U10       	188B4     	GND                 
          	               	U13       	188B4     	GND                 
          	               	U17       	186B2     	P1V8_PCH_AUX        
          	               	U19       	186B2     	P1V8_PCH_AUX        
          	               	U20       	186B2     	P1V8_PCH_AUX        
          	               	U22       	186B2     	P1V8_PCH_AUX        
          	               	U24       	186B2     	P1V8_PCH_AUX        
          	               	U25       	188B4     	GND                 
          	               	U27       	186B4     	P1V05_PCH_PLL_AUX   
          	               	U29       	186B2     	P1V8_PCH_PLL_AUX    
          	               	U32       	181B2     	TP_P3E_PCH_13_TX_DN 
          	               	U36       	181B2     	TP_P3E_PCH_12_TX_DP 
          	               	U39       	188B4     	GND                 
          	               	U41       	181B4     	P3E_PCH_BMC_RX_DN   
          	               	U43       	181B4     	P3E_PCH_BMC_RX_DP   
          	               	V2        	188B4     	GND                 
          	               	V4        	184B2     	PD_GPP_I_17         
          	               	V8        	184B2     	FM_BOARD_SKU_ID2    
          	               	V11       	185B4     	TP_PCH_GPP_N_4      
          	               	V15       	186B2     	P3V3_AUX            
          	               	V31       	188B4     	GND                 
          	               	V34       	181B2     	TP_P3E_PCH_12_TX_DN 
          	               	V37       	181B2     	P3E_PCH_NVS_TX_DP<1>
          	               	V40       	181B4     	P3E_PCH_E1S_RX_DN<3>
          	               	V42       	181B4     	P3E_PCH_E1S_RX_DP<3>
          	               	W1        	183B2     	FM_PCH_BOOT_BIOS_STRAP
          	               	W3        	188B4     	GND                 
          	               	W5        	188B4     	GND                 
          	               	W7        	184B2     	FM_BOARD_SKU_ID1    
          	               	W10       	184B2     	PD_GPP_M_8          
          	               	W13       	184B2     	PD_GPP_M_17         
          	               	W17       	186B4     	P1V05_PCH_AUX       
          	               	W19       	186B4     	P1V05_PCH_AUX       
          	               	W20       	186B4     	P1V05_PCH_AUX       
          	               	W22       	186B4     	P1V05_PCH_AUX       
          	               	W24       	186B4     	P1V05_PCH_AUX       
          	               	W25       	188B4     	GND                 
          	               	W27       	186B2     	P1V8_PCH_PLL_AUX    
          	               	W29       	186B2     	P1V8_PCH_PLL_AUX    
          	               	W32       	181B2     	TP_P3E_PCH_13_TX_DP 
          	               	W36       	181B2     	P3E_PCH_NVS_TX_DN<0>
          	               	W39       	188B4     	GND                 
          	               	W41       	181B4     	P3E_PCH_E1S_RX_DN<2>
          	               	W43       	181B4     	P3E_PCH_E1S_RX_DP<2>
          	               	Y2        	183B2     	FM_PLT_BMC_THERMTRIP_R_N
          	               	Y4        	183B2     	FM_BIOS_IMAGE_SWAP_N
          	               	Y8        	188B4     	GND                 
          	               	Y11       	188B4     	GND                 
          	               	Y15       	188B4     	GND                 
          	               	Y31       	188B4     	GND                 
          	               	Y34       	188B4     	GND                 
          	               	Y37       	181B2     	P3E_PCH_NVS_TX_DP<0>
          	               	Y40       	181B4     	P3E_PCH_E1S_RX_DN<1>
          	               	Y42       	181B4     	P3E_PCH_E1S_RX_DP<1>

U13       	9SQ440NQQI8    	          	          	                    
          	               	A1        	208A3     	FM_CK440Q_DEV_25M_EN
          	               	A2        	208B2     	CLK_25M_CK440_CPU1_DN
          	               	A3        	208B2     	CLK_25M_CK440_CPU1_DP
          	               	A4        	208B2     	CLK_25M_CK440_CPU0_DN
          	               	A5        	208B2     	CLK_25M_CK440_CPU0_DP
          	               	A6        	208A2     	TP_CLK_CK440_PFT_OUT_DP
          	               	A7        	208A2     	TP_CLK_CK440_PFT_OUT_DN
          	               	A8        	208A3     	TP_CLK_PFT_IN_DP    
          	               	A9        	208A3     	TP_CLK_PFT_IN_DN    
          	               	A10       	208A3     	SMB_HOST_CLK_3V3AUX_SCL
          	               	A11       	208A3     	CLK_CK440_SMB_ADDR0 
          	               	A12       	208B3     	P3V3_AUX_CLK_GEN_VDDXTAL_CK440
          	               	A13       	208A3     	XTAL_CLK_GEN1_25M_X1
          	               	A14       	208A2     	GND                 
          	               	A15       	208B2     	NC_CK440_A15        
          	               	A16       	208A3     	FM_CLK_CK440_SS_EN  
          	               	A17       	208A3     	FM_PLD_CLKS_DEV_EN  
          	               	A18       	208B2     	NC_CLK_CK440_100M6_DN
          	               	A19       	208B2     	NC_CLK_CK440_100M6_DP
          	               	A20       	208B2     	NC_CLK_CK440_100M5_DN
          	               	A21       	208B2     	NC_CLK_CK440_100M5_DP
          	               	A22       	208B2     	NC_CLK_CK440_100M4_DN
          	               	A23       	208B2     	NC_CLK_CK440_100M4_DP
          	               	A24       	208B2     	NC_CLK_CK440_100M3_DN
          	               	A25       	208B2     	NC_CLK_CK440_100M3_DP
          	               	A26       	208A3     	CK440Q_OE_3         
          	               	A27       	208B2     	NC_CLK_CK440_100M2_DN
          	               	A28       	208B2     	NC_CLK_CK440_100M2_DP
          	               	A29       	208A3     	CK440Q_OE_2         
          	               	A30       	208A3     	CK440Q_OE_1         
          	               	A31       	208B2     	NC_CLK_CK440_100M1_DN
          	               	A32       	208B2     	NC_CLK_CK440_100M1_DP
          	               	A33       	208B2     	CLK_100M_DB2000_DN  
          	               	A34       	208B2     	CLK_100M_DB2000_DP  
          	               	A35       	208A2     	NC_CLK_CK440_MXCK8_DN
          	               	A36       	208A2     	NC_CLK_CK440_MXCK8_DP
          	               	A37       	208A2     	NC_CLK_CK440_MXCK7_DN
          	               	A38       	208A2     	NC_CLK_CK440_MXCK7_DP
          	               	A39       	208A2     	NC_CLK_CK440_MXCK6_DN
          	               	A40       	208A2     	NC_CLK_CK440_MXCK6_DP
          	               	A41       	208A2     	NC_CLK_CK440_MXCK5_DN
          	               	A42       	208A2     	NC_CLK_CK440_MXCK5_DP
          	               	A43       	208A2     	NC_CLK_CK440_MXCK4_DN
          	               	A44       	208A2     	NC_CLK_CK440_MXCK4_DP
          	               	A45       	208A2     	NC_CLK_CK440_MXCK3_DN
          	               	A46       	208A2     	NC_CLK_CK440_MXCK3_DP
          	               	A47       	208A2     	CLK_100M_CK440_PCH_EXTCLK_R_DN
          	               	A48       	208A2     	CLK_100M_CK440_PCH_EXTCLK_R_DP
          	               	A49       	208A2     	NC_CLK_CK440_MXCK1_DN
          	               	A50       	208A2     	NC_CLK_CK440_MXCK1_DP
          	               	A51       	208A2     	NC_CLK_CK440_MXCK0_DN
          	               	A52       	208B2     	NC_CLK_CK440_MXCK0_DP
          	               	A53       	208B3     	TP_CK440_SBI_DATA_OUT
          	               	A54       	208B3     	PD_CK440_SBI_CLK    
          	               	A55       	208B2     	CLK_25M_CK440_ISCLK_REF_DN
          	               	A56       	208B2     	CLK_25M_CK440_ISCLK_REF_DP
          	               	B1        	208B3     	P3V3_AUX_CLK_GEN_VDDA25M_CK440
          	               	B2        	208B2     	NC_CK440_B2         
          	               	B3        	208B2     	NC_CK440_B3         
          	               	B4        	208A3     	PU_CLK_PFT_LOST_N   
          	               	B5        	208B2     	NC_CK440_B5         
          	               	B6        	208B3     	P3V3_AUX_CLK_GEN_VDDPT_CK440
          	               	B7        	208B2     	NC_CK440_B7         
          	               	B8        	208A3     	SMB_HOST_CLK_3V3AUX_SDA
          	               	B9        	208A3     	CLK_CK440_SMB_ADDR1 
          	               	B10       	208A2     	GND                 
          	               	B11       	208A3     	XTAL_CLK_GEN1_25M_X2
          	               	B12       	208A2     	GND                 
          	               	B13       	208B2     	NC_CK440_B13        
          	               	B14       	208A3     	CK440Q_OE_6         
          	               	B15       	208A3     	CK440Q_OE_5         
          	               	B16       	208B2     	NC_CK440_B16        
          	               	B17       	208B3     	P3V3_AUX_CLK_GEN_VDDA100M_CK440
          	               	B18       	208B2     	NC_CK440_B18        
          	               	B19       	208A3     	CK440Q_OE_4         
          	               	B20       	208B2     	NC_CK440_B20        
          	               	B21       	208B3     	P3V3_AUX_CLK_GEN_VDD_CK440
          	               	B22       	208B2     	NC_CK440_B22        
          	               	B23       	208B3     	P3V3_AUX_CLK_GEN_VDD_CK440
          	               	B24       	208B2     	NC_CK440_B24        
          	               	B25       	208B2     	NC_CK440_B25        
          	               	B26       	208B2     	NC_CK440_B26        
          	               	B27       	208A3     	FM_CLK_GEN1_OE0_N   
          	               	B28       	208B2     	NC_CK440_B28        
          	               	B29       	208B3     	P3V3_AUX_CLK_GEN_VDDMXCK_CK440
          	               	B30       	208B2     	NC_CK440_B30        
          	               	B31       	208B2     	NC_CK440_B31        
          	               	B32       	208B3     	P3V3_AUX_CLK_GEN_VDDMXCK_CK440
          	               	B33       	208B2     	NC_CK440_B33        
          	               	B34       	208B2     	NC_CK440_B34        
          	               	B35       	208B3     	P3V3_AUX_CLK_GEN_VDDMXCK_CK440
          	               	B36       	208B2     	NC_CK440_B36        
          	               	B37       	208B2     	NC_CK440_B37        
          	               	B38       	208B3     	FM_CK440_MXCK_25M_100M
          	               	B39       	208B2     	NC_CK440_B39        
          	               	B40       	208B3     	P3V3_AUX_CLK_GEN_VDDMXCK_CK440
          	               	B41       	208B2     	NC_CK440_B41        
          	               	B42       	208B3     	PU_CK440_SHFT_LD_N  
          	               	B43       	208B3     	PD_CK440_SBI_DATA_IN
          	               	B44       	208B2     	NC_CK440_B44        
          	               	C1        	208A2     	GND                 

U14       	QS3VH257QG8_SMLF	          	          	                    
          	               	1         	230B3     	FM_SPD_REMOTE_EN    
          	               	2         	230B3     	I3C_SPD_DDRABCD_CPU1_R_SCL
          	               	3         	230B3     	I3C_SPD_DDRABCD_CPU1_BMC_SCL
          	               	4         	230B3     	I3C_SPD_DDRABCD_CPU1_LVC1_R_SCL
          	               	5         	230B3     	I3C_SPD_DDRABCD_CPU1_R_SDA
          	               	6         	230B3     	I3C_SPD_DDRABCD_CPU1_BMC_SDA
          	               	7         	230B3     	I3C_SPD_DDRABCD_CPU1_LVC1_R_SDA
          	               	8         	230B3     	GND                 
          	               	9         	230B3     	I3C_SPD_DDREFGH_CPU1_LVC1_R_SCL
          	               	10        	230B3     	I3C_SPD_DDREFGH_CPU1_BMC_SCL
          	               	11        	230B3     	I3C_SPD_DDREFGH_CPU1_R_SCL
          	               	12        	230B3     	I3C_SPD_DDREFGH_CPU1_LVC1_R_SDA
          	               	13        	230B3     	I3C_SPD_DDREFGH_CPU1_BMC_SDA
          	               	14        	230B3     	I3C_SPD_DDREFGH_CPU1_R_SDA
          	               	15        	230B3     	PD_I3C_SPD_DDR_CPU1_OE_N
          	               	16        	230B3     	P3V3_AUX            

U15       	QS3VH257QG8_SMLF	          	          	                    
          	               	1         	229A3     	FM_SPD_REMOTE_EN    
          	               	2         	229B3     	I3C_SPD_DDRABCD_CPU0_R_SCL
          	               	3         	229B3     	I3C_SPD_DDRABCD_CPU0_BMC_SCL
          	               	4         	229B3     	I3C_SPD_DDRABCD_CPU0_LVC1_R_SCL
          	               	5         	229B3     	I3C_SPD_DDRABCD_CPU0_R_SDA
          	               	6         	229B3     	I3C_SPD_DDRABCD_CPU0_BMC_SDA
          	               	7         	229B3     	I3C_SPD_DDRABCD_CPU0_LVC1_R_SDA
          	               	8         	229A3     	GND                 
          	               	9         	229A3     	I3C_SPD_DDREFGH_CPU0_LVC1_R_SCL
          	               	10        	229B3     	I3C_SPD_DDREFGH_CPU0_BMC_SCL
          	               	11        	229A3     	I3C_SPD_DDREFGH_CPU0_R_SCL
          	               	12        	229A3     	I3C_SPD_DDREFGH_CPU0_LVC1_R_SDA
          	               	13        	229A3     	I3C_SPD_DDREFGH_CPU0_BMC_SDA
          	               	14        	229A3     	I3C_SPD_DDREFGH_CPU0_R_SDA
          	               	15        	229A3     	PD_I3C_SPD_DDR_CPU0_OE_N
          	               	16        	229B3     	P3V3_AUX            

U16       	74LVC1G66GV    	          	          	                    
          	               	1         	133A2     	JTAG_CPU0_MUX_GTL_TDO
          	               	2         	133A2     	JTAG_MUX_CPU1_GTL_TDI
          	               	3         	133A2     	GND                 
          	               	4         	133A2     	FM_CPU_EN_R         
          	               	5         	133A2     	P3V3_AUX            

U17       	74CBTLV3126PW  	          	          	                    
          	               	1         	132B3     	PWRGD_PVNN_MAIN_CPU0
          	               	2         	132B3     	JTAG_DBP_TMS        
          	               	3         	132B3     	JTAG_DBP_CPU_QS_GTL_TMS
          	               	4         	132B3     	PWRGD_PVNN_MAIN_CPU0
          	               	5         	132B3     	JTAG_DBP_TDI        
          	               	6         	132B3     	JTAG_QS_MUX_GTL_TDI 
          	               	7         	132B3     	GND                 
          	               	8         	132B3     	TP_74CB_B8          
          	               	9         	132B3     	PD_74CB_A9          
          	               	10        	132B3     	PWRGD_PVNN_MAIN_CPU0
          	               	11        	132B3     	JTAG_MUX_QS_GTL_TDO 
          	               	12        	132B3     	JTAG_DBP_TDO        
          	               	13        	132B3     	PWRGD_PVNN_MAIN_CPU0
          	               	14        	132B3     	P3V3_AUX            

U18       	74CBTLV3126PW  	          	          	                    
          	               	1         	132B3     	PWRGD_PVNN_MAIN_CPU0
          	               	2         	132B3     	JTAG_DBP_CPU_HOOK9_MBP3_GTL_N
          	               	3         	132B3     	DBP_CPU_HOOK9_MBP3_GTL_QS_N
          	               	4         	132B3     	PWRGD_PVNN_MAIN_CPU0
          	               	5         	132B3     	JTAG_DBP_CPU_HOOK8_MBP2_GTL_N
          	               	6         	132B3     	DBP_CPU_HOOK8_MBP2_GTL_QS_N
          	               	7         	132B3     	GND                 
          	               	8         	132B3     	H_CPU_PRDY_QS_GTL_N 
          	               	9         	132B3     	JTAG_DBP_PRDY_N     
          	               	10        	132B3     	PWRGD_PVNN_MAIN_CPU0
          	               	11        	132B3     	H_CPU_PREQ_QS_GTL_N 
          	               	12        	132B3     	JTAG_DBP_PREQ_N     
          	               	13        	132B3     	PWRGD_PVNN_MAIN_CPU0
          	               	14        	132B3     	P3V3_AUX            

U21       	NC7SB3157_SMLF 	          	          	                    
          	               	1         	133B4     	JTAG_MUX_CPU1_GTL_TDI
          	               	2         	133B4     	GND                 
          	               	3         	133B4     	JTAG_MUX_CPU0_GTL_TDI
          	               	4         	133B4     	JTAG_QS_MUX_GTL_TDI 
          	               	5         	133B4     	P3V3_AUX            
          	               	6         	133B4     	FM_CPU0_SKTOCC_N    

U22       	NC7SB3157_SMLF 	          	          	                    
          	               	1         	133B4     	JTAG_CPU0_MUX_GTL_TDO
          	               	2         	133B4     	GND                 
          	               	3         	133B4     	JTAG_CPU1_MUX_GTL_TDO
          	               	4         	133B4     	JTAG_MUX_QS_GTL_TDO 
          	               	5         	133B4     	P3V3_AUX            
          	               	6         	133B4     	FM_CPU1_SKTOCC_N    

U23       	74LVC1G02GW_SMLF	          	          	                    
          	               	1         	133A3     	FM_CPU1_SKTOCC_N    
          	               	2         	133A3     	FM_CPU0_SKTOCC_N    
          	               	3         	133A3     	GND                 
          	               	4         	133A3     	FM_CPU_EN           
          	               	5         	133A3     	P3V3_AUX            

U28       	PCA9617ADP     	          	          	                    
          	               	1         	235B3     	PVNN_TERM_CPU0      
          	               	2         	235B3     	SMB_PEHPCPU0_GTL_R_SCL
          	               	3         	235B3     	SMB_PEHPCPU0_GTL_R_SDA
          	               	4         	235B3     	GND                 
          	               	5         	235B3     	TP_SMB_PEHPCPU0_EN  
          	               	6         	235B3     	SMB_PEHPCPU0_LVC3_SDA_R0
          	               	7         	235B3     	SMB_PEHPCPU0_LVC3_SCL_R0
          	               	8         	235B3     	P3V3_AUX            

U29       	PCA9617ADP     	          	          	                    
          	               	1         	235B3     	PVNN_TERM_CPU1      
          	               	2         	235B3     	SMB_PEHPCPU1_GTL_R_SCL
          	               	3         	235B3     	SMB_PEHPCPU1_GTL_R_SDA
          	               	4         	235B3     	GND                 
          	               	5         	235B3     	TP_SMB_PEHPCPU1_EN  
          	               	6         	235B3     	SMB_PEHPCPU1_LVC3_SDA_R0
          	               	7         	235B3     	SMB_PEHPCPU1_LVC3_SCL_R0
          	               	8         	235B3     	P3V3_AUX            

U30       	PCA9517AD      	          	          	                    
          	               	1         	236B4     	PVNN_TERM_CPU0      
          	               	2         	236B4     	SMB_S3M_CPU0_R_SCL  
          	               	3         	236B4     	SMB_S3M_CPU0_R_SDA  
          	               	4         	236A4     	GND                 
          	               	5         	236A3     	TP_SMB_S3M_CPU0_EN  
          	               	6         	236B3     	SMB_S3M_CPU0_3V3AUX_SDA
          	               	7         	236B3     	SMB_S3M_CPU0_3V3AUX_SCL
          	               	8         	236B3     	P3V3_AUX            

U31       	PCA9517AD      	          	          	                    
          	               	1         	236A4     	PVNN_TERM_CPU1      
          	               	2         	236A4     	SMB_S3M_CPU1_R_SCL  
          	               	3         	236A4     	SMB_S3M_CPU1_R_SDA  
          	               	4         	236A4     	GND                 
          	               	5         	236A3     	TP_SMB_S3M_CPU1_EN  
          	               	6         	236A3     	SMB_S3M_CPU1_3V3AUX_SDA
          	               	7         	236A3     	SMB_S3M_CPU1_3V3AUX_SCL
          	               	8         	236A3     	P3V3_AUX            

U36       	TCA9548APWR    	          	          	                    
          	               	1         	231B3     	PCA9548_PCIE3_ADDR0 
          	               	2         	231B3     	PCA9548_PCIE3_ADDR1 
          	               	3         	231B3     	PU_RST_SMB_PCIE0_N  
          	               	4         	231B3     	NC                  
          	               	5         	231B3     	NC                  
          	               	6         	231B3     	SMB_IOEXP_3V3AUX_SDA_R
          	               	7         	231B3     	SMB_IOEXP_3V3AUX_SCL_R
          	               	8         	231B3     	SMB_PCIE0_3V3AUX_SDA_R3
          	               	9         	231B3     	SMB_PCIE0_3V3AUX_SCL_R3
          	               	10        	231B3     	SMB_PCIE0_3V3AUX_SDA_R5
          	               	11        	231B3     	SMB_PCIE0_3V3AUX_SCL_R5
          	               	12        	231B2     	GND                 
          	               	13        	231B2     	SMB_BMC_SWB_SDA_R4  
          	               	14        	231B2     	SMB_BMC_SWB_SCL_R4  
          	               	15        	231B2     	SMB_FRU_3V3AUX_SDA_R
          	               	16        	231B2     	SMB_FRU_3V3AUX_SCL_R
          	               	17        	231B2     	SMB_INA230_3V3AUX_SDA_R
          	               	18        	231B2     	SMB_INA230_3V3AUX_SCL_R
          	               	19        	231B2     	NC                  
          	               	20        	231B2     	NC                  
          	               	21        	231B3     	PCA9548_PCIE3_ADDR2 
          	               	22        	231B2     	SMB_PCIE0_3V3AUX_SCL_R
          	               	23        	231B2     	SMB_PCIE0_3V3AUX_SDA_R
          	               	24        	231B3     	P3V3_AUX            

U38       	9QXL2001BNHGI8 	          	          	                    
          	               	A1        	206A2     	CLK_100M_OCP_V3_2_D_R_DP
          	               	A2        	206A2     	CLK_100M_OCP_V3_2_C_R_DN
          	               	A3        	206A2     	CLK_100M_OCP_V3_2_C_R_DP
          	               	A4        	206A2     	CLK_100M_OCP_V3_2_B_R_DN
          	               	A5        	206A2     	CLK_100M_OCP_V3_2_B_R_DP
          	               	A6        	206B2     	CLK_100M_OCP_V3_2_A_R_DN
          	               	A7        	206B2     	CLK_100M_OCP_V3_2_A_R_DP
          	               	A8        	206B2     	TP_CLK_100M_DIF13_DN
          	               	A9        	206B2     	TP_CLK_100M_DIF13_DP
          	               	A10       	206B2     	CLK_100M_OCP_SFF_3_R_DN
          	               	A11       	206B2     	CLK_100M_OCP_SFF_3_R_DP
          	               	A12       	206B2     	CLK_100M_OCP_SFF_2_R_DN
          	               	B1        	206A2     	CLK_100M_OCP_V3_2_D_R_DN
          	               	B2        	206B2     	P3V3_DB2000_VDD     
          	               	B3        	206A2     	NC_CLK_100M_DB2000_NC1
          	               	B4        	206B2     	PD_DB2000_SMB_SA0   
          	               	B5        	206A2     	NC_CLK_100M_DB2000_NC2
          	               	B6        	206B2     	P3V3_DB2000_VDDA    
          	               	B7        	206A2     	NC_CLK_100M_DB2000_NC3
          	               	B8        	206B2     	PD_DB2000_SMB_SA1   
          	               	B9        	206A2     	NC_CLK_100M_DB2000_NC4
          	               	B10       	206B2     	FM_DB2000_12_OE_N   
          	               	B11       	206B2     	P3V3_DB2000_VDD     
          	               	B12       	206B2     	CLK_100M_OCP_SFF_2_R_DP
          	               	C1        	206A2     	TP_CLK_100M_DIF18_DP
          	               	C2        	206A2     	NC_CLK_100M_DB2000_NC5
          	               	C11       	206B2     	FM_DB2000_11_OE_N   
          	               	C12       	206B2     	CLK_100M_OCP_SFF_1_R_DN
          	               	D1        	206A2     	TP_CLK_100M_DIF18_DN
          	               	D2        	206A2     	NC_CLK_100M_DB2000_NC6
          	               	D11       	206A2     	NC_CLK_100M_DB2000_NC7
          	               	D12       	206B2     	CLK_100M_OCP_SFF_1_R_DP
          	               	E1        	206A2     	TP_CLK_100M_DIF19_DP
          	               	E2        	206B2     	FM_DB2000_VSBEN     
          	               	E11       	206B2     	FM_DB2000_10_OE_N   
          	               	E12       	206B2     	FM_DB2000_9_OE_N    
          	               	F1        	206A2     	TP_CLK_100M_DIF19_DN
          	               	F2        	206A2     	NC_CLK_100M_DB2000_NC8
          	               	F11       	206A2     	NC_CLK_100M_DB2000_NC9
          	               	F12       	206B2     	CLK_100M_OCP_SFF_0_R_DN
          	               	G1        	206B2     	CLK_100M_DB2000_DP  
          	               	G2        	206A2     	NC_CLK_100M_DB2000_NC10
          	               	G11       	206A2     	NC_CLK_100M_DB2000_NC11
          	               	G12       	206B2     	CLK_100M_OCP_SFF_0_R_DP
          	               	H1        	206B2     	CLK_100M_DB2000_DN  
          	               	H2        	206B2     	P3V3_DB2000_VDDR    
          	               	H11       	206B2     	FM_DB2000_8_OE_N    
          	               	H12       	206B2     	CLK_100M_GPU_SWB_REF_DN
          	               	J1        	206B2     	CLK_100M_DB2000_CPU0_BCLK0_DP
          	               	J2        	206A2     	NC_CLK_100M_DB2000_NC12
          	               	J11       	206A2     	NC_CLK_100M_DB2000_NC13
          	               	J12       	206B2     	CLK_100M_GPU_SWB_REF_DP
          	               	K1        	206B2     	CLK_100M_DB2000_CPU0_BCLK0_DN
          	               	K2        	206A2     	NC_CLK_100M_DB2000_NC14
          	               	K11       	206B2     	FM_DB2000_1_OE_N    
          	               	K12       	206B2     	CLK_100M_DB2000_CPU1_BCLK3_DN
          	               	L1        	206B2     	CLK_100M_DB2000_CPU0_BCLK1_DP
          	               	L2        	206B2     	P3V3_DB2000_VDD     
          	               	L3        	206A2     	NC_CLK_100M_DB2000_NC17
          	               	L4        	206B2     	SMB_HOST_DB2000_3V3AUX_SDA
          	               	L5        	206B2     	SMB_HOST_DB2000_3V3AUX_SCL
          	               	L6        	206A2     	NC_CLK_100M_DB2000_NC15
          	               	L7        	206A2     	NC_CLK_100M_DB2000_NC16
          	               	L8        	206B2     	FM_DB2000_1_OE_N    
          	               	L9        	206A2     	NC_CLK_100M_DB2000_NC18
          	               	L10       	206B2     	FM_DB2000_1_OE_N    
          	               	L11       	206B2     	P3V3_DB2000_VDD     
          	               	L12       	206B2     	CLK_100M_DB2000_CPU1_BCLK3_DP
          	               	M1        	206B2     	CLK_100M_DB2000_CPU0_BCLK1_DN
          	               	M2        	206B2     	CLK_100M_DB2000_CPU0_BCLK2_DP
          	               	M3        	206B2     	CLK_100M_DB2000_CPU0_BCLK2_DN
          	               	M4        	206B2     	CLK_100M_DB2000_CPU0_BCLK3_DP
          	               	M5        	206B2     	CLK_100M_DB2000_CPU0_BCLK3_DN
          	               	M6        	206B2     	FM_DB2000_DEV_EN    
          	               	M7        	206B2     	CLK_100M_DB2000_CPU1_BCLK0_DP
          	               	M8        	206B2     	CLK_100M_DB2000_CPU1_BCLK0_DN
          	               	M9        	206B2     	CLK_100M_DB2000_CPU1_BCLK1_DP
          	               	M10       	206B2     	CLK_100M_DB2000_CPU1_BCLK1_DN
          	               	M11       	206B2     	CLK_100M_DB2000_CPU1_BCLK2_DP
          	               	M12       	206B2     	CLK_100M_DB2000_CPU1_BCLK2_DN
          	               	TH        	206A2     	GND                 

U39       	TCA9548APWR    	          	          	                    
          	               	1         	233B3     	PCA9548_PCIE0_ADDR0 
          	               	2         	233B3     	PCA9548_PCIE0_ADDR1 
          	               	3         	233B3     	PU_RST_SMB_PCIE2_N  
          	               	4         	233B3     	SMB_VR_3V3AUX_SDA_R6
          	               	5         	233B3     	SMB_VR_3V3AUX_SCL_R6
          	               	6         	233B3     	SMB_LM75_0_3V3AUX_SDA_R
          	               	7         	233B3     	SMB_LM75_0_3V3AUX_SCL_R
          	               	8         	233B3     	SMB_LM75_1_3V3AUX_SDA_R
          	               	9         	233B3     	SMB_LM75_1_3V3AUX_SCL_R
          	               	10        	233B3     	SMB_LM75_2_3V3AUX_SDA_R
          	               	11        	233B3     	SMB_LM75_2_3V3AUX_SCL_R
          	               	12        	233B2     	GND                 
          	               	13        	233B2     	SMB_LM75_3_3V3AUX_SDA_R
          	               	14        	233B2     	SMB_LM75_3_3V3AUX_SCL_R
          	               	15        	233B2     	NC                  
          	               	16        	233B2     	NC                  
          	               	17        	233B2     	NC                  
          	               	18        	233B2     	NC                  
          	               	19        	233B2     	NC                  
          	               	20        	233B2     	NC                  
          	               	21        	233B3     	PCA9548_PCIE0_ADDR2 
          	               	22        	233B2     	SMB_VR_SENSOR_3V3AUX_SCL_R
          	               	23        	233B2     	SMB_VR_SENSOR_3V3AUX_SDA_R
          	               	24        	233B3     	P3V3_AUX            

U49       	MOSFET_N_SMLF  	          	          	                    
          	               	D         	158A4     	HP_LVC3_OCP_V3_1_PRSNT2
          	               	G         	158A4     	HP_LVC3_OCP_V3_1_PRSNT2_N
          	               	S         	158A4     	GND                 

U50       	74LVC1G08W57   	          	          	                    
          	               	1         	164A4     	HP_OCP_V3_2_EN      
          	               	2         	164A4     	HP_LVC3_OCP_V3_2_PRSNT2
          	               	3         	164A4     	GND                 
          	               	4         	164A4     	HP_LVC3_OCP_V3_2_EN 
          	               	5         	164A4     	P3V3_AUX            

U51       	PCA9555APW     	          	          	                    
          	               	1         	164B3     	FM_SMB_CPU1_ALERT   
          	               	2         	164B3     	PD_SMB_OCP2_HP_ADD1 
          	               	3         	164B3     	PD_SMB_OCP2_HP_ADD2 
          	               	4         	164B3     	TP_PCA9555_U51_P00  
          	               	5         	164B3     	TP_PCA9555_U51_P01  
          	               	6         	164B3     	HP_OCP_V3_2_EN      
          	               	7         	164B3     	HP_LVC3_OCP_V3_2_ATTN_OUT_SW_N
          	               	8         	164B3     	HP_LVC3_OCP_V3_2_PRSNT2_N
          	               	9         	164B3     	TP_PCA9555_U51_P05  
          	               	10        	164B3     	TP_PCA9555_U51_P06  
          	               	11        	164B3     	TP_PCA9555_U51_P07  
          	               	12        	164B3     	GND                 
          	               	13        	164B3     	TP_PCA9555_U51_P10  
          	               	14        	164B3     	TP_PCA9555_U51_P11  
          	               	15        	164B3     	TP_PCA9555_U51_P12  
          	               	16        	164B3     	TP_PCA9555_U51_P13  
          	               	17        	164B3     	TP_PCA9555_U51_P14  
          	               	18        	164B3     	TP_PCA9555_U51_P15  
          	               	19        	164B3     	TP_PCA9555_U51_P16  
          	               	20        	164B3     	TP_PCA9555_U51_P17  
          	               	21        	164B3     	PD_SMB_OCP2_HP_ADD0 
          	               	22        	164B3     	SMB_PEHPCPU1_LVC3_R3_SCL
          	               	23        	164B3     	SMB_PEHPCPU1_LVC3_R3_SDA
          	               	24        	164B3     	P3V3_AUX            

U52       	APX80929SAG7   	          	          	                    
          	               	1         	158B4     	GND                 
          	               	2         	158B4     	HP_OCP_V3_1_RST     
          	               	3         	158B4     	P3V3_OCP_SFF        

U53       	74LVC1G08W57   	          	          	                    
          	               	1         	164B1     	HP_LVC3_OCP_V3_2_PWRGD_R
          	               	2         	164B1     	RST_OCP_V3_2_N      
          	               	3         	164B1     	GND                 
          	               	4         	164B1     	RST_HP_OCP_V3_2_N   
          	               	5         	164B1     	P3V3_AUX            

U58       	74LVC2G07DW7   	          	          	                    
          	               	1         	162A4     	OCP_V3_2_PRSNT0_R_N 
          	               	2         	162A4     	GND                 
          	               	3         	162A4     	OCP_V3_2_PRSNT1_R_N 
          	               	4         	162A3     	HP_LVC3_OCP_V3_2_PRSNT2_N_R
          	               	5         	162A3     	P3V3_AUX            
          	               	6         	162A3     	HP_LVC3_OCP_V3_2_PRSNT2_N_R

U59       	74LVC2G07DW7   	          	          	                    
          	               	1         	162A4     	OCP_V3_2_PRSNT2_R_N 
          	               	2         	162A4     	GND                 
          	               	3         	162A4     	OCP_V3_2_PRSNT3_R_N 
          	               	4         	162A3     	HP_LVC3_OCP_V3_2_PRSNT2_N_R
          	               	5         	162A3     	P3V3_AUX            
          	               	6         	162A3     	HP_LVC3_OCP_V3_2_PRSNT2_N_R

U60       	NC7SB3157_SMLF 	          	          	                    
          	               	1         	202B3     	IRQ_LPC_PIRQA_N_ESPI_ALERT0_R_N
          	               	2         	202B3     	GND                 
          	               	3         	202B3     	IRQ_LPC_SERIRQ_ESPI_CS1_R_N
          	               	4         	202B3     	IRQ_ESPI_LPC_SERIRQ_ALERT_N
          	               	5         	202B3     	PGPPA_AUX           
          	               	6         	202B3     	FM_ESPI_PLD_EN      

U61       	NC7SB3157_SMLF 	          	          	                    
          	               	1         	202B3     	RST_ESPI_RESET_N_R  
          	               	2         	202B3     	GND                 
          	               	3         	202B3     	RST_PLTRST_B_MUX_N  
          	               	4         	202B3     	ESPI_BMC_LPC_RST_N  
          	               	5         	202B3     	PGPPA_AUX           
          	               	6         	202B3     	FM_ESPI_PLD_EN      

U62       	BAS70057F      	          	          	                    
          	               	1         	185B2     	P3V_BAT_R           
          	               	2         	185B2     	P3V3_AUX            
          	               	3         	185B2     	P3V3_RTC_AUX        

U64       	M24128BWMN6TP  	          	          	                    
          	               	1         	243B3     	MB_FRU_ADDR0        
          	               	2         	243B3     	MB_FRU_ADDR1        
          	               	3         	243B3     	MB_FRU_ADDR2        
          	               	4         	243B3     	GND                 
          	               	5         	243B3     	SMB_FRU_3V3AUX_SDA  
          	               	6         	243B3     	SMB_FRU_3V3AUX_SCL  
          	               	7         	243B3     	PD_MB_FRU_WP        
          	               	8         	243B3     	P3V3_AUX            

U66       	74LVC1G126SE7  	          	          	                    
          	               	1         	154B4     	OCP_SFF_AUX_PWR_EN_R1
          	               	2         	154B4     	FM_OCP_SFF_PWR_GOOD 
          	               	3         	154B3     	GND                 
          	               	4         	154B3     	FB_BMC_ISOLATE_R1   
          	               	5         	154B3     	P3V3_AUX            

U67       	74CBTLV3126PW  	          	          	                    
          	               	1         	154B2     	FB_BMC_ISOLATE      
          	               	2         	154B2     	NCSI_BMC_RXD1_R     
          	               	3         	154B3     	NCSI_OCP_SFF_RXD1   
          	               	4         	154B2     	FB_BMC_ISOLATE      
          	               	5         	154B2     	NCSI_BMC_RXD0_R     
          	               	6         	154B3     	NCSI_OCP_SFF_RXD0   
          	               	7         	154B3     	GND                 
          	               	8         	154B3     	NCSI_OCP_SFF_CRS_DV 
          	               	9         	154B2     	NCSI_BMC_CRS_DV_R   
          	               	10        	154B2     	FB_BMC_ISOLATE      
          	               	11        	154B3     	OCP_SFF_ISO1_RBT_ARB_IN
          	               	12        	154B2     	OCP_SFF_RBT_ARB_IN_R
          	               	13        	154B2     	FB_BMC_ISOLATE      
          	               	14        	154B3     	P3V3_AUX            

U68       	74CBTLV3126PW  	          	          	                    
          	               	1         	154B2     	FB_BMC_ISOLATE      
          	               	2         	154B2     	NCSI_BMC_TXD1_R     
          	               	3         	154B3     	NCSI_OCP_SFF_TXD1   
          	               	4         	154B2     	FB_BMC_ISOLATE      
          	               	5         	154B2     	NCSI_BMC_TXD0_R     
          	               	6         	154B3     	NCSI_OCP_SFF_TXD0   
          	               	7         	154B3     	GND                 
          	               	8         	154B3     	NCSI_OCP_SFF_TX_EN  
          	               	9         	154B2     	NCSI_BMC_TX_EN_R    
          	               	10        	154B2     	FB_BMC_ISOLATE      
          	               	11        	154B3     	OCP_SFF_ISO2_RBT_ARB_OUT
          	               	12        	154B2     	OCP_SFF_RBT_ARB_OUT 
          	               	13        	154B2     	FB_BMC_ISOLATE      
          	               	14        	154B3     	P3V3_AUX            

U70       	MOSFET_N_SMLF  	          	          	                    
          	               	D         	223B4     	FM_PLD_CLKS_OE_R_N  
          	               	G         	223B4     	FM_PLD_CLKS_DEV_EN  
          	               	S         	223B4     	GND                 

U75       	74LVC1G17GW    	          	          	                    
          	               	1         	155B3     	NC                  
          	               	2         	155B4     	RST_HP_OCP_V3_1_N   
          	               	3         	155B4     	GND                 
          	               	4         	155B3     	RST_OCP_V3_1_BUF_N  
          	               	5         	155B4     	P3V3_AUX            

U82       	74LVC1G126SE7  	          	          	                    
          	               	1         	155B4     	PU_OCP_SFF_WAKE_OE  
          	               	2         	155B4     	IRQ_LVC3_OCP_SFF_WAKE_N
          	               	3         	155A4     	GND                 
          	               	4         	155B4     	OCP_SFF_WAKE_BUFF_N 
          	               	5         	155B4     	P3V3_AUX            

U83       	GTL2014PW      	          	          	                    
          	               	1         	239B3     	PD_GTL2014_BMC_JTAG_DIR_2
          	               	2         	239B3     	PD_JTAG_DBP_B0      
          	               	3         	239B3     	JTAG_DBP_PRDY_R_N   
          	               	4         	239B3     	P0V7_JTAG_VREF_2    
          	               	5         	239B3     	PD_JTAG_DBP_B2      
          	               	6         	239B3     	JTAG_DBP_FB_TDO     
          	               	7         	239B3     	GND                 
          	               	8         	239B3     	GND                 
          	               	9         	239B3     	JTAG_BMC_DBP_TDO_R  
          	               	10        	239B3     	TP_JTAG_BMC_A2      
          	               	11        	239B3     	GND                 
          	               	12        	239B3     	JTAG_DBP_BMC_PRDY_R1_N
          	               	13        	239B3     	TP_JTAG_BMC_A0      
          	               	14        	239B3     	P3V3_AUX            

U84       	GTL2014PW      	          	          	                    
          	               	1         	239B3     	PU_GTL2014_BMC_JTAG_DIR_1
          	               	2         	239B3     	JTAG_DBP_PREQ_R_N   
          	               	3         	239B3     	FM_CPU_FBRK_DEBUG_N 
          	               	4         	239B3     	PD_GTL2014_BMC_JTAG_VREF_1
          	               	5         	239B3     	JTAG_DBP_FB_TDI     
          	               	6         	239B3     	JTAG_DBP_FB_TMS     
          	               	7         	239B3     	GND                 
          	               	8         	239B3     	GND                 
          	               	9         	239B3     	JTAG_BMC_DBP_TMS_R  
          	               	10        	239B3     	JTAG_BMC_DBP_TDI_R  
          	               	11        	239B3     	GND                 
          	               	12        	239B3     	FM_BMC_CPU_FBRK_OUT_N
          	               	13        	239B3     	JTAG_DBP_BMC_PREQ_R1_N
          	               	14        	239B3     	P3V3_AUX            

U85       	NC7SB3157_SMLF 	          	          	                    
          	               	1         	134B4     	JTAG_BMC_PCH_TCK    
          	               	2         	134B4     	GND                 
          	               	3         	134B4     	JTAG_BMC_CPU_TCK    
          	               	4         	134B4     	JTAG_BMC_DBP_TCK    
          	               	5         	134B4     	P3V3_AUX            
          	               	6         	134B4     	FM_JTAG_TCK_MUX_SEL 

U86       	74CBTLV3126PW  	          	          	                    
          	               	1         	134B3     	PD_JTAG_BMC_NTRST_N 
          	               	2         	134B3     	FM_BMC_EN_DET       
          	               	3         	134B3     	TP_JTAG_BMC_1B      
          	               	4         	134B3     	JTAG_BMC_CPU_TCK    
          	               	5         	134B3     	FM_BMC_EN_DET       
          	               	6         	134B3     	JTAG_DBP_CPU_GTL_TCK_R1
          	               	7         	134B3     	GND                 
          	               	8         	134B3     	JTAG_DBP_TCK_PCH_R  
          	               	9         	134B3     	FM_BMC_EN_DET       
          	               	10        	134B3     	JTAG_BMC_PCH_TCK    
          	               	11        	134B3     	TP_JTAG_BMC_4B      
          	               	12        	134B3     	FM_BMC_EN_DET       
          	               	13        	134B3     	PD_JTAG_BMC_NTRST_N 
          	               	14        	134B3     	P3V3_AUX            

U87       	MOSFET_N_SMLF  	          	          	                    
          	               	D         	134B3     	P1V05_PCH_AUX       
          	               	G         	134B3     	FM_REMOTE_DEBUG_DET_R
          	               	S         	134B3     	FM_BMC_EN_DET       

U89       	MOSFET_N_SMLF  	          	          	                    
          	               	D         	218B3     	FM_PLD_HEARTBEAT_LVC3_D
          	               	G         	218B3     	FM_PLD_HEARTBEAT_LVC3
          	               	S         	218B3     	GND                 

U90       	PI6CV304LE     	          	          	                    
          	               	1         	155A3     	CLK_50M_RMII_R      
          	               	2         	155A3     	CLK_50M_EN          
          	               	3         	155A3     	CLK_50M_BMC_MAC_R   
          	               	4         	155A3     	GND                 
          	               	5         	155A3     	CLK_50M_NCSI_OCP_1  
          	               	6         	155A3     	P3V3_AUX            
          	               	7         	155A3     	CLK_50M_NCSI_OCP_2  
          	               	8         	155A3     	TP_CLK_50M_PCH_LOM  

U94       	ADM1086AKSZREEL7	          	          	                    
          	               	1         	244B3     	FM_COMP_P3V3_AUX_ENIN
          	               	2         	244B3     	GND                 
          	               	3         	244B3     	FM_COMP_P3V3_AUX_VIN
          	               	4         	244B3     	PWRGD_DSW_PWROK_R1  
          	               	5         	244B3     	FM_COMP_P3V3_STBY_CEXT
          	               	6         	244B3     	P3V3_AUX            

U95       	74LVC1G07SE7   	          	          	                    
          	               	1         	244A3     	NC                  
          	               	2         	244A3     	PWRGD_DSW_PWROK_R1  
          	               	3         	244A3     	GND                 
          	               	4         	244A3     	PWRGD_DSW_PWROK_R2  
          	               	5         	244A3     	P3V3_AUX            

U96       	NX3L2267GM     	          	          	                    
          	               	1         	239A3     	JTAG_BMC_PLD_TDI    
          	               	2         	239A3     	JTAG_BMC_DBP_TDI    
          	               	3         	239A3     	JTAG_BMC_PLD_TDO    
          	               	4         	239A3     	JTAG_BMC_DBP_TDO    
          	               	5         	239A4     	GND                 
          	               	6         	239A4     	JTAG_BMC_SW_TDO     
          	               	7         	239A4     	FM_JTAG_BMC_MUX_SEL 
          	               	8         	239A4     	FM_JTAG_BMC_MUX_SEL 
          	               	9         	239A4     	JTAG_BMC_SW_TDI     
          	               	10        	239A3     	P3V3_AUX            

U97       	NX3L2267GM     	          	          	                    
          	               	1         	239A1     	JTAG_BMC_PLD_TMS    
          	               	2         	239A1     	JTAG_BMC_DBP_TMS    
          	               	3         	239A1     	JTAG_BMC_PLD_TCK    
          	               	4         	239A1     	JTAG_BMC_DBP_TCK    
          	               	5         	239A2     	GND                 
          	               	6         	239A2     	JTAG_BMC_SW_TCK     
          	               	7         	239A2     	FM_JTAG_BMC_MUX_SEL 
          	               	8         	239A2     	FM_JTAG_BMC_MUX_SEL 
          	               	9         	239A2     	JTAG_BMC_SW_TMS     
          	               	10        	239A1     	P3V3_AUX            

U98       	PCA9306DP1     	          	          	                    
          	               	1         	194B3     	GND                 
          	               	2         	194B3     	P1V8_PCH_AUX        
          	               	3         	194B3     	SMB_M2_P0_1V8AUX_SCL_R
          	               	4         	194B3     	SMB_M2_P0_1V8AUX_SDA_R
          	               	5         	194B3     	SMB_SENSOR_M2_P0_3V3AUX_SDA
          	               	6         	194B3     	SMB_SENSOR_M2_P0_3V3AUX_SCL
          	               	7         	194B3     	SMB_PCIE_M2_0_EN    
          	               	8         	194B3     	SMB_PCIE_M2_0_EN    

U99       	RT9818C44GV    	          	          	                    
          	               	1         	260A3     	PWRGD_P5V           
          	               	2         	260A3     	GND                 
          	               	3         	260A3     	P5V                 

U102      	INA183A1IDBVR  	          	          	                    
          	               	1         	251A2     	GND                 
          	               	2         	251A2     	GND                 
          	               	3         	251A2     	PVCCD_HV_CPU0_NVDIMM_ISENSE
          	               	4         	251A2     	P12V_AUX_CPU0_DIMM_ISEN_N
          	               	5         	251A2     	P12V_AUX_CPU0_DIMM_ISEN_P

U103      	INA183A1IDBVR  	          	          	                    
          	               	1         	251A2     	GND                 
          	               	2         	251A2     	GND                 
          	               	3         	251A2     	PVCCD_HV_CPU1_NVDIMM_ISENSE
          	               	4         	251A2     	P12V_AUX_CPU1_DIMM_ISEN_N
          	               	5         	251A2     	P12V_AUX_CPU1_DIMM_ISEN_P

U104      	74LVC1G07GV    	          	          	                    
          	               	1         	155B4     	NC_U104_NC1         
          	               	2         	155B4     	FM_SYS_THROTTLE_R_N 
          	               	3         	155B4     	GND                 
          	               	4         	155B3     	OCP_SFF_PWRBRK_BUFF_N
          	               	5         	155B3     	P3V3_AUX            

U117      	TPS3895ADRYR   	          	          	                    
          	               	1         	244B3     	FM_COMP_P3V3_AUX_ENIN
          	               	2         	244B3     	GND                 
          	               	3         	244B3     	FM_COMP_P3V3_AUX_VIN
          	               	4         	244B3     	PWRGD_DSW_PWROK_R1  
          	               	5         	244B3     	FM_COMP_P3V3_STBY_CEXT
          	               	6         	244B3     	P3V3_AUX            

U134      	74LVC2G07DW7   	          	          	                    
          	               	1         	191A3     	RST_SMB_E1S_N       
          	               	2         	191A3     	GND                 
          	               	3         	191A3     	RST_SMB_E1S_N       
          	               	4         	191A3     	SMB_PCIE_E1S_ISO_EN_R2
          	               	5         	191A3     	P3V3_AUX            
          	               	6         	191A3     	RST_SMB_BUF_E1S_0_N 

U142      	NC7SB3157_SMLF 	          	          	                    
          	               	1         	197B3     	PECI_BMC_B1         
          	               	2         	197B3     	GND                 
          	               	3         	197B3     	PECI_PCH_B1         
          	               	4         	197B2     	PECI_CPU_GTL        
          	               	5         	197B2     	P3V3_AUX            
          	               	6         	197B2     	PECI_MUX_SEL_R      

U143      	PCA9545APW     	          	          	                    
          	               	1         	236B3     	PCA9543_S3M_ADDR0   
          	               	2         	236B3     	PCA9543_S3M_ADDR1   
          	               	3         	236B3     	RST_SMB_S3M_N       
          	               	4         	236B3     	PCA9543_S3M_INT0_N  
          	               	5         	236B3     	SMB_S3M_CPU0_3V3AUX_SDA_R
          	               	6         	236B3     	SMB_S3M_CPU0_3V3AUX_SCL_R
          	               	7         	236B3     	PCA9543_S3M_INT1_N  
          	               	8         	236B3     	SMB_S3M_CPU1_3V3AUX_SDA_R
          	               	9         	236B3     	SMB_S3M_CPU1_3V3AUX_SCL_R
          	               	10        	236B3     	GND                 
          	               	11        	236B3     	PCA9543_S3M_INT2_N  
          	               	12        	236B3     	SMB_S3M_CPU0_PIROM_3V3AUX_SDA_R
          	               	13        	236B3     	SMB_S3M_CPU0_PIROM_3V3AUX_SCL_R
          	               	14        	236B3     	PCA9543_S3M_INT3_N  
          	               	15        	236B3     	SMB_S3M_CPU1_PIROM_3V3AUX_SDA_R
          	               	16        	236B3     	SMB_S3M_CPU1_PIROM_3V3AUX_SCL_R
          	               	17        	236B3     	PCA9545_S3M_INT_N   
          	               	18        	236B3     	SMB_S3M_CPU_3V3AUX_SCL
          	               	19        	236B3     	SMB_S3M_CPU_3V3AUX_SDA
          	               	20        	236B3     	P3V3_AUX            

U145      	74LVC1G126SE7  	          	          	                    
          	               	1         	191A1     	FM_PS_EN_PLD_BUF1_R1
          	               	2         	191A1     	E1S_0_PRSNT         
          	               	3         	191A1     	GND                 
          	               	4         	191A1     	E1S_0_EN            
          	               	5         	191A1     	P3V3_AUX            

U150      	74LVC2G17GW    	          	          	                    
          	               	1         	224B3     	FM_PS_EN_PLD_R      
          	               	2         	224B3     	GND                 
          	               	3         	224B3     	NC_U150_A1          
          	               	4         	224B3     	NC_U150_B1          
          	               	5         	224B3     	P3V3_AUX            
          	               	6         	224B3     	FM_PS_EN_PLD_BUF1   

U154      	74LVC1G07SE7   	          	          	                    
          	               	1         	202B2     	NC_ESPI_PLD_R_EN_BUF
          	               	2         	202B3     	FM_ESPI_PLD_R1_EN   
          	               	3         	202B3     	GND                 
          	               	4         	202B2     	FM_ESPI_PLD_R_EN_BUF
          	               	5         	202B3     	P3V3_AUX            

U157      	74LVC1G07GV    	          	          	                    
          	               	1         	155B2     	NC_U157_NC1         
          	               	2         	155B2     	OCP_SFF_WAKE_BUFF_R_N
          	               	3         	155A2     	GND                 
          	               	4         	155A2     	IRQ_LVC3_WAKE_BUF_N 
          	               	5         	155B2     	P3V3_AUX            

U158      	MOSFET_NCH_GDS_ESD_PROTECTED	          	          	                    
          	               	D         	247B3     	FM_P12V_HSC_EN_N    
          	               	G         	247B3     	FM_P12V_HSC_EN_R    
          	               	S         	247B3     	GND                 

U175      	LTC4307CMS8    	          	          	                    
          	               	1         	234B4     	SMB_BMC_SWB_EN_R    
          	               	2         	234B4     	SMB_BMC_SWB_BUF_R_SCL
          	               	3         	234B4     	SMB_BMC_SWB_R_SCL   
          	               	4         	234B4     	GND                 
          	               	5         	234B4     	NC                  
          	               	6         	234B4     	SMB_BMC_SWB_R_SDA   
          	               	7         	234B4     	SMB_BMC_SWB_BUF_R_SDA
          	               	8         	234B4     	P3V3_AUX            

U176      	LTC4307CMS8    	          	          	                    
          	               	1         	234A3     	SMB_BMC_SWB_EN_R2   
          	               	2         	234A2     	I3C_BMC_SWB_BUF_R_SCL
          	               	3         	234A3     	I3C_BMC_SWB_R_SCL   
          	               	4         	234A3     	GND                 
          	               	5         	234A2     	NC                  
          	               	6         	234A3     	I3C_BMC_SWB_R_SDA   
          	               	7         	234A2     	I3C_BMC_SWB_BUF_R_SDA
          	               	8         	234A2     	P3V3_AUX            

U181      	PCA9539RPW     	          	          	                    
          	               	1         	227B3     	PU_U181_INT         
          	               	2         	227B3     	TCA9539_0_ADD1      
          	               	3         	227B3     	PU_RST_SMB_U181_N   
          	               	4         	227B3     	RST_USB_HUB_N       
          	               	5         	227B3     	RST_SWB_BIC_N       
          	               	6         	227B3     	TP_TCA9539_0_P0_2   
          	               	7         	227B3     	TP_TCA9539_0_P0_3   
          	               	8         	227B3     	PRSNT_SWB_ISO_R1_N  
          	               	9         	227B3     	GPU_PRSNT_N_ISO_R1  
          	               	10        	227B3     	PRSNT_CABLE_GPU_B3_ISO_R1_N
          	               	11        	227B3     	PRSNT_CABLE_SWB_B2_ISO_R_N
          	               	12        	227B3     	GND                 
          	               	13        	227B3     	PRSNT_CABLE_GPU_A2_ISO_R1_N
          	               	14        	227B3     	PRSNT_CABLE_SWB_B1_ISO_R_N
          	               	15        	227B3     	GPU_BASE_ID0_R      
          	               	16        	227B3     	GPU_BASE_ID1_R      
          	               	17        	227B3     	GPU_PEX_STRAP0_R    
          	               	18        	227B3     	GPU_PEX_STRAP1_R    
          	               	19        	227B3     	PRSNT_CABLE_GPU_A1_ISO_R1_N
          	               	20        	227B3     	PRSNT_CABLE_GPU_A3_ISO_R_N
          	               	21        	227B3     	TCA9539_0_ADD0      
          	               	22        	227B3     	SMB_IOEXP_3V3AUX_SCL_R1
          	               	23        	227B3     	SMB_IOEXP_3V3AUX_SDA_R1
          	               	24        	227B3     	P3V3_AUX            

U192      	LTC4307CMS8    	          	          	                    
          	               	1         	245A3     	FM_MB_PDB_SMB9_R_EN 
          	               	2         	245A2     	SMB_FAN_3V3AUX_BUF_SCL
          	               	3         	245A3     	SMB_FAN_3V3AUX_R_SCL
          	               	4         	245A3     	GND                 
          	               	5         	245A2     	NC                  
          	               	6         	245A3     	SMB_FAN_3V3AUX_R_SDA
          	               	7         	245A2     	SMB_FAN_3V3AUX_BUF_SDA
          	               	8         	245A2     	P3V3_AUX            

U193      	MAX11617EEET   	          	          	                    
          	               	1         	250B2     	MAX11617_VREF_R     
          	               	2         	250B2     	GND                 
          	               	3         	250B2     	GND                 
          	               	4         	250B2     	GND                 
          	               	5         	250B2     	P12V_AUX_ADC_MAM    
          	               	6         	250B2     	P12V_OCP_SFF_ISENSE_MAM
          	               	7         	250B2     	P12V_OCP_V3_2_ISENSE_MAM
          	               	8         	250B2     	P5V_ADC_MAM         
          	               	9         	250B1     	P3V3_ADC_MAM        
          	               	10        	250B1     	P3V3_AUX_ADC_MAM    
          	               	11        	250B1     	P3V3_PDB_AUX_ADC_MAM
          	               	12        	250B1     	P12V_E1S_0_ISENSE_MAM
          	               	13        	250B1     	SMB_SEN_MAM_3V3AUX_SCL
          	               	14        	250B1     	SMB_SEN_MAM_3V3AUX_SDA
          	               	15        	250B1     	GND                 
          	               	16        	250B1     	P3V3_MAX11617_VDD   

U194      	LTC4307CMS8    	          	          	                    
          	               	1         	234B3     	SMB_BMC_GPU_EN_R1   
          	               	2         	234B2     	SMB_1_BMC_GPU_BUF_R_SCL
          	               	3         	234B3     	SMB_1_BMC_GPU_R_SCL 
          	               	4         	234B3     	GND                 
          	               	5         	234B2     	NC                  
          	               	6         	234B3     	SMB_1_BMC_GPU_R_SDA 
          	               	7         	234B2     	SMB_1_BMC_GPU_BUF_R_SDA
          	               	8         	234B2     	P3V3_AUX            

U195      	74LVC2G17GW    	          	          	                    
          	               	1         	151B3     	BMC_MONITER_R       
          	               	2         	151B3     	GND                 
          	               	3         	151B3     	RST_SWB_BIC_R_N     
          	               	4         	151B3     	RST_SWB_BIC_BUF_R_N 
          	               	5         	151B3     	P3V3_AUX            
          	               	6         	151B3     	BMC_MONITER_BUF_R   

U196      	74LVC2G17GW    	          	          	                    
          	               	1         	151B3     	FM_GPU_PWR_EN_R     
          	               	2         	151A3     	GND                 
          	               	3         	151B3     	GPU_FPGA_RST_R_N    
          	               	4         	151B3     	GPU_FPGA_RST_R1_BUF_N
          	               	5         	151B3     	P3V3_AUX            
          	               	6         	151B3     	FM_GPU_PWR_EN_R1    

U200      	LTC4307CMS8    	          	          	                    
          	               	1         	234B4     	SMB_BMC_GPU_EN_R3   
          	               	2         	234B4     	SMB_2_BMC_GPU_BUF_R_SCL
          	               	3         	234B4     	SMB_2_BMC_GPU_R_SCL 
          	               	4         	234A4     	GND                 
          	               	5         	234A4     	NC                  
          	               	6         	234B4     	SMB_2_BMC_GPU_R_SDA 
          	               	7         	234B4     	SMB_2_BMC_GPU_BUF_R_SDA
          	               	8         	234B4     	P3V3_AUX            

U204      	74LVC1G126SE7  	          	          	                    
          	               	1         	151A4     	FM_UART_EN          
          	               	2         	151A4     	UART_BMC_BIC_R_RX   
          	               	3         	151A4     	GND                 
          	               	4         	151A4     	UART_BMC_BIC_R_BUF_RX
          	               	5         	151A4     	P3V3_AUX            

U205      	TPS3700DDCR    	          	          	                    
          	               	1         	306A4     	PWRGD_DSW_PWROK_R4  
          	               	2         	306A4     	GND                 
          	               	3         	306A4     	A_HSC_INAP          
          	               	4         	306A4     	NC_U205_INB-        
          	               	5         	306A4     	U205_VDD            
          	               	6         	306A4     	NC_U205_OUTB        

U206      	LT6700CS61TRPBF	          	          	                    
          	               	1         	306A2     	FM_UV_ADR_TRIGGER_N 
          	               	2         	306A2     	GND                 
          	               	3         	306A3     	A_P12V_STBY_ADR_TRIGGER
          	               	4         	306A3     	A_P12V_STBY_FP_TRIGGER
          	               	5         	306A3     	U206_VDD            
          	               	6         	306A2     	A_P12V_STBY_FPH_GATE

U207      	74LVC1G17GW    	          	          	                    
          	               	1         	161B3     	NC                  
          	               	2         	161B4     	RST_HP_OCP_V3_2_N   
          	               	3         	161B4     	GND                 
          	               	4         	161B3     	RST_OCP_V3_2_BUF_N  
          	               	5         	161B4     	P3V3_AUX            

U208      	74LVC1G08W57   	          	          	                    
          	               	1         	158A4     	HP_OCP_V3_1_EN      
          	               	2         	158A4     	HP_LVC3_OCP_V3_1_PRSNT2
          	               	3         	158A4     	GND                 
          	               	4         	158A4     	HP_LVC3_OCP_V3_1_EN 
          	               	5         	158A4     	P3V3_AUX            

U209      	PCA9555APW     	          	          	                    
          	               	1         	158B3     	FM_SMB_CPU0_ALERT   
          	               	2         	158B3     	PD_SMB_OCP1_HP_ADD1 
          	               	3         	158B3     	PD_SMB_OCP1_HP_ADD2 
          	               	4         	158B3     	TP_PCA9555_0_P00    
          	               	5         	158B3     	TP_PCA9555_0_P01    
          	               	6         	158B3     	HP_OCP_V3_1_EN      
          	               	7         	158B3     	HP_LVC3_OCP_V3_1_ATTN_OUT_SW_N
          	               	8         	158B3     	HP_LVC3_OCP_V3_1_PRSNT2_N
          	               	9         	158B3     	TP_PCA9555_0_P5     
          	               	10        	158B3     	TP_PCA9555_0_P6     
          	               	11        	158B3     	TP_PCA9555_0_P7     
          	               	12        	158B3     	GND                 
          	               	13        	158B3     	TP_PCA9555_0_P10    
          	               	14        	158B3     	TP_PCA9555_0_P11    
          	               	15        	158B3     	TP_PCA9555_0_P12    
          	               	16        	158B3     	TP_PCA9555_0_P13    
          	               	17        	158B3     	TP_PCA9555_0_P14    
          	               	18        	158B3     	TP_PCA9555_0_P15    
          	               	19        	158B3     	TP_PCA9555_0_P16    
          	               	20        	158B3     	TP_PCA9555_0_P17    
          	               	21        	158B3     	PD_SMB_OCP1_HP_ADD0 
          	               	22        	158B3     	SMB_PEHPCPU0_LVC3_R_SCL
          	               	23        	158B3     	SMB_PEHPCPU0_LVC3_R_SDA
          	               	24        	158B3     	P3V3_AUX            

U210      	74LVC1G08W57   	          	          	                    
          	               	1         	158B1     	HP_LVC3_OCP_V3_1_PWRGD_R
          	               	2         	158B1     	RST_OCP_V3_1_N      
          	               	3         	158B1     	GND                 
          	               	4         	158B1     	RST_HP_OCP_V3_1_N   
          	               	5         	158B1     	P3V3_AUX            

U211      	74LVC2G07DW7   	          	          	                    
          	               	1         	156A3     	OCP_SFF_PRSNT0_R_N  
          	               	2         	156A3     	GND                 
          	               	3         	156A3     	OCP_SFF_PRSNT1_R_N  
          	               	4         	156A3     	HP_LVC3_OCP_V3_1_PRSNT2_N_R
          	               	5         	156A3     	P3V3_AUX            
          	               	6         	156A3     	HP_LVC3_OCP_V3_1_PRSNT2_N_R

U212      	74LVC2G07DW7   	          	          	                    
          	               	1         	156A3     	OCP_SFF_PRSNT2_R_N  
          	               	2         	156A3     	GND                 
          	               	3         	156A3     	OCP_SFF_PRSNT3_R_N  
          	               	4         	156A3     	HP_LVC3_OCP_V3_1_PRSNT2_N_R
          	               	5         	156A3     	P3V3_AUX            
          	               	6         	156A3     	HP_LVC3_OCP_V3_1_PRSNT2_N_R

U215      	MOSFET_N_SMLF  	          	          	                    
          	               	D         	164A4     	HP_LVC3_OCP_V3_2_PRSNT2
          	               	G         	164A4     	HP_LVC3_OCP_V3_2_PRSNT2_N
          	               	S         	164A4     	GND                 

U216      	APX80929SAG7   	          	          	                    
          	               	1         	164B4     	GND                 
          	               	2         	164B4     	HP_OCP_V3_2_RST     
          	               	3         	164B4     	P3V3_OCP_V3_2       

U217      	74LVC1G126SE7  	          	          	                    
          	               	1         	161B4     	PU_OCP_V3_2_WAKE_OE 
          	               	2         	161B4     	IRQ_LVC3_OCP_V3_2_WAKE_N
          	               	3         	161B4     	GND                 
          	               	4         	161B4     	OCP_V3_2_WAKE_BUFF_N
          	               	5         	161B4     	P3V3_AUX            

U218      	74LVC1G07GV    	          	          	                    
          	               	1         	161B4     	NC_U218_NC1         
          	               	2         	161B4     	FM_SYS_THROTTLE_R_N 
          	               	3         	161B4     	GND                 
          	               	4         	161B3     	OCP_V3_2_PWRBRK_BUFF_N
          	               	5         	161B3     	P3V3_AUX            

U219      	74LVC1G07GV    	          	          	                    
          	               	1         	161B2     	NC_U219_NC1         
          	               	2         	161B2     	OCP_V3_2_WAKE_BUFF_R_N
          	               	3         	161B2     	GND                 
          	               	4         	161B2     	IRQ_LVC3_V3_2_WAKE_BUF_N
          	               	5         	161B2     	P3V3_AUX            

U222      	74CBTLV3126PW  	          	          	                    
          	               	1         	160B2     	FB_BMC_ISOLATE1     
          	               	2         	160B2     	NCSI_BMC_RXD1_R1    
          	               	3         	160B3     	NCSI_OCP_V3_2_RXD1  
          	               	4         	160B2     	FB_BMC_ISOLATE1     
          	               	5         	160B2     	NCSI_BMC_RXD0_R1    
          	               	6         	160B3     	NCSI_OCP_V3_2_RXD0  
          	               	7         	160B3     	GND                 
          	               	8         	160B3     	NCSI_OCP_V3_2_CRS_DV
          	               	9         	160B2     	NCSI_BMC_CRS_DV_R1  
          	               	10        	160B2     	FB_BMC_ISOLATE1     
          	               	11        	160B3     	OCP_V3_2_ISO1_RBT_ARB_IN
          	               	12        	160B2     	OCP_V3_2_RBT_ARB_IN_R
          	               	13        	160B2     	FB_BMC_ISOLATE1     
          	               	14        	160B3     	P3V3_AUX            

U223      	74CBTLV3126PW  	          	          	                    
          	               	1         	160B2     	FB_BMC_ISOLATE1     
          	               	2         	160B2     	NCSI_BMC_TXD1_R1    
          	               	3         	160B3     	NCSI_OCP_V3_2_TXD1  
          	               	4         	160B2     	FB_BMC_ISOLATE1     
          	               	5         	160B2     	NCSI_BMC_TXD0_R1    
          	               	6         	160B3     	NCSI_OCP_V3_2_TXD0  
          	               	7         	160B3     	GND                 
          	               	8         	160B3     	NCSI_OCP_V3_2_TX_EN 
          	               	9         	160B2     	NCSI_BMC_TX_EN_R1   
          	               	10        	160B2     	FB_BMC_ISOLATE1     
          	               	11        	160B3     	OCP_V3_2_ISO2_RBT_ARB_OUT
          	               	12        	160B2     	OCP_V3_2_RBT_ARB_OUT
          	               	13        	160B2     	FB_BMC_ISOLATE1     
          	               	14        	160B3     	P3V3_AUX            

U224      	74LVC1G126SE7  	          	          	                    
          	               	1         	154A4     	OCP_SFF_AUX_PWR_EN_R4
          	               	2         	154A4     	RST_SMB_SWITCH_N    
          	               	3         	154A4     	GND                 
          	               	4         	154A3     	RST_HP_OCP_SFF_R_N  
          	               	5         	154A4     	P3V3_AUX            

U225      	74LVC1G126SE7  	          	          	                    
          	               	1         	161A4     	OCP_V3_2_AUX_PWR_EN_R3
          	               	2         	161A4     	RST_SMB_SWITCH_N    
          	               	3         	161A3     	GND                 
          	               	4         	161A3     	RST_HP_OCP_V3_2_R_N 
          	               	5         	161A3     	P3V3_AUX            

U235      	PCA9617ADP     	          	          	                    
          	               	1         	238B3     	P3V3_AUX            
          	               	2         	238B3     	SMB_OCP_V3_2_3V3AUX_SCL
          	               	3         	238B3     	SMB_OCP_V3_2_3V3AUX_SDA
          	               	4         	238B3     	GND                 
          	               	5         	238B3     	HP_LVC3_OCP_V3_2_R_EN
          	               	6         	238B3     	SMB_OCP_V3_2_3V3AUX_BUF_SDA
          	               	7         	238B3     	SMB_OCP_V3_2_3V3AUX_BUF_SCL
          	               	8         	238B3     	P3V3_OCP_V3_2       

U236      	PCA9617ADP     	          	          	                    
          	               	1         	238B3     	P3V3_AUX            
          	               	2         	238B3     	SMB_OCP_SFF_3V3AUX_SCL
          	               	3         	238B3     	SMB_OCP_SFF_3V3AUX_SDA
          	               	4         	238B3     	GND                 
          	               	5         	238B3     	HP_LVC3_OCP_V3_1_R_EN
          	               	6         	238B3     	SMB_OCP_SFF_3V3AUX_BUF_SDA
          	               	7         	238B3     	SMB_OCP_SFF_3V3AUX_BUF_SCL
          	               	8         	238B3     	P3V3_OCP_SFF        

U237      	PI3EQX12902AZLEX	          	          	                    
          	               	1         	166B4     	P3V3_AUX            
          	               	2         	166B4     	P2E_MB_BMC_TX_C_R1_DP<0>
          	               	3         	166B4     	P2E_MB_BMC_TX_C_R1_DN<0>
          	               	4         	166B3     	GND                 
          	               	5         	166B3     	PU_TEST             
          	               	6         	166B3     	GND                 
          	               	7         	166B3     	GND                 
          	               	8         	166B3     	P2E_MB_BMC_RX_BUF_C_DN<0>
          	               	9         	166B3     	P2E_MB_BMC_RX_BUF_C_DP<0>
          	               	10        	166B4     	P3V3_AUX            
          	               	11        	166B3     	FM_P2E_EN_N         
          	               	12        	166B4     	FM_P2E_SWB          
          	               	13        	166B3     	GND                 
          	               	14        	166B4     	FM_P2E_FGB          
          	               	15        	166B4     	FM_P2E_EQB1         
          	               	16        	166B4     	P3V3_AUX            
          	               	17        	166B4     	P2E_MB_BMC_RX_R1_DP<0>
          	               	18        	166B4     	P2E_MB_BMC_RX_R1_DN<0>
          	               	19        	166B3     	GND                 
          	               	20        	166B4     	FM_P2E_EQB0         
          	               	21        	166B4     	FM_P2E_EQA0         
          	               	22        	166B3     	GND                 
          	               	23        	166B3     	P2E_MB_BMC_TX_BUF_DN<0>
          	               	24        	166B3     	P2E_MB_BMC_TX_BUF_DP<0>
          	               	25        	166B4     	P3V3_AUX            
          	               	26        	166B4     	FM_P2E_EQA1         
          	               	27        	166B4     	FM_P2E_FGA          
          	               	28        	166B3     	GND                 
          	               	29        	166B4     	FM_P2E_SWA          
          	               	30        	166B3     	FM_P2E_MODE         
          	               	TH        	166B3     	GND                 

U239      	74LVC1G126SE7  	          	          	                    
          	               	1         	190B3     	PU_BUFFER_HDD_ACTIVITY
          	               	2         	190B3     	LED_HDD_ACTIVITY_N  
          	               	3         	190A3     	GND                 
          	               	4         	190B3     	LED_HDD_ACTIVITY_B_N
          	               	5         	190B3     	P3V3_AUX            

U240      	74LVC2G08DP    	          	          	                    
          	               	1         	165B4     	OCP_SFF_PRSNT0_R_N  
          	               	2         	165B4     	OCP_SFF_PRSNT1_R_N  
          	               	3         	165B4     	OCP_SFF_PRSNT23_R_N 
          	               	4         	165B4     	GND                 
          	               	5         	165B4     	OCP_SFF_PRSNT2_R_N  
          	               	6         	165B4     	OCP_SFF_PRSNT3_R_N  
          	               	7         	165B4     	OCP_SFF_PRSNT01_R_N 
          	               	8         	165B4     	P3V3_AUX            

U241      	74LVC2G08DP    	          	          	                    
          	               	1         	165B4     	OCP_V3_2_PRSNT0_R_N 
          	               	2         	165B4     	OCP_V3_2_PRSNT1_R_N 
          	               	3         	165B4     	OCP_V3_2_PRSNT23_R_N
          	               	4         	165B4     	GND                 
          	               	5         	165B4     	OCP_V3_2_PRSNT2_R_N 
          	               	6         	165A4     	OCP_V3_2_PRSNT3_R_N 
          	               	7         	165B4     	OCP_V3_2_PRSNT01_R_N
          	               	8         	165B4     	P3V3_AUX            

U242      	74LVC2G08DP    	          	          	                    
          	               	1         	165B3     	OCP_SFF_PRSNT01_R_N 
          	               	2         	165B3     	OCP_SFF_PRSNT23_R_N 
          	               	3         	165B3     	OCP_V3_2_PRSNT_ALL_R_N
          	               	4         	165B3     	GND                 
          	               	5         	165B3     	OCP_V3_2_PRSNT01_R_N
          	               	6         	165B3     	OCP_V3_2_PRSNT23_R_N
          	               	7         	165B3     	OCP_SFF_PRSNT_ALL_R_N
          	               	8         	165B3     	P3V3_AUX            

U243      	NC7SB3157_SMLF 	          	          	                    
          	               	1         	165B2     	OCP_SFF_NOT_PRSNT_RBT_ARB_IN
          	               	2         	165B2     	GND                 
          	               	3         	165B2     	OCP_SFF_RBT_ARB_OUT 
          	               	4         	165B2     	OCP_SFF_RBT_ARB_IN_MUX2
          	               	5         	165B2     	P3V3_AUX            
          	               	6         	165B2     	OCP_SFF_PRSNT_ALL_R1_N

U244      	NC7SB3157_SMLF 	          	          	                    
          	               	1         	165B2     	OCP_SFF_NOT_PRSNT_RBT_ARB_IN
          	               	2         	165B2     	GND                 
          	               	3         	165B2     	OCP_SFF_RBT_ARB_IN  
          	               	4         	165B2     	OCP_SFF_RBT_ARB_IN_MUX1_R
          	               	5         	165B2     	P3V3_AUX            
          	               	6         	165B2     	OCP_SFF_PRSNT_ALL_R3_N

U245      	NC7SB3157_SMLF 	          	          	                    
          	               	1         	165A2     	OCP_V3_2_NOT_PRSNT_RBT_ARB_IN
          	               	2         	165A2     	GND                 
          	               	3         	165A2     	OCP_V3_2_RBT_ARB_IN 
          	               	4         	165A2     	OCP_SFF_RBT_ARB_IN_MUX2_R
          	               	5         	165A2     	P3V3_AUX            
          	               	6         	165A2     	OCP_V3_2_PRSNT_ALL_R3_N

U246      	NC7SB3157_SMLF 	          	          	                    
          	               	1         	165B2     	OCP_V3_2_NOT_PRSNT_RBT_ARB_IN
          	               	2         	165B2     	GND                 
          	               	3         	165B2     	OCP_V3_2_RBT_ARB_OUT
          	               	4         	165B2     	OCP_SFF_RBT_ARB_IN_MUX1
          	               	5         	165B2     	P3V3_AUX            
          	               	6         	165B2     	OCP_V3_2_PRSNT_ALL_R1_N

U247      	9FGL0251CKILFT 	          	          	                    
          	               	1         	212B3     	CLK_GEN2_XTAL_IN    
          	               	2         	212B3     	CLK_GEN2_XTAL_OUT   
          	               	3         	212B3     	VFG3P3_CLK_GEN      
          	               	4         	212B2     	CLK_GEN2_SMB_SADR   
          	               	5         	212B2     	GND                 
          	               	6         	212B2     	GND                 
          	               	7         	212B3     	VFG3P3_CLK_GEN      
          	               	8         	212B3     	SMB_HOST_CLK_GEN2_3V3AUX_SCL
          	               	9         	212B3     	SMB_HOST_CLK_GEN2_3V3AUX_SDA
          	               	10        	212B2     	GND                 
          	               	11        	212B3     	VFG3P3_CLK_GEN      
          	               	12        	212B3     	CLK_GEN2_BMC_RC_OE_R3_N
          	               	13        	212B2     	CLK_100M_BMC_RC_DP_R
          	               	14        	212B2     	CLK_100M_BMC_RC_DN_R
          	               	15        	212B2     	GND                 
          	               	16        	212B3     	VFG_3P3A_CLK_GEN    
          	               	17        	212B2     	CLK_100M_GPU_FPGA_DP_R
          	               	18        	212B2     	CLK_100M_GPU_FPGA_DN_R
          	               	19        	212B3     	CLK_GEN2_GPU_OE_N   
          	               	20        	212B3     	VFG3P3_CLK_GEN      
          	               	21        	212B2     	GND                 
          	               	22        	212B3     	P3V3_PWRGD_CLKGEN   
          	               	23        	212B3     	FG_SS_EN            
          	               	24        	212B2     	GND                 
          	               	TH        	212B2     	GND                 

U248      	74LVC1G32GW_SMLF	          	          	                    
          	               	1         	212A3     	GPU_FPGA_READY_R_N  
          	               	2         	212A3     	CLK_GEN2_GPU_FPGA_OE_R2_N
          	               	3         	212A3     	GND                 
          	               	4         	212A3     	CLK_GEN2_GPU_FPGA_OE_OR_N
          	               	5         	212A3     	P3V3_AUX            

U249      	LCMXO3LF9400C5BG484C	          	          	                    
          	               	A1        	217B3     	GND                 
          	               	A2        	213B3     	FM_GPU_PWR_EN       
          	               	A3        	213B3     	FM_GPU_HSC_EN_R     
          	               	A4        	213B3     	SMB_BMC_SWB_EN      
          	               	A5        	213B3     	FM_TPM_PRSNT_R_N    
          	               	A6        	213B3     	FM_PECI_MUX_SEL_N   
          	               	A7        	213B3     	FM_OCP_SFF_PWR_GOOD_R
          	               	A8        	213B3     	IRQ_SML1_PMBUS_PLD_ALERT_N
          	               	A9        	213B3     	GPU_NVS_PWR_BRAKE_R_N
          	               	A10       	213B3     	SMB_HOST_3V3AUX_PLD_SCL
          	               	A11       	213B3     	GPU_WP_HW_CTRL_R_N  
          	               	A12       	213B2     	SMB_1_PLD_3V3AUX_SDA_R1
          	               	A13       	213B2     	PWRGD_PVNN_MAIN_CPU0
          	               	A14       	213B2     	PWRGD_PVPP_HBM_CPU1 
          	               	A15       	213B2     	SGPIO_DEBUG_PLD_DOUT
          	               	A16       	213B2     	SGPIO_OCP_SFF_DATAOUT
          	               	A17       	213B2     	SGPIO_OCP_V3_2_DATAOUT
          	               	A18       	213B2     	GPU_FPGA_READY_ISO_R
          	               	A19       	213B2     	P12V_HSC_TEMP_ALERT_R_N
          	               	A20       	213B2     	NC_FPGA_PT43A       
          	               	A21       	213B2     	NC_FPGA_PT44A       
          	               	A22       	217B3     	GND                 
          	               	AA1       	216B3     	H_CPU_NMI_LVC1_R_N  
          	               	AA2       	215B3     	FM_ADR_ACK_R        
          	               	AA3       	215B3     	FM_ADR_MODE0_R      
          	               	AA4       	215B3     	IRQ_PVCCD_CPU0_VRHOT_LVC3_N
          	               	AA5       	215B3     	PWRGD_PLT_AUX_CPU0_LVT3_R
          	               	AA6       	215B3     	RST_MB_STBY_R_N     
          	               	AA7       	215B3     	FM_DIS_PS_PWROK_DLY 
          	               	AA8       	215B3     	FM_CPU_RMCA_CATERR_LVT3_R_N
          	               	AA9       	215B3     	JTAG_DBP_BMC_PRDY_R_N
          	               	AA10      	215B3     	CLK_25M_OSC_MAIN_FPGA
          	               	AA11      	215B3     	PRSNT_CABLE_GPU_B3_ISO_R_N
          	               	AA12      	215B3     	IRQ_PSYS_CRIT_N     
          	               	AA13      	215B3     	IRQ_PVCCD_CPU1_VRHOT_LVC3_N
          	               	AA14      	215B3     	FM_SYS_THROTTLE_R_N 
          	               	AA15      	215B3     	NC_FPGA_PB35B       
          	               	AA16      	215B3     	FM_PCH_PLD_GLB_RST_WARN_N
          	               	AA17      	215B3     	FM_BMC_READY_R_PLD_N
          	               	AA18      	215B3     	CLK_GPU_1_OE_N      
          	               	AA19      	215B3     	FM_PLD_REV_N        
          	               	AA20      	215B3     	HPDB_HSC_PWRGD_ISO_R
          	               	AA21      	215B3     	NC_FPGA_PB46B       
          	               	AA22      	214B2     	LED_HDD_ACTIVITY_B_PLD_N
          	               	AB1       	217B3     	GND                 
          	               	AB2       	215B3     	FM_UV_ADR_TRIGGER_R_N
          	               	AB3       	215B3     	FM_ADR_MODE1_R      
          	               	AB4       	215B3     	IRQ_BMC_PCH_NMI_R   
          	               	AB5       	215B3     	PWRGD_PLT_AUX_CPU1_LVT3_R
          	               	AB6       	215B3     	RST_SMB_SWITCH_N    
          	               	AB7       	215B3     	FM_PCH_CRASHLOG_TRIG_R_N
          	               	AB8       	215B3     	FM_PCH_BMC_THERMTRIP_N
          	               	AB9       	215B3     	FM_DEBUG_PORT_PRSNT_N
          	               	AB10      	215B3     	NC_FPGA_PB22B       
          	               	AB11      	215B3     	GPU_3V3IO_RSVD3_FFU_ISO_R
          	               	AB12      	215B3     	IRQ_SGPIO_INTR_N_R  
          	               	AB13      	215B3     	IRQ_TPM_SPI_N       
          	               	AB14      	215B3     	RST_PLTRST_PLD_B_N  
          	               	AB15      	215B3     	FM_SPD_REMOTE_EN_R  
          	               	AB16      	215B3     	VIRTUAL_RESEAT      
          	               	AB17      	215B3     	FM_PCHHOT_R_N       
          	               	AB18      	215B3     	JTAG_DBP_BMC_PREQ_R_N
          	               	AB19      	215B3     	CLK_GEN2_BMC_RC_OE_N
          	               	AB20      	215B3     	HGX_DETECT_N_R      
          	               	AB21      	215B3     	PULL_FPGA_PB46A     
          	               	AB22      	217B3     	GND                 
          	               	B1        	213B3     	FM_SWB_PWR_EN       
          	               	B2        	213B3     	FM_FAN_PWR_EN       
          	               	B3        	213B3     	FM_SWB_BIC_READY_ISO_R_N
          	               	B4        	213B3     	FM_PCH_PRSNT_N      
          	               	B5        	213B3     	IRQ_HSC_FAULT_R1_N  
          	               	B6        	213B3     	FM_OCP_V3_2_PWR_GOOD_R
          	               	B7        	217B3     	GND                 
          	               	B8        	213B3     	IRQ_SML0_ALERT_R_N  
          	               	B9        	213B3     	GPU_FPGA_THERM_OVERT_ISO_R_N
          	               	B10       	213B3     	SMB_HOST_3V3AUX_PLD_SDA
          	               	B11       	213B3     	GPU_FPGA_OVERT_ISO_R_N
          	               	B12       	213B2     	SMB_1_PLD_3V3AUX_SCL_R1
          	               	B13       	213B2     	PWRGD_PVNN_PCH_AUX  
          	               	B14       	213B2     	FM_NCSI_OCP_V3_2_R_OE
          	               	B15       	213B2     	SGPIO_DEBUG_PLD_CLK 
          	               	B16       	217B3     	GND                 
          	               	B17       	213B2     	SGPIO_OCP_SFF_CLK   
          	               	B18       	213B2     	SGPIO_OCP_V3_2_CLK  
          	               	B19       	213B2     	PU_MAIN_FPGA_CONFIG_DONE
          	               	B20       	213B2     	P12V_HSC_T_CRIT_R_N 
          	               	B21       	213B2     	NC_FPGA_PT43B       
          	               	B22       	213B2     	NC_FPGA_PT44B       
          	               	C1        	216B4     	RST_PLD_CPU0_DRAM_AB_N
          	               	C2        	217B3     	GND                 
          	               	C3        	213B3     	BIC_MONITER_ISO_R   
          	               	C4        	213B3     	BMC_MONITER         
          	               	C5        	213B3     	FM_BMC_SUSACK_R_N   
          	               	C6        	213B3     	FM_S3M_CPU0_CPLD_CRC_ERROR
          	               	C7        	217B4     	P3V3_AUX_FPGA_VCCIO0
          	               	C8        	213B3     	OCP_SFF_CLK_OE_R_N  
          	               	C9        	213B3     	FM_SLP_SUS_RSM_RST_N
          	               	C10       	216A3     	JTAG_PLD_TMS_R      
          	               	C11       	217B3     	GND                 
          	               	C12       	217B4     	P3V3_AUX_FPGA_VCCIO0
          	               	C13       	213B2     	PWRGD_PVNN_MAIN_CPU1
          	               	C14       	213B2     	SGPIO_BMC_DOUT      
          	               	C15       	213B2     	SGPIO_DEBUG_PLD_DIN 
          	               	C16       	217B4     	P3V3_AUX_FPGA_VCCIO0
          	               	C17       	213B2     	SGPIO_OCP_SFF_DATAIN
          	               	C18       	213B2     	JTAG_BMC_SW_PLD_OE  
          	               	C19       	213B2     	NC_FPGA_PT43C       
          	               	C20       	213B2     	NC_FPGA_PT43D       
          	               	C21       	214B3     	FM_PVCCD_HV_CPU0_EN 
          	               	C22       	214B3     	FM_PVCCD_HV_CPU1_EN 
          	               	D1        	216B4     	RST_PLD_CPU1_DRAM_AB_N
          	               	D2        	216B4     	RST_PLD_CPU0_DRAM_CD_N
          	               	D3        	216B4     	RST_CPU0_DRAM_AB_PLD_LVT3_N
          	               	D4        	216B4     	RST_CPU0_DRAM_CD_PLD_LVT3_N
          	               	D5        	213B3     	VIRTUAL_RESEAT_FPGA_R_N
          	               	D6        	213B3     	OCP_V3_2_AUX_PWR_PLD_EN
          	               	D7        	213B3     	FM_S3M_CPU1_CPLD_CRC_ERROR
          	               	D8        	213B3     	IRQ_SML1_PMBUS_BMC_ALERT_N
          	               	D9        	213B3     	PU_RST_DEDI_BUSY_PLD_N
          	               	D10       	216A3     	JTAG_PLD_TCK_R      
          	               	D11       	213B3     	GPU_FPGA_EROT_FATALERR_ISO_R_N
          	               	D12       	213B2     	PWRGD_P5V_AUX_R2    
          	               	D13       	213B2     	PWRGD_PVPP_HBM_CPU0 
          	               	D14       	213B2     	SGPIO_BMC_CLK       
          	               	D15       	213B2     	SGPIO_DEBUG_PLD_LD_N
          	               	D16       	213B2     	SGPIO_OCP_SFF_LD_N  
          	               	D17       	213B2     	SGPIO_OCP_V3_2_LD_N 
          	               	D18       	213B2     	NC_FPGA_PT41D       
          	               	D19       	214B3     	FM_PVCCINFAON_CPU0_R_EN
          	               	D20       	214B3     	FM_PVCCINFAON_CPU1_R_EN
          	               	D21       	214B3     	FM_PVCCFA_EHV_FIVRA_CPU1_R_EN
          	               	D22       	214B3     	FM_PVCCFA_EHV_FIVRA_CPU0_R_EN
          	               	E1        	216B4     	NC                  
          	               	E2        	216B4     	RST_PLD_CPU1_DRAM_CD_N
          	               	E3        	216B4     	RST_PLD_CPU1_DRAM_EF_N
          	               	E4        	216B4     	RST_CPU1_DRAM_AB_PLD_LVT3_N
          	               	E5        	217B3     	GND                 
          	               	E6        	213B3     	FM_SWB_PWRGD_ISO_R  
          	               	E7        	213B3     	OCP_SFF_AUX_PWR_PLD_EN
          	               	E8        	216A3     	JTAG_PLD_TDO_R      
          	               	E9        	216A3     	JTAG_PLD_TDI_R      
          	               	E10       	213B3     	GPU_HMC_PRSNT_ISO_R_N
          	               	E11       	213B3     	GPU_PRSNT_N_ISO_R   
          	               	E12       	213B2     	PWRGD_P3V3          
          	               	E13       	213B2     	PWRGD_PVCCFA_EHV_FIVRA_CPU0
          	               	E14       	216A3     	JTAG_PLD_JTAGEN     
          	               	E15       	216A3     	PU_FPGA_D12_PROGRAMN
          	               	E16       	213B2     	SGPIO_OCP_V3_2_DATAIN
          	               	E17       	216A3     	NC_FPGA_PT44D       
          	               	E18       	217B3     	GND                 
          	               	E19       	214B3     	FM_PVCCIN_CPU0_R_EN 
          	               	E20       	214B3     	FM_PVCCIN_CPU1_R_EN 
          	               	E21       	214B3     	FM_PVNN_MAIN_CPU1_EN
          	               	E22       	214B3     	FM_PVNN_MAIN_CPU0_EN
          	               	F1        	216B4     	NC                  
          	               	F2        	217B3     	GND                 
          	               	F3        	217B4     	P3V3_AUX_FPGA_VCCIO5
          	               	F4        	216B4     	RST_PLD_CPU1_DRAM_GH_N
          	               	F5        	216B4     	RST_CPU1_DRAM_CD_PLD_LVT3_N
          	               	F6        	216B4     	RST_CPU0_DRAM_EF_PLD_LVT3_N
          	               	F7        	213B3     	FM_GPU_PWRGD_ISO_R  
          	               	F8        	213B3     	RST_BMC_FROM_SWB_ISO_R_N
          	               	F9        	213B3     	GPU_FPGA_EROT_RST_R_N
          	               	F10       	213B3     	GPU_BASE_HMC_READY_ISO_R
          	               	F11       	213B3     	GPU_FPGA_EROT_RECOV_R_N
          	               	F12       	213B2     	PWRGD_PVCCD_HV_CPU0 
          	               	F13       	213B2     	PWRGD_PVCCIN_CPU0   
          	               	F14       	213B2     	SGPIO_BMC_LD_N      
          	               	F15       	213B2     	RST_SRST_PLD_BMC_R_N
          	               	F16       	216A3     	NC_FPGA_PT44C       
          	               	F17       	214B3     	FM_PVCCFA_EHV_CPU0_R_EN
          	               	F18       	214B3     	FM_AUX_SW_EN        
          	               	F19       	214B3     	FM_PCH_P1V8_AUX_EN  
          	               	F20       	217B4     	P3V3_AUX_FPGA_VCCIO1
          	               	F21       	217B3     	GND                 
          	               	F22       	214B3     	FM_PVPP_HBM_CPU1_EN 
          	               	G1        	216B3     	PWRGD_DRAMPWRGD_CPU0_CD_R_LVC1
          	               	G2        	216B3     	PWRGD_DRAMPWRGD_CPU0_AB_R_LVC1
          	               	G3        	216B4     	NC                  
          	               	G4        	216B4     	NC                  
          	               	G5        	216B4     	RST_PLD_CPU0_DRAM_EF_N
          	               	G6        	216B4     	RST_CPU1_DRAM_EF_PLD_LVT3_N
          	               	G7        	216B4     	RST_CPU0_DRAM_GH_PLD_LVT3_N
          	               	G8        	213B3     	SMB_BMC_GPU_EN      
          	               	G9        	213B3     	GPU_BASE_STBY_EN_R  
          	               	G10       	217B4     	P3V3_AUX_FPGA_VCCIO0
          	               	G11       	213B3     	GPU_FPGA_BOOT_EN_R  
          	               	G12       	213B2     	PWRGD_P3V3_AUX_PLD  
          	               	G13       	217B4     	P3V3_AUX_FPGA_VCCIO0
          	               	G14       	213B2     	SGPIO_BMC_DIN_R     
          	               	G15       	213B2     	NC_FPGA_PT42D       
          	               	G16       	214B3     	FM_PVCCFA_EHV_CPU1_R_EN
          	               	G17       	214B3     	PWRGD_PVCCINFAON_CPU0
          	               	G18       	214B3     	PWRGD_PVCCIN_CPU1   
          	               	G19       	214B3     	FM_ESPI_PLD_R_EN    
          	               	G20       	214B3     	FM_P1V05_PCH_AUX_EN 
          	               	G21       	214B3     	FM_P5V_EN           
          	               	G22       	214B3     	FM_PVPP_HBM_CPU0_EN 
          	               	H1        	216B3     	PWRGD_DRAMPWRGD_CPU1_CD_R_LVC1
          	               	H2        	216B3     	PWRGD_DRAMPWRGD_CPU1_AB_R_LVC1
          	               	H3        	216B3     	PWRGD_DRAMPWRGD_CPU0_GH_R_LVC1
          	               	H4        	216B3     	PWRGD_DRAMPWRGD_CPU0_EF_R_LVC1
          	               	H5        	216B3     	FM_BOARD_BMC_SKU_ID4
          	               	H6        	216B4     	RST_PLD_CPU0_DRAM_GH_N
          	               	H7        	216B4     	RST_CPU1_DRAM_GH_PLD_LVT3_N
          	               	H8        	217B3     	GND                 
          	               	H9        	217B4     	P3V3_AUX_FPGA_VCCIO0
          	               	H10       	217B3     	GND                 
          	               	H11       	217B4     	P3V3_AUX_FPGA_VCCIO0
          	               	H12       	217B4     	P3V3_AUX_FPGA_VCCIO0
          	               	H13       	217B3     	GND                 
          	               	H14       	217B4     	P3V3_AUX_FPGA_VCCIO0
          	               	H15       	217B3     	GND                 
          	               	H16       	214B3     	PWRGD_PS_PWROK_PLD_ISO_R
          	               	H17       	214B3     	FM_PFR_DSW_PWROK_N  
          	               	H18       	214B3     	PWRGD_PVCCD_HV_CPU1 
          	               	H19       	214B3     	PWRGD_PVCCFA_EHV_FIVRA_CPU1
          	               	H20       	214B3     	PWRGD_PVCCINFAON_CPU1
          	               	H21       	214B3     	PWRGD_PVCCFA_EHV_CPU1
          	               	H22       	214B3     	PWRGD_PVCCFA_EHV_CPU0
          	               	J1        	216B3     	FAB_BMC_REV_ID2     
          	               	J2        	216B3     	FM_BOARD_BMC_SKU_ID0
          	               	J3        	216B3     	FM_BOARD_BMC_SKU_ID1
          	               	J4        	216B3     	FM_BOARD_BMC_SKU_ID2
          	               	J5        	216B3     	FM_BOARD_BMC_SKU_ID3
          	               	J6        	216B3     	PWRGD_DRAMPWRGD_CPU1_GH_R_LVC1
          	               	J7        	216B3     	PWRGD_DRAMPWRGD_CPU1_EF_R_LVC1
          	               	J8        	217B4     	P3V3_AUX_FPGA_VCCIO5
          	               	J9        	217B3     	GND                 
          	               	J10       	217B3     	GND                 
          	               	J11       	217B3     	GND                 
          	               	J12       	217B3     	GND                 
          	               	J13       	217B3     	GND                 
          	               	J14       	217B3     	GND                 
          	               	J15       	217B4     	P3V3_AUX_FPGA_VCCIO1
          	               	J16       	214B3     	PWRGD_P1V05_PCH_AUX 
          	               	J17       	214B3     	PWRGD_P1V8_PCH_AUX_PLD
          	               	J18       	214B3     	PWRGD_SYS_PWROK_R   
          	               	J19       	214B3     	PWRGD_PCH_PWROK_R   
          	               	J20       	214B3     	E1S_0_P3V3_ADC_ALERT
          	               	J21       	214B3     	IRQ_PVCCFA_CPU0_VRHOT_R_N
          	               	J22       	214B3     	IRQ_PVCCFA_CPU1_VRHOT_R_N
          	               	K1        	216B4     	HP_E1S_0_P3V3_PWRGD_PLD
          	               	K2        	216B4     	HP_LVC3_E1S_0_HSC_PWRGD_PLD
          	               	K3        	216B4     	HP_LVC3_OCP_V3_2_PRSNT2_PLD_N
          	               	K4        	216B4     	HP_LVC3_OCP_V3_1_PRSNT2_PLD_N
          	               	K5        	216B4     	HP_LVC3_OCP_V3_2_FUSE_PWRGD
          	               	K6        	216B3     	FAB_BMC_REV_ID0     
          	               	K7        	216B3     	FAB_BMC_REV_ID1     
          	               	K8        	217B4     	P3V3_AUX_FPGA_VCCIO5
          	               	K9        	217B3     	GND                 
          	               	K10       	217B4     	VCC_PLD_CORE        
          	               	K11       	217B4     	VCC_PLD_CORE        
          	               	K12       	217B4     	VCC_PLD_CORE        
          	               	K13       	217B4     	VCC_PLD_CORE        
          	               	K14       	217B3     	GND                 
          	               	K15       	217B4     	P3V3_AUX_FPGA_VCCIO1
          	               	K16       	214B3     	P12V_SCM_ADC_ALERT  
          	               	K17       	214B3     	M2_0_P3V3_ADC_ALERT 
          	               	K18       	214B3     	OCP_V3_2_P3V3_ADC_ALERT
          	               	K19       	214B3     	NC_FPGA_PR13A       
          	               	K20       	214B3     	OCP_SFF_P3V3_ADC_ALERT
          	               	K21       	217B3     	GND                 
          	               	K22       	214B3     	FM_SOL_UART_CH_SEL  
          	               	L1        	216B4     	NC                  
          	               	L2        	217B3     	GND                 
          	               	L3        	216B4     	NC                  
          	               	L4        	216B4     	NC                  
          	               	L5        	216B4     	HP_LVC3_SCM_HSC_PWRGD_PLD
          	               	L6        	216B4     	E1S_0_CLK_OE_N      
          	               	L7        	216B4     	HP_LVC3_OCP_V3_1_FUSE_PWRGD
          	               	L8        	217B4     	P3V3_AUX_FPGA_VCCIO4
          	               	L9        	217B3     	GND                 
          	               	L10       	217B3     	GND                 
          	               	L11       	217B4     	VCC_PLD_CORE        
          	               	L12       	217B4     	VCC_PLD_CORE        
          	               	L13       	217B3     	GND                 
          	               	L14       	217B3     	GND                 
          	               	L15       	217B4     	P3V3_AUX_FPGA_VCCIO1
          	               	L16       	214B3     	NC_FPGA_PR14B       
          	               	L17       	214B3     	NC_FPGA_PR14A       
          	               	L18       	217B3     	GND                 
          	               	L19       	214B3     	FM_UARTSW_LSB_N     
          	               	L20       	214B3     	FM_UARTSW_MSB_N     
          	               	L21       	214B3     	FM_THERMAL_ALERT_R_N
          	               	L22       	214B3     	NC_FPGA_PR16C       
          	               	M1        	216B3     	NC                  
          	               	M2        	216B4     	NC                  
          	               	M3        	217B4     	P3V3_AUX_FPGA_VCCIO4
          	               	M4        	217B3     	GND                 
          	               	M5        	216B3     	NC                  
          	               	M6        	216B3     	NC                  
          	               	M7        	216B3     	NC                  
          	               	M8        	217B4     	P3V3_AUX_FPGA_VCCIO4
          	               	M9        	217B3     	GND                 
          	               	M10       	217B3     	GND                 
          	               	M11       	217B4     	VCC_PLD_CORE        
          	               	M12       	217B4     	VCC_PLD_CORE        
          	               	M13       	217B3     	GND                 
          	               	M14       	217B3     	GND                 
          	               	M15       	217B4     	P3V3_AUX_FPGA_VCCIO1
          	               	M16       	214B2     	FM_CPU0_SKTOCC_LVT3_PLD_N
          	               	M17       	214B3     	NC_FPGA_PR16D       
          	               	M18       	217B4     	P3V3_AUX_FPGA_VCCIO1
          	               	M19       	214B2     	RST_PCIE_CPU1_DEV_PERST_N
          	               	M20       	214B2     	RST_PCIE_CPU0_DEV_PERST_N
          	               	M21       	214B2     	SMB_2_PLD_3V3AUX_SDA_R1
          	               	M22       	214B2     	SMB_2_PLD_3V3AUX_SCL_R1
          	               	N1        	216B3     	NC                  
          	               	N2        	216B3     	NC                  
          	               	N3        	216B3     	NC                  
          	               	N4        	216B3     	NC                  
          	               	N5        	216B4     	NC                  
          	               	N6        	216B4     	NC                  
          	               	N7        	216B4     	NC                  
          	               	N8        	217B4     	P3V3_AUX_FPGA_VCCIO3
          	               	N9        	217B3     	GND                 
          	               	N10       	217B4     	VCC_PLD_CORE        
          	               	N11       	217B4     	VCC_PLD_CORE        
          	               	N12       	217B4     	VCC_PLD_CORE        
          	               	N13       	217B4     	VCC_PLD_CORE        
          	               	N14       	217B3     	GND                 
          	               	N15       	217B4     	P3V3_AUX_FPGA_VCCIO1
          	               	N16       	214B2     	FM_CPU1_SKTOCC_LVT3_PLD_N
          	               	N17       	214B2     	FM_CPU0_PROC_ID0    
          	               	N18       	214B2     	FM_CPU0_PROC_ID1    
          	               	N19       	214B2     	FM_CPU0_PKGID1      
          	               	N20       	214B2     	FM_CPU0_PKGID0      
          	               	N21       	217B3     	GND                 
          	               	N22       	214B2     	FM_CPU1_PROC_ID0    
          	               	P1        	216B3     	NC                  
          	               	P2        	216B3     	NC                  
          	               	P3        	216B3     	NC                  
          	               	P4        	216B4     	NC                  
          	               	P5        	216B4     	PWRGD_CPUPWRGD_LVC2_R1
          	               	P6        	216B4     	NC                  
          	               	P7        	216B4     	H_CPU1_THERMTRIP_LVC1_N
          	               	P8        	217B4     	P3V3_AUX_FPGA_VCCIO3
          	               	P9        	217B3     	GND                 
          	               	P10       	217B3     	GND                 
          	               	P11       	217B3     	GND                 
          	               	P12       	217B3     	GND                 
          	               	P13       	217B3     	GND                 
          	               	P14       	217B3     	GND                 
          	               	P15       	217B4     	P3V3_AUX_FPGA_VCCIO1
          	               	P16       	214B2     	FM_CPU_RMCA_CATERR_DLY_LVT3_R_N
          	               	P17       	214B2     	FM_RST_PERST_BIT1   
          	               	P18       	214B2     	FM_RST_PERST_BIT0   
          	               	P19       	214B2     	IRQ_PVCCIN_CPU1_VRHOT_R_N
          	               	P20       	214B2     	FM_CPU1_PKGID2      
          	               	P21       	214B2     	FM_CPU1_PROC_ID1    
          	               	P22       	214B2     	FM_CPU1_PKGID1      
          	               	R1        	216B3     	NC                  
          	               	R2        	216B4     	NC                  
          	               	R3        	216B4     	NC                  
          	               	R4        	216B4     	NC                  
          	               	R5        	216B4     	NC                  
          	               	R6        	216B4     	H_CPU0_MEMTRIP_LVC1_N
          	               	R7        	216B4     	H_CPU1_MEMHOT_OUT_LVC1_N
          	               	R8        	217B3     	GND                 
          	               	R9        	217B4     	P3V3_AUX_FPGA_VCCIO2
          	               	R10       	217B4     	P3V3_AUX_FPGA_VCCIO2
          	               	R11       	217B4     	P3V3_AUX_FPGA_VCCIO2
          	               	R12       	217B4     	P3V3_AUX_FPGA_VCCIO2
          	               	R13       	217B4     	P3V3_AUX_FPGA_VCCIO2
          	               	R14       	217B4     	P3V3_AUX_FPGA_VCCIO2
          	               	R15       	217B3     	GND                 
          	               	R16       	214B2     	PWRGD_FAIL_CPU1_CD_R
          	               	R17       	214B2     	PWRGD_FAIL_CPU1_AB_R
          	               	R18       	214B2     	PWRGD_FAIL_CPU0_GH_R
          	               	R19       	214B2     	PWRGD_FAIL_CPU0_EF_R
          	               	R20       	214B2     	PWRGD_FAIL_CPU0_CD_R
          	               	R21       	214B2     	FM_CPU1_PKGID0      
          	               	R22       	214B2     	FM_CPU0_PKGID2      
          	               	T1        	216B4     	NC                  
          	               	T2        	216B4     	H_CPU0_THERMTRIP_LVC1_N
          	               	T3        	216B4     	H_CPU0_MEMHOT_OUT_LVC1_N
          	               	T4        	216B4     	H_CPU_ERR2_LVC2_N   
          	               	T5        	216B4     	H_CPU_ERR1_LVC2_N   
          	               	T6        	216B4     	H_CPU_ERR0_LVC2_N   
          	               	T7        	216B3     	H_CPU0_MEMHOT_IN_LVC1_R_N
          	               	T8        	215B3     	FM_PLD_CLK_25M_R_EN 
          	               	T9        	215B3     	FM_BIOS_POST_CMPLT_BMC_N
          	               	T10       	215B3     	FM_PLD_HEARTBEAT_LVC3
          	               	T11       	215B3     	GPU_3V3IO_RSVD0_FFU_ISO_R
          	               	T12       	215B3     	GPU_3V3IO_RSVD1_ISO_R
          	               	T13       	215B3     	RST_SGPIO_RESET_N_R 
          	               	T14       	215B3     	FM_ME_BT_DONE       
          	               	T15       	215B3     	CLK_SWB_BUF2_OE_N   
          	               	T16       	215B3     	FM_AC_PWR_BTN_PLD_ISO_N
          	               	T17       	214B2     	OCP_V3_2_MAIN_PWR_EN
          	               	T18       	214B2     	OCP_SFF_MAIN_PWR_EN 
          	               	T19       	214B2     	PWRGD_FAIL_CPU1_GH_R
          	               	T20       	214B2     	PWRGD_FAIL_CPU1_EF_R
          	               	T21       	214B2     	IRQ_PVCCIN_CPU0_VRHOT_R_N
          	               	T22       	214B2     	PWRGD_DSW_PWROK_R3  
          	               	U1        	216B4     	H_CPU1_MEMTRIP_LVC1_N
          	               	U2        	216B3     	NC                  
          	               	U3        	216B3     	NC                  
          	               	U4        	216B3     	NC                  
          	               	U5        	216B3     	RST_CPU0_LVC1_R_N   
          	               	U6        	215B3     	FM_ADR_COMPLETE     
          	               	U7        	215B3     	FM_PLD_CLKS_DEV_R_EN
          	               	U8        	215B3     	FM_BMC_DBP_PRESENT_R_N
          	               	U9        	215B3     	FM_BMC_RSTBTN_OUT_N 
          	               	U10       	215B3     	FM_FORCE_PWRON_LVC3 
          	               	U11       	215B3     	GPU_3V3IO_RSVD1_FFU_ISO_R
          	               	U12       	215B3     	GPU_3V3IO_RSVD3_ISO_R
          	               	U13       	215B3     	IRQ_BMC_CPU_NMI_R1  
          	               	U14       	215B3     	RST_PCIE_PCH_DEV_PERST_N
          	               	U15       	215B3     	FM_SLPS3_PLD_N      
          	               	U16       	215B3     	NC_FPGA_PB43D       
          	               	U17       	214B2     	FM_JTAG_TCK_MUX_SEL_R
          	               	U18       	214B2     	E1S_0_LED_ACT_R_N   
          	               	U19       	214B2     	FM_SMB_2_ALERT_GPU_ISO_R_N
          	               	U20       	214B2     	HP_LVC3_OCP_V3_2_HSC_PWRGD_PLD_
          	               	U21       	214B2     	FM_SLPS4_PLD_N      
          	               	U22       	214B2     	FM_JTAG_BMC_MUX_SEL_R
          	               	V1        	216B3     	NC                  
          	               	V2        	217B3     	GND                 
          	               	V3        	217B4     	P3V3_AUX_FPGA_VCCIO3
          	               	V4        	216B3     	RST_CPU1_LVC1_R_N   
          	               	V5        	216B3     	H_CPU1_MEMHOT_IN_LVC1_R_N
          	               	V6        	215B3     	FM_ADR_TRIGGER_N    
          	               	V7        	215B3     	RST_PFR_OVR_SRTC_R  
          	               	V8        	215B3     	FM_REMOTE_DEBUG_DET 
          	               	V9        	215B3     	FM_PS_PWROK_DLY_SEL 
          	               	V10       	215B3     	E1S_0_PRSNT_N       
          	               	V11       	215B3     	PRSNT_CABLE_GPU_A2_ISO_R_N
          	               	V12       	215B3     	GPU_3V3IO_RSVD4_ISO_R
          	               	V13       	215B3     	IRQ_PCH_CPU_NMI_EVENT_N
          	               	V14       	215B3     	NC_FPGA_PB32D       
          	               	V15       	215B3     	ROT_P1_RST_IND_N_R  
          	               	V16       	215B3     	RST_RSMRST_PLD_R_N  
          	               	V17       	215B3     	FM_PDB_BUF_EN       
          	               	V18       	214B2     	FM_BMC_CPU_FBRK_OUT_R_N
          	               	V19       	214B2     	CLK_GEN2_GPU_FPGA_OE_R_N
          	               	V20       	217B4     	P3V3_AUX_FPGA_VCCIO1
          	               	V21       	217B3     	GND                 
          	               	V22       	214B2     	FM_PS_EN_PLD_R      
          	               	W1        	216B3     	PWRGD_CPU1_LVC1_R   
          	               	W2        	216B3     	PWRGD_CPU0_LVC1_R   
          	               	W3        	216B3     	FM_THERMTRIP_DLY_LVC1_R_N
          	               	W4        	216B3     	H_CPU0_PROCHOT_LVC1_R_N
          	               	W5        	215B3     	NC_FPGA_PB7D        
          	               	W6        	215B3     	RST_PFR_OVR_RTC_R   
          	               	W7        	217B4     	P3V3_AUX_FPGA_VCCIO2
          	               	W8        	215B3     	FM_RST_PERST_BIT2   
          	               	W9        	215B3     	USB_OC1_REAR_N      
          	               	W10       	215B3     	HSC_D_OC_R1         
          	               	W11       	217B4     	P3V3_AUX_FPGA_VCCIO2
          	               	W12       	217B3     	GND                 
          	               	W13       	215B3     	IRQ_PCH_SCI_WHEA_R_N
          	               	W14       	215B3     	FM_BIOS_DEBUG_EN_N  
          	               	W15       	215B3     	FM_DIMM_12V_CPS_SX_N
          	               	W16       	217B4     	P3V3_AUX_FPGA_VCCIO2
          	               	W17       	215B3     	CLK_SWB_OE_N        
          	               	W18       	215B3     	SWB_HSC_PWRGD_ISO_R 
          	               	W19       	214B2     	RST_PERST_SWB_N     
          	               	W20       	214B2     	FM_PCH_SPKR_R       
          	               	W21       	214B2     	FM_SMB_1_ALERT_GPU_ISO_R_N
          	               	W22       	214B2     	PWRGD_FAIL_CPU0_AB_R
          	               	Y1        	216B3     	H_CPU_RMCA_LVC2_R2_N
          	               	Y2        	216B3     	H_CPU_CATERR_LVC2_R2_N
          	               	Y3        	216B3     	H_CPU1_PROCHOT_LVC1_R_N
          	               	Y4        	215B3     	IRQ_UV_DETECT_R_N   
          	               	Y5        	215B3     	PCIE_M2_SSD0_PRSNT_N
          	               	Y6        	215B3     	FM_HBM2_HBM3_VPP_SEL
          	               	Y7        	217B3     	GND                 
          	               	Y8        	215B3     	FM_ME_AUTHN_FAIL    
          	               	Y9        	215B3     	PRSNT_SWB_ISO_R_N   
          	               	Y10       	215B3     	FM_PCH_BMC_RST_N    
          	               	Y11       	215B3     	GPU_3V3IO_RSVD5_FFU_ISO_R
          	               	Y12       	215B3     	PRSNT_CABLE_GPU_A1_ISO_R_N
          	               	Y13       	215B3     	IRQ_PSU_ALERT_R_N   
          	               	Y14       	215B3     	FM_NCSI_OCP_V3_1_R_OE
          	               	Y15       	215B3     	FM_THROTTLE_R_N     
          	               	Y16       	217B3     	GND                 
          	               	Y17       	215B3     	RST_PLTRST_PLD_N    
          	               	Y18       	215B3     	CLK_GPU_2_OE_N      
          	               	Y19       	215B3     	SWB_HSC_EN_R        
          	               	Y20       	214B2     	NC_FPGA_PR30D       
          	               	Y21       	214B2     	GPU_FPGA_RST_N      
          	               	Y22       	214B2     	HP_LVC3_OCP_V3_1_HSC_PWRGD_PLD_

U252      	74LVC2G17GW    	          	          	                    
          	               	1         	149B3     	RST_PERST_SWB_R_N   
          	               	2         	149B3     	GND                 
          	               	3         	149B3     	RST_PERST_SWB_R_N   
          	               	4         	149B3     	RST_PERST_1_SWB_BUF_R_N
          	               	5         	149B3     	P3V3_AUX            
          	               	6         	149B3     	RST_PERST_0_SWB_BUF_R_N

U253      	74LVC2G17GW    	          	          	                    
          	               	1         	149B3     	GPU_FPGA_BOOT_EN    
          	               	2         	149B3     	GND                 
          	               	3         	149B3     	GPU_BASE_STBY_EN    
          	               	4         	149B3     	GPU_BASE_STBY_EN_BUF_R
          	               	5         	149B3     	P3V3_AUX            
          	               	6         	149B3     	GPU_FPGA_BOOT_EN_BUF_R

U255      	74LVC2G07DW7   	          	          	                    
          	               	1         	150B3     	GPU_NVS_PWR_BRAKE_N 
          	               	2         	150B3     	GND                 
          	               	3         	150B3     	GPU_FPGA_EROT_RST_N 
          	               	4         	150B3     	GPU_FPGA_EROT_RST_BUF_R_N
          	               	5         	150B3     	P3V3_AUX            
          	               	6         	150B3     	GPU_NVS_PWR_BRAKE_N_R

U256      	74LVC2G17GW    	          	          	                    
          	               	1         	149A3     	RST_PERST_SWB_R_N   
          	               	2         	149A3     	GND                 
          	               	3         	149A3     	FM_SWB_PWR_EN_R     
          	               	4         	149A3     	FM_SWB_PWR_EN_R1_BUF
          	               	5         	149A3     	P3V3_AUX            
          	               	6         	149A3     	RST_PERST_2_SWB_BUF_R_N

U257      	74LVC2G07DW7   	          	          	                    
          	               	1         	150B3     	GPU_FPGA_EROT_RECOV_N
          	               	2         	150B3     	GND                 
          	               	3         	150B3     	GND                 
          	               	4         	150B3     	NC_U257_2Y          
          	               	5         	150B3     	P3V3_AUX            
          	               	6         	150B3     	GPU_FPGA_EROT_RECOV_BUF_R_N

U259      	SN74LVC2G07DCKR_SMLF	          	          	                    
          	               	1         	190A4     	M2_SSD0_CLKREQ_EN_N 
          	               	2         	190A4     	GND                 
          	               	3         	190A4     	RST_PCIE_PCH_DEV_PERST_M2_R_N
          	               	4         	190A3     	RST_PCIE_PCH_DEV_BUF_M2_0_PERST
          	               	5         	190A3     	P3V3_AUX            
          	               	6         	190A3     	HDD_ACTIVITY_BUF    

U263      	INA230AIRGTR   	          	          	                    
          	               	1         	172B3     	INA230_3_A1         
          	               	2         	172B3     	INA230_3_A0         
          	               	3         	172B2     	OCP_V3_2_P3V3_ADC_ALERT_R
          	               	4         	172B3     	SMB_INA230_3_3V3AUX_SDA_R1
          	               	5         	172B3     	SMB_INA230_3_3V3AUX_SCL_R1
          	               	6         	172B2     	NC_INA230_3_NC0     
          	               	7         	172B2     	NC_INA230_3_NC1     
          	               	8         	172B2     	NC_INA230_3_NC2     
          	               	9         	172B3     	P3V3_AUX            
          	               	10        	172B2     	GND                 
          	               	11        	172B3     	P3V3_OCP_V3_2_R     
          	               	12        	172B3     	VSENSE_P12V_INA230_3_INN
          	               	13        	172B3     	VSENSE_P12V_INA230_3_INP
          	               	14        	172B2     	NC_INA230_3_NC3     
          	               	15        	172B2     	NC_INA230_3_NC4     
          	               	16        	172B2     	NC_INA230_3_NC5     
          	               	TH        	172B2     	GND                 

U264      	INA230AIRGTR   	          	          	                    
          	               	1         	172B3     	INA230_4_A1         
          	               	2         	172B3     	INA230_4_A0         
          	               	3         	172B2     	M2_0_P3V3_ADC_ALERT_R
          	               	4         	172B3     	SMB_INA230_4_3V3AUX_SDA_R1
          	               	5         	172B3     	SMB_INA230_4_3V3AUX_SCL_R1
          	               	6         	172B2     	NC_INA230_4_NC0     
          	               	7         	172B2     	NC_INA230_4_NC1     
          	               	8         	172B2     	NC_INA230_4_NC2     
          	               	9         	172B3     	P3V3_AUX            
          	               	10        	172B2     	GND                 
          	               	11        	172B3     	P3V3                
          	               	12        	172B3     	VSENSE_P12V_INA230_4_INN
          	               	13        	172B3     	VSENSE_P12V_INA230_4_INP
          	               	14        	172B2     	NC_INA230_4_NC3     
          	               	15        	172B2     	NC_INA230_4_NC4     
          	               	16        	172B2     	NC_INA230_4_NC5     
          	               	TH        	172B2     	GND                 

U265      	INA230AIRGTR   	          	          	                    
          	               	1         	172A3     	INA230_5_A1         
          	               	2         	172A3     	INA230_5_A0         
          	               	3         	172A2     	P12V_SCM_ADC_ALERT_R
          	               	4         	172A3     	SMB_INA230_5_3V3AUX_SDA_R1
          	               	5         	172A3     	SMB_INA230_5_3V3AUX_SCL_R1
          	               	6         	172A2     	NC_INA230_5_NC0     
          	               	7         	172A2     	NC_INA230_5_NC1     
          	               	8         	172A2     	NC_INA230_5_NC2     
          	               	9         	172A3     	P3V3_AUX            
          	               	10        	172A2     	GND                 
          	               	11        	172A3     	P12V_SCM_R          
          	               	12        	172A3     	VSENSE_P12V_INA230_5_INN
          	               	13        	172A3     	VSENSE_P12V_INA230_5_INP
          	               	14        	172A2     	NC_INA230_5_NC3     
          	               	15        	172A2     	NC_INA230_5_NC4     
          	               	16        	172A2     	NC_INA230_5_NC5     
          	               	TH        	172A2     	GND                 

U266      	INA230AIRGTR   	          	          	                    
          	               	1         	171B3     	INA230_1_A1         
          	               	2         	171B3     	INA230_1_A0         
          	               	3         	171B2     	OCP_SFF_P3V3_ADC_ALERT_R
          	               	4         	171B3     	SMB_INA230_1_3V3AUX_SDA_R1
          	               	5         	171B3     	SMB_INA230_1_3V3AUX_SCL_R1
          	               	6         	171B2     	NC_INA230_1_NC0     
          	               	7         	171B2     	NC_INA230_1_NC1     
          	               	8         	171B2     	NC_INA230_1_NC2     
          	               	9         	171B3     	P3V3_AUX            
          	               	10        	171B2     	GND                 
          	               	11        	171B3     	P3V3_OCP_SFF_R      
          	               	12        	171B3     	VSENSE_P3V3_INA230_1_INN
          	               	13        	171B3     	VSENSE_P3V3_INA230_1_INP
          	               	14        	171B2     	NC_INA230_1_NC3     
          	               	15        	171B2     	NC_INA230_1_NC4     
          	               	16        	171B2     	NC_INA230_1_NC5     
          	               	TH        	171B2     	GND                 

U268      	GL852GOHY60    	          	          	                    
          	               	1         	152B3     	USB2_P0_R_DN        
          	               	2         	152B3     	USB2_P0_R_DP        
          	               	3         	152B3     	USB2_HUB_SWB_DN     
          	               	4         	152B3     	USB2_HUB_SWB_DP     
          	               	5         	152B3     	P3V3_AUX_USB_HUB    
          	               	6         	152B3     	NC_USB_HUB_DM2      
          	               	7         	152B3     	NC_USB_HUB_DP2      
          	               	8         	152B3     	USB_HUB_RREF        
          	               	9         	152B3     	P3V3_AUX_USB_HUB    
          	               	10        	152B3     	USB_HUB_XTAL_IN     
          	               	11        	152B3     	USB_HUB_XTAL_OUT    
          	               	12        	152B3     	NC_USB_HUB_DM3      
          	               	13        	152B3     	NC_USB_HUB_DP3      
          	               	14        	152B3     	P3V3_AUX_USB_HUB    
          	               	15        	152B3     	NC_USB_HUB_DM4      
          	               	16        	152B3     	NC_USB_HUB_DP4      
          	               	17        	152B3     	RST_USB_HUB_R_N     
          	               	18        	152B3     	USB_HUB_TEST        
          	               	19        	152B3     	USB_HUB_OVCUR4      
          	               	20        	152B3     	USB_HUB_OVCUR3      
          	               	21        	152B3     	USB_HUB_DVDD        
          	               	22        	152B3     	USB_HUB_PSELF       
          	               	23        	152B3     	USB_HUB_PGANG       
          	               	24        	152B3     	USB_HUB_OVCUR2      
          	               	25        	152B3     	USB_HUB_OVCUR1      
          	               	26        	152B3     	NC_USB_HUB_SDA      
          	               	27        	152B3     	P3V3_AUX_USB_HUB    
          	               	28        	152B3     	P3V3_AUX_USB_HUB    
          	               	TH        	152B3     	GND                 

U269      	ADC128D818CIMTXNOPB	          	          	                    
          	               	1         	250A1     	ADC128_VREF         
          	               	2         	250A1     	SMB_SEN_TIC_3V3AUX_SDA
          	               	3         	250A1     	SMB_SEN_TIC_3V3AUX_SCL
          	               	4         	250A1     	GND                 
          	               	5         	250B1     	P3V3_ADC128_VCC     
          	               	6         	250B1     	TP_ADC128_INT       
          	               	7         	250A1     	ADC128_A0           
          	               	8         	250A1     	ADC128_A1           
          	               	9         	250A1     	P12V_E1S_0_ISENSE_TIC
          	               	10        	250A1     	P3V3_PDB_AUX_ADC_TIC
          	               	11        	250A1     	P3V3_AUX_ADC_TIC    
          	               	12        	250A1     	P3V3_ADC_TIC        
          	               	13        	250A1     	P5V_ADC_TIC         
          	               	14        	250A1     	P12V_OCP_V3_2_ISENSE_TIC
          	               	15        	250A1     	P12V_OCP_SFF_ISENSE_TIC
          	               	16        	250A1     	P12V_AUX_ADC_TIC    

U270      	LM75BD         	          	          	                    
          	               	1         	170B3     	SMB_LM75_0_3V3AUX_SDA_R1
          	               	2         	170B3     	SMB_LM75_0_3V3AUX_SCL_R1
          	               	3         	170B3     	FM_G751_0_ALERT_N   
          	               	4         	170B3     	GND                 
          	               	5         	170B3     	U270_0_ADD2         
          	               	6         	170B3     	U270_0_ADD1         
          	               	7         	170B3     	U270_0_ADD0         
          	               	8         	170B3     	P3V3_AUX            

U271      	LM75BD         	          	          	                    
          	               	1         	170B3     	SMB_LM75_1_3V3AUX_SDA_R1
          	               	2         	170B3     	SMB_LM75_1_3V3AUX_SCL_R1
          	               	3         	170B3     	FM_G751_1_ALERT_N   
          	               	4         	170B3     	GND                 
          	               	5         	170B3     	U271_1_ADD2         
          	               	6         	170B3     	U271_1_ADD1         
          	               	7         	170B3     	U271_1_ADD0         
          	               	8         	170B3     	P3V3_AUX            

U272      	LM75BD         	          	          	                    
          	               	1         	170B3     	SMB_LM75_2_3V3AUX_SDA_R1
          	               	2         	170B3     	SMB_LM75_2_3V3AUX_SCL_R1
          	               	3         	170A3     	FM_LM75_2_ALERT_N   
          	               	4         	170A3     	GND                 
          	               	5         	170A3     	U272_2_ADD2         
          	               	6         	170A3     	U272_2_ADD1         
          	               	7         	170B3     	U272_2_ADD0         
          	               	8         	170B3     	P3V3_AUX            

U273      	LM75BD         	          	          	                    
          	               	1         	170A3     	SMB_LM75_3_3V3AUX_SDA_R1
          	               	2         	170A3     	SMB_LM75_3_3V3AUX_SCL_R1
          	               	3         	170A3     	FM_LM75_3_ALERT_N   
          	               	4         	170A3     	GND                 
          	               	5         	170A3     	U273_3_ADD2         
          	               	6         	170A3     	U273_3_ADD1         
          	               	7         	170A3     	U273_3_ADD0         
          	               	8         	170A3     	P3V3_AUX            

U276      	INA230AIRGTR   	          	          	                    
          	               	1         	171A3     	INA230_2_A1         
          	               	2         	171A3     	INA230_2_A0         
          	               	3         	171A2     	E1S_0_P3V3_ADC_ALERT_R
          	               	4         	171A3     	SMB_INA230_2_3V3AUX_SDA_R1
          	               	5         	171A3     	SMB_INA230_2_3V3AUX_SCL_R1
          	               	6         	171A2     	NC_INA230_2_NC0     
          	               	7         	171A2     	NC_INA230_2_NC1     
          	               	8         	171A2     	NC_INA230_2_NC2     
          	               	9         	171A3     	P3V3_AUX            
          	               	10        	171A2     	GND                 
          	               	11        	171A3     	P3V3_E1S_0_R        
          	               	12        	171A3     	VSENSE_P3V3_INA230_2_INN
          	               	13        	171A3     	VSENSE_P3V3_INA230_2_INP
          	               	14        	171A2     	NC_INA230_2_NC3     
          	               	15        	171A2     	NC_INA230_2_NC4     
          	               	16        	171A2     	NC_INA230_2_NC5     
          	               	TH        	171A2     	GND                 

U278      	74LVC1G08W57   	          	          	                    
          	               	1         	246B3     	FM_GPU_HSC_EN       
          	               	2         	246B3     	GPU_PRSNT_R         
          	               	3         	246B3     	GND                 
          	               	4         	246B3     	FM_GPU_HSC_EN_BUF_R 
          	               	5         	246B3     	P3V3_AUX            

U279      	PCA9617ADP     	          	          	                    
          	               	1         	194B3     	P3V3_E1S_0          
          	               	2         	194B3     	SMB_E1S_3V3AUX_ISO_SCL_R
          	               	3         	194B3     	SMB_E1S_3V3AUX_ISO_SDA_R
          	               	4         	194B3     	GND                 
          	               	5         	194B3     	SMB_PCIE_E1S_ISO_EN_R
          	               	6         	194B3     	SMB_SENSOR_E1S_3V3AUX_SDA
          	               	7         	194B3     	SMB_SENSOR_E1S_3V3AUX_SCL
          	               	8         	194B3     	P3V3_AUX            

U286      	74LVC1G126SE7  	          	          	                    
          	               	1         	160B4     	OCP_V3_2_AUX_PWR_EN_R1
          	               	2         	160B4     	FM_OCP_V3_2_PWR_GOOD
          	               	3         	160B3     	GND                 
          	               	4         	160B3     	FB_BMC_ISOLATE_R2   
          	               	5         	160B3     	P3V3_AUX            

U290      	MOSFET_NCH_GDS_ESD_PROTECTED	          	          	                    
          	               	D         	301A4     	HSC_EN              
          	               	G         	301A4     	PDB_PRSNT_N         
          	               	S         	301A4     	GND                 

U301      	GTL2014PW      	          	          	                    
          	               	1         	226B3     	PD_CPU0_ERRS_DIR    
          	               	2         	226B3     	H_CPU_CATERR_LVC1_R_N
          	               	3         	226B3     	H_CPU_CATERR_LVC1_R_N
          	               	4         	226B3     	P0V62_CPU0_ERRS_VREF
          	               	5         	226B3     	H_CPU_RMCA_LVC1_R_N 
          	               	6         	226B3     	PWRGD_CPUPWRGD_LVC1 
          	               	7         	226B3     	GND                 
          	               	8         	226B3     	GND                 
          	               	9         	226B3     	PWRGD_CPUPWRGD_LVC2_R
          	               	10        	226B3     	H_CPU_RMCA_LVC2_R1_N
          	               	11        	226B3     	GND                 
          	               	12        	226B3     	H_CPU_CATERR_LVC2_R1_N
          	               	13        	226B3     	H_CPU_CATERR_LVC2_BMC_R_N
          	               	14        	226B3     	P3V3                

U304      	GTL2014PW      	          	          	                    
          	               	1         	225B3     	PD_GTL2014_BMC_JTAG_DIR_0
          	               	2         	225B3     	RST_CPU0_DRAM_GH_PLD_N
          	               	3         	225B3     	RST_CPU0_DRAM_EF_PLD_N
          	               	4         	225B3     	P0V62_CPU0_RST_DDR_VREF
          	               	5         	225B3     	RST_CPU0_DRAM_CD_PLD_N
          	               	6         	225B3     	RST_CPU0_DRAM_AB_PLD_N
          	               	7         	225B3     	GND                 
          	               	8         	225B3     	GND                 
          	               	9         	225B3     	RST_CPU0_DRAM_AB_PLD_LVT3_R_N
          	               	10        	225B3     	RST_CPU0_DRAM_CD_PLD_LVT3_R_N
          	               	11        	225B3     	GND                 
          	               	12        	225B3     	RST_CPU0_DRAM_EF_PLD_LVT3_R_N
          	               	13        	225B3     	RST_CPU0_DRAM_GH_PLD_LVT3_R_N
          	               	14        	225B3     	P3V3_AUX            

U305      	GTL2014PW      	          	          	                    
          	               	1         	225B3     	PD_GTL2014_BMC_JTAG_DIR_1
          	               	2         	225B3     	RST_CPU1_DRAM_GH_PLD_N
          	               	3         	225B3     	RST_CPU1_DRAM_EF_PLD_N
          	               	4         	225B3     	P0V62_CPU1_RST_DDR_VREF
          	               	5         	225B3     	RST_CPU1_DRAM_CD_PLD_N
          	               	6         	225B3     	RST_CPU1_DRAM_AB_PLD_N
          	               	7         	225B3     	GND                 
          	               	8         	225B3     	GND                 
          	               	9         	225B3     	RST_CPU1_DRAM_AB_PLD_LVT3_R_N
          	               	10        	225B3     	RST_CPU1_DRAM_CD_PLD_LVT3_R_N
          	               	11        	225B3     	GND                 
          	               	12        	225B3     	RST_CPU1_DRAM_EF_PLD_LVT3_R_N
          	               	13        	225B3     	RST_CPU1_DRAM_GH_PLD_LVT3_R_N
          	               	14        	225B3     	P3V3_AUX            

U306      	GTL2014PW      	          	          	                    
          	               	1         	225A3     	PD_CPU1_ERRS_U306_DIR
          	               	2         	225A3     	PD_GTL2014_ERROR_B0 
          	               	3         	225A3     	H_CPU_ERR2_LVC1_N   
          	               	4         	225A3     	P0V62_CPU0_ERRS_U306_VREF
          	               	5         	225A3     	H_CPU_ERR1_LVC1_N   
          	               	6         	225A3     	H_CPU_ERR0_LVC1_N   
          	               	7         	225A3     	GND                 
          	               	8         	225A3     	GND                 
          	               	9         	225A3     	H_CPU_ERR0_LVC2_R_N 
          	               	10        	225A3     	H_CPU_ERR1_LVC2_R_N 
          	               	11        	225A3     	GND                 
          	               	12        	225A3     	H_CPU_ERR2_LVC2_R_N 
          	               	13        	225A3     	NC_U306_A0          
          	               	14        	225A3     	P3V3                

U307      	MOSFET_N_SMLF  	          	          	                    
          	               	D         	257B4     	FM_LPC_ESPI_SEL     
          	               	G         	257B4     	FM_ESPI_PLD_R_EN_BUF_R
          	               	S         	257B4     	GND                 

U308      	74LVC2G07DW7   	          	          	                    
          	               	1         	246B3     	PWRGD_P3V3_AUX_PDB_R
          	               	2         	246B3     	GND                 
          	               	3         	246B3     	NC                  
          	               	4         	246B3     	NC                  
          	               	5         	246B3     	P3V3_AUX            
          	               	6         	246B3     	PWRGD_P3V3_AUX_PDB_BUF_R

U309      	PI3EQX1002EZREX	          	          	                    
          	               	1         	169B3     	FM_USB3_1_EQA       
          	               	2         	169B3     	FM_USB3_1_FGA       
          	               	3         	169B3     	FM_USB3_1_SWA       
          	               	4         	169B3     	FM_USB3_1_EN_N      
          	               	5         	169B3     	P3V3_AUX_USB_BUF    
          	               	6         	169B3     	USB3_PCH_TX_C_DP<4> 
          	               	7         	169B3     	USB3_PCH_TX_C_DN<4> 
          	               	8         	169B3     	GND                 
          	               	9         	169B3     	GND                 
          	               	10        	169B3     	GND                 
          	               	11        	169B3     	USB3_PCH_RX_BUF_C_DN<4>
          	               	12        	169B3     	USB3_PCH_RX_BUF_C_DP<4>
          	               	13        	169B3     	FM_USB3_1_RXDET_EN  
          	               	14        	169B3     	FM_USB3_1_SWB       
          	               	15        	169B3     	FM_USB3_1_FGB       
          	               	16        	169B3     	FM_USB3_1_EQB       
          	               	17        	169B3     	P3V3_AUX_USB_BUF    
          	               	18        	169B3     	USB3_PCH_RX_C_DP<4> 
          	               	19        	169B3     	USB3_PCH_RX_C_DN<4> 
          	               	20        	169B3     	GND                 
          	               	21        	169B3     	GND                 
          	               	22        	169B3     	GND                 
          	               	23        	169B3     	USB3_PCH_TX_BUF_DN<4>
          	               	24        	169B3     	USB3_PCH_TX_BUF_DP<4>
          	               	TH        	169B3     	GND                 

U312      	TUSB211IRWBR   	          	          	                    
          	               	1         	196A3     	USB2_HUB_2_BUF_EXT_R_DN
          	               	2         	196A3     	USB2_HUB_2_BUF_EXT_R_DP
          	               	3         	196A3     	TP_USB_HUB_2_TEST   
          	               	4         	196A3     	TP_USB_HUB_2_CD     
          	               	5         	196A3     	PD_USB_HUB_2_RSTN   
          	               	6         	196A3     	PD_USB_HUB_2_EQ     
          	               	7         	196A3     	USB2_HUB_2_BUF_EXT_R_DP
          	               	8         	196A3     	USB2_HUB_2_BUF_EXT_R_DN
          	               	9         	196A3     	TP_USB_HUB_2_ENA_HS 
          	               	10        	196A3     	GND                 
          	               	11        	196A3     	PD_USB_HUB_2_VREG   
          	               	12        	196A3     	P3V3_AUX            

U313      	GL852GOHY60    	          	          	                    
          	               	1         	196B3     	USB2_PCH_0_R_DN     
          	               	2         	196B3     	USB2_PCH_0_R_DP     
          	               	3         	196B3     	USB2_HUB_2_EXT_DN   
          	               	4         	196B3     	USB2_HUB_2_EXT_DP   
          	               	5         	196B3     	P3V3_AUX_USB_HUB_2  
          	               	6         	196B3     	NC_USB_HUB_2_DM2    
          	               	7         	196B3     	NC_USB_HUB_2_DP2    
          	               	8         	196B3     	USB_HUB_2_RREF      
          	               	9         	196B3     	P3V3_AUX_USB_HUB_2  
          	               	10        	196B3     	USB_HUB_2_XTAL_IN   
          	               	11        	196B3     	USB_HUB_2_XTAL_OUT  
          	               	12        	196B3     	NC_USB_HUB_2_DM3    
          	               	13        	196B3     	NC_USB_HUB_2_DP3    
          	               	14        	196B3     	P3V3_AUX_USB_HUB_2  
          	               	15        	196B3     	NC_USB_HUB_2_DM4    
          	               	16        	196B3     	NC_USB_HUB_2_DP4    
          	               	17        	196B3     	RST_USB_HUB_2_R_N   
          	               	18        	196B3     	USB_HUB_2_TEST      
          	               	19        	196B3     	USB_HUB_2_OVCUR4    
          	               	20        	196B3     	USB_HUB_2_OVCUR3    
          	               	21        	196B3     	USB_HUB_2_DVDD      
          	               	22        	196B3     	USB_HUB_2_PSELF     
          	               	23        	196B3     	USB_HUB_2_PGANG     
          	               	24        	196B3     	USB_HUB_2_OVCUR2    
          	               	25        	196B3     	USB_HUB_2_OVCUR1    
          	               	26        	196B3     	NC_USB_HUB_2_SDA    
          	               	27        	196B3     	P3V3_AUX_USB_HUB_2  
          	               	28        	196B3     	P3V3_AUX_USB_HUB_2  
          	               	TH        	196B3     	GND                 

U314      	9ZXL0451EKILFT 	          	          	                    
          	               	1         	211B3     	FM_9ZXL045_DEV_EN   
          	               	2         	211B3     	P3V3_9ZXL045_VDDR   
          	               	3         	211B3     	CLK_100M_GPU_SWB_REF_DP
          	               	4         	211B3     	CLK_100M_GPU_SWB_REF_DN
          	               	5         	211B3     	CLK_9ZXL045_SADR0   
          	               	6         	211B3     	SMB_HOST_9ZXL045_3V3AUX_SDA
          	               	7         	211B3     	SMB_HOST_9ZXL045_3V3AUX_SCL
          	               	8         	211B3     	NC_U314_FBOUT_N     
          	               	9         	211B3     	NC_U314_FBOUT       
          	               	10        	211B3     	NC_U314_NC0         
          	               	11        	211B3     	NC_U314_NC1         
          	               	12        	211B3     	P3V3_9ZXL045_VDD    
          	               	13        	211B2     	CLK_100M_SWB_R_DP   
          	               	14        	211B2     	CLK_100M_SWB_R_DN   
          	               	15        	211B2     	FM_9ZXL045_0_OE_N   
          	               	16        	211B3     	P3V3_9ZXL045_VDD    
          	               	17        	211B3     	NC_U314_NC2         
          	               	18        	211B2     	FM_9ZXL045_1_OE_N   
          	               	19        	211B2     	CLK_100M_GPU_1_R_DP 
          	               	20        	211B2     	CLK_100M_GPU_1_R_DN 
          	               	21        	211B3     	P3V3_9ZXL045_VDD    
          	               	22        	211B2     	CLK_100M_GPU_2_R_DP 
          	               	23        	211B2     	CLK_100M_GPU_2_R_DN 
          	               	24        	211B2     	FM_9ZXL045_2_OE_N   
          	               	25        	211B3     	P3V3_9ZXL045_VDD    
          	               	26        	211B2     	FM_9ZXL045_3_OE_N   
          	               	27        	211B2     	TP_CLK_100M_BUF_DIF3_DP
          	               	28        	211B2     	TP_CLK_100M_BUF_DIF3_DN
          	               	29        	211B3     	P3V3_9ZXL045_VDD    
          	               	30        	211B3     	NC_U314_NC3         
          	               	31        	211B2     	P3V3_9ZXL045_VDDA   
          	               	32        	211B2     	CLK_9ZXL045_HIBW    
          	               	33        	211B2     	GND                 

U315      	PCA9617ADP     	          	          	                    
          	               	1         	237B3     	P3V3_AUX            
          	               	2         	237B3     	SMB_HOST_CLK_BUF_3V3AUX_SCL
          	               	3         	237B3     	SMB_HOST_CLK_BUF_3V3AUX_SDA
          	               	4         	237B3     	GND                 
          	               	5         	237B3     	PU_CLK_BUF_ISO_EN   
          	               	6         	237B3     	SMB_HOST_CLK_BUF_ISO_3V3AUX_S_2
          	               	7         	237B3     	SMB_HOST_CLK_BUF_ISO_3V3AUX_S_1
          	               	8         	237B3     	P3V3                

U316      	74LVC2G17GW    	          	          	                    
          	               	1         	145B2     	SWB_HSC_EN          
          	               	2         	145B2     	GND                 
          	               	3         	145B2     	GND                 
          	               	4         	145B2     	NC_U316_2Y          
          	               	5         	145B2     	P3V3_AUX            
          	               	6         	145B2     	SWB_HSC_EN_BUF_R    

U320      	74LVC1G66GV    	          	          	                    
          	               	1         	155A2     	CLK_50M_NCSI_OCP_SFF
          	               	2         	155A2     	CLK_50M_NCSI_OCP_SFF_ISO_R
          	               	3         	155A2     	GND                 
          	               	4         	155A1     	FB_BMC_ISOLATE      
          	               	5         	155A1     	P3V3_AUX            

U321      	74LVC1G66GV    	          	          	                    
          	               	1         	161A1     	CLK_50M_NCSI_OCP_V3_2
          	               	2         	161A1     	CLK_50M_NCSI_OCP_V3_2_ISO_R
          	               	3         	161A1     	GND                 
          	               	4         	161A1     	FB_BMC_ISOLATE1     
          	               	5         	161A1     	P3V3_AUX            

U322      	74LVC1G08W57   	          	          	                    
          	               	1         	158B3     	HP_OCP_V3_1_RST_R   
          	               	2         	158B3     	HP_LVC3_OCP_V3_1_P12V_PWRGD
          	               	3         	158B3     	GND                 
          	               	4         	158B2     	HP_LVC3_OCP_V3_1_PWRGD
          	               	5         	158B2     	P3V3_AUX            

U323      	74LVC1G08W57   	          	          	                    
          	               	1         	164B3     	HP_OCP_V3_2_RST_R   
          	               	2         	164B3     	HP_LVC3_OCP_V3_2_P12V_PWRGD
          	               	3         	164B3     	GND                 
          	               	4         	164B2     	HP_LVC3_OCP_V3_2_PWRGD
          	               	5         	164B2     	P3V3_AUX            

U324      	MOSFET_NCH_GDS_ESD_PROTECTED	          	          	                    
          	               	D         	260B2     	VR_P5V_EN_D         
          	               	G         	260B3     	VR_P5V_EN_N         
          	               	S         	260B2     	GND                 

U325      	MOSFET_N_SMLF  	          	          	                    
          	               	D         	306A1     	IRQ_UV_DETECT_N     
          	               	G         	306A2     	A_P12V_STBY_FPH_GATE
          	               	S         	306A1     	GND                 

U327      	74CBTLV3126PW  	          	          	                    
          	               	1         	248B3     	JTAG_BMC_SW_R_OE    
          	               	2         	248B3     	JTAG_BMC_TCK_R      
          	               	3         	248B2     	JTAG_BMC_SW_TCK_R   
          	               	4         	248B3     	JTAG_BMC_SW_R_OE    
          	               	5         	248B3     	JTAG_BMC_TMS_R      
          	               	6         	248B2     	JTAG_BMC_SW_TMS_R   
          	               	7         	248B2     	GND                 
          	               	8         	248B2     	JTAG_BMC_SW_TDI_R   
          	               	9         	248B3     	JTAG_BMC_TDI_R      
          	               	10        	248B3     	JTAG_BMC_SW_R_OE    
          	               	11        	248B2     	JTAG_BMC_SW_TDO_R   
          	               	12        	248B3     	JTAG_BMC_TDO_R      
          	               	13        	248B3     	JTAG_BMC_SW_R_OE    
          	               	14        	248B2     	P3V3_AUX            

U328      	DS125BR111RTWR 	          	          	                    
          	               	1         	167B2     	FM_P2E_BUF2_EQB0    
          	               	2         	167B2     	FM_P2E_BUF2_EQB1    
          	               	3         	167B2     	PD_P2E_BUF2_ENSMB   
          	               	4         	167B2     	FM_P2E_BUF2_VODA_DB 
          	               	5         	167B2     	FM_P2E_BUF2_VODB_DB 
          	               	6         	167B2     	FM_P2E_EN2_N        
          	               	7         	167B2     	P2E_MB_BMC_TX_BUF2_DP<0>
          	               	8         	167B2     	P2E_MB_BMC_TX_BUF2_DN<0>
          	               	9         	167B2     	FM_P2E_BUF2_EQA1    
          	               	10        	167B2     	FM_P2E_BUF2_EQA0    
          	               	11        	167B2     	P2E_MB_BMC_RX_R2_DP<0>
          	               	12        	167B2     	P2E_MB_BMC_RX_R2_DN<0>
          	               	13        	167B2     	NC_RES              
          	               	14        	167B2     	FM_P2E_BUF2_SD_TH   
          	               	15        	167B2     	P3V3_AUX            
          	               	16        	167B2     	GND                 
          	               	17        	167B2     	FM_P2E_BUF2_VOD_SEL 
          	               	18        	167B2     	FM_P2E_BUF2_RXDET   
          	               	19        	167B2     	P2E_MB_BMC_RX_BUF2_C_DN<0>
          	               	20        	167B2     	P2E_MB_BMC_RX_BUF2_C_DP<0>
          	               	21        	167B2     	P2E_BUF2_VDD        
          	               	22        	167B2     	P2E_BUF2_VDD        
          	               	23        	167B2     	P2E_MB_BMC_TX_C_R2_DN<0>
          	               	24        	167B2     	P2E_MB_BMC_TX_C_R2_DP<0>
          	               	25        	167B2     	GND                 

U329      	MOSFET_NCH_GDS_ESD_PROTECTED	          	          	                    
          	               	D         	306B2     	A_HSC_LOW_DRAIN     
          	               	G         	306B2     	A_HSC_LOW_GATE      
          	               	S         	306B2     	GND                 

U330      	APX80929SAG7   	          	          	                    
          	               	1         	260A4     	GND                 
          	               	2         	260A4     	PWRGD_P3V3_R1       
          	               	3         	260A4     	P3V3                

U331      	ISL28022FRZT   	          	          	                    
          	               	1         	251B3     	HSC_TYPE_ADC_A1     
          	               	2         	251B3     	HSC_TYPE_ADC_A0     
          	               	3         	251B2     	TP_HSC_TYPE_ADC_ALERT
          	               	4         	251B3     	SMB_HSC_TYPE_ADC_SDA
          	               	5         	251B3     	SMB_HSC_TYPE_ADC_SCL
          	               	6         	251B2     	NC_HSC_TYPE_NC0     
          	               	7         	251B2     	NC_HSC_TYPE_NC1     
          	               	8         	251B2     	NC_HSC_TYPE_NC2     
          	               	9         	251B3     	P3V3_AUX            
          	               	10        	251B2     	GND                 
          	               	11        	251B3     	HSC_TYPE_ADC        
          	               	12        	251B3     	NC_HSC_TYPE_VINM    
          	               	13        	251B3     	NC_HSC_TYPE_VINP    
          	               	14        	251B2     	NC_HSC_TYPE_NC3     
          	               	15        	251B2     	NC_HSC_TYPE_NC4     
          	               	16        	251B2     	NC_HSC_TYPE_NC5     
          	               	TH        	251B2     	GND                 

U332      	74LVC2G07DW7   	          	          	                    
          	               	1         	224A3     	FM_AC_PWR_BTN_PLD_N 
          	               	2         	224A3     	GND                 
          	               	3         	224A3     	GND                 
          	               	4         	224A3     	NC_UXX_2Y           
          	               	5         	224A3     	P3V3_AUX            
          	               	6         	224A3     	FM_AC_PWR_BTN_PLD_ISO_R_N

U334      	74LVC1G08W57   	          	          	                    
          	               	1         	158A2     	HP_LVC3_OCP_V3_1_PWRGD_R2
          	               	2         	158A2     	OCP_SFF_AUX_PWR_PLD_EN_R
          	               	3         	158A2     	GND                 
          	               	4         	158A2     	OCP_SFF_AUX_PWR_EN_R2
          	               	5         	158A2     	P3V3_AUX            

U335      	74LVC1G08W57   	          	          	                    
          	               	1         	164A2     	HP_LVC3_OCP_V3_2_PWRGD_R2
          	               	2         	164A2     	OCP_V3_2_AUX_PWR_PLD_EN_R
          	               	3         	164A2     	GND                 
          	               	4         	164A2     	OCP_V3_2_AUX_PWR_EN_R2
          	               	5         	164A2     	P3V3_AUX            

U336      	APX80929SAG7   	          	          	                    
          	               	1         	191B4     	GND                 
          	               	2         	191A4     	HP_E1S_0_P3V3_PWRGD 
          	               	3         	191B4     	P3V3_E1S_0          

U337      	LM4040AIM3X25NOPB	          	          	                    
          	               	1         	307B4     	UV_ADR_P2V5_COMP    
          	               	2         	307B4     	GND                 
          	               	3         	307B4     	NC                  

U338      	LM4040AIM3X25NOPB	          	          	                    
          	               	1         	307B4     	UV_P2V5_COMP        
          	               	2         	307A4     	GND                 
          	               	3         	307A4     	NC                  

U339      	AP331AWG7      	          	          	                    
          	               	1         	307B3     	UV_ADR_P2V5_COMP    
          	               	2         	307B3     	GND                 
          	               	3         	307B3     	P12V_AUX_UV_ADR_TRIGGER
          	               	4         	307B3     	FM_UV_ADR_TRIGGER_N_R2
          	               	5         	307B3     	P12V_AUX            

U340      	AP331AWG7      	          	          	                    
          	               	1         	307B3     	UV_P2V5_COMP        
          	               	2         	307B3     	GND                 
          	               	3         	307B3     	P12V_AUX_UV_TRIGGER 
          	               	4         	307B3     	IRQ_UV_DETECT_R2_N  
          	               	5         	307B3     	P12V_AUX            

U341      	LM4040AIM3X25NOPB	          	          	                    
          	               	1         	307A4     	DSW_PWROK_P2V5_COMP 
          	               	2         	307A4     	GND                 
          	               	3         	307A4     	NC                  

U342      	AP331AWG7      	          	          	                    
          	               	1         	307A3     	DSW_PWROK_P2V5_COMP 
          	               	2         	307A3     	GND                 
          	               	3         	307A3     	PWRGD_DSW_PWROK_TRIGGER
          	               	4         	307A3     	PWRGD_DSW_PWROK_R5  
          	               	5         	307A3     	P12V_AUX            

U343      	LM4040AIM3X25NOPB	          	          	                    
          	               	1         	306B4     	OC_P2V5_COMP        
          	               	2         	306B4     	GND                 
          	               	3         	306B4     	NC                  

U344      	AP331AWG7      	          	          	                    
          	               	1         	306B3     	OC_P2V5_COMP        
          	               	2         	306B3     	GND                 
          	               	3         	306B3     	HSC_OC_VOL          
          	               	4         	306B3     	HSC_D_OC_R2         
          	               	5         	306B3     	P12V_AUX            

U345      	NCT7718W       	          	          	                    
          	               	1         	305A2     	P3V3_AUX            
          	               	2         	305A2     	P12V_HSC_TEMP_D+    
          	               	3         	305A2     	P12V_HSC_TEMP_D-    
          	               	4         	305A2     	P12V_HSC_T_CRIT_N   
          	               	5         	305A2     	GND                 
          	               	6         	305A2     	P12V_HSC_TEMP_ALERT_N
          	               	7         	305A2     	P12V_HSC_TEMP_SDA   
          	               	8         	305A2     	P12V_HSC_TEMP_SCL   

U365      	MMBT3904_SMLF  	          	          	                    
          	               	B         	305A3     	P12V_HSC_TEMP_R     
          	               	C         	305A3     	P12V_HSC_TEMP_R     
          	               	E         	305A3     	P12V_HSC_TEMP_E     

U369      	TPS3700DDCR    	          	          	                    
          	               	1         	306B3     	A_HSC_LOW_GATE      
          	               	2         	306B3     	GND                 
          	               	3         	306B3     	A_HSC_LOW           
          	               	4         	306B3     	A_HSC_HIGH          
          	               	5         	306B3     	U369_VDD            
          	               	6         	306B3     	HSC_D_OC            

U5201     	TUSB211IRWBR   	          	          	                    
          	               	1         	152A3     	USB2_HUB_BUF_SWB_R_DN
          	               	2         	152A3     	USB2_HUB_BUF_SWB_R_DP
          	               	3         	152A3     	TP_USB2_TEST        
          	               	4         	152A3     	TP_USB2_CD          
          	               	5         	152A3     	PD_U5201_RSTN       
          	               	6         	152A3     	PD_U5201_EQ         
          	               	7         	152A3     	USB2_HUB_BUF_SWB_R_DP
          	               	8         	152A3     	USB2_HUB_BUF_SWB_R_DN
          	               	9         	152A3     	TP_USB2_ENA_HS      
          	               	10        	152A3     	GND                 
          	               	11        	152A3     	PD_U5201_VREG       
          	               	12        	152A3     	P3V3_AUX            

X1        	TP_TDR_4P_FTS_TH	          	          	                    
          	               	1         	309B3     	TDR_DIFF_85_TOP_DP  
          	               	2         	309B3     	T1_GND              
          	               	3         	309B3     	T1_GND              
          	               	4         	309B3     	TDR_DIFF_85_TOP_DN  

X2        	TP_TDR_4P_FTS_TH	          	          	                    
          	               	1         	309B3     	TDR_DIFF_85_IN1_DP  
          	               	2         	309B3     	T1_GND              
          	               	3         	309B3     	T1_GND              
          	               	4         	309B3     	TDR_DIFF_85_IN1_DN  

X3        	TP_TDR_4P_FTS_TH	          	          	                    
          	               	1         	309B3     	TDR_DIFF_85_IN2_DP  
          	               	2         	309B3     	T1_GND              
          	               	3         	309B3     	T1_GND              
          	               	4         	309B3     	TDR_DIFF_85_IN2_DN  

X4        	TP_TDR_4P_FTS_TH	          	          	                    
          	               	1         	309B3     	TDR_DIFF_85_IN3_DP  
          	               	2         	309B3     	T1_GND              
          	               	3         	309B3     	T1_GND              
          	               	4         	309B3     	TDR_DIFF_85_IN3_DN  

X5        	TP_TDR_4P_FTS_TH	          	          	                    
          	               	1         	309B3     	TDR_DIFF_85_IN4_DP  
          	               	2         	309B3     	T1_GND              
          	               	3         	309B3     	T1_GND              
          	               	4         	309B3     	TDR_DIFF_85_IN4_DN  

X6        	TP_TDR_4P_FTS_TH	          	          	                    
          	               	1         	309A3     	TDR_DIFF_85_BOT_DP  
          	               	2         	309A3     	T1_GND              
          	               	3         	309A3     	T1_GND              
          	               	4         	309A3     	TDR_DIFF_85_BOT_DN  

X7        	TP_TDR_4P_FTS_TH	          	          	                    
          	               	1         	309B2     	TDR_DIFF_85_TOP_DN  
          	               	2         	309B2     	T1_GND              
          	               	3         	309B2     	T1_GND              
          	               	4         	309B2     	TDR_DIFF_85_TOP_DP  

X8        	TP_TDR_4P_FTS_TH	          	          	                    
          	               	1         	309B2     	TDR_DIFF_85_IN1_DN  
          	               	2         	309B2     	T1_GND              
          	               	3         	309B2     	T1_GND              
          	               	4         	309B2     	TDR_DIFF_85_IN1_DP  

X9        	TP_TDR_4P_FTS_TH	          	          	                    
          	               	1         	309B2     	TDR_DIFF_85_IN2_DN  
          	               	2         	309B2     	T1_GND              
          	               	3         	309B2     	T1_GND              
          	               	4         	309B2     	TDR_DIFF_85_IN2_DP  

X10       	TP_TDR_4P_FTS_TH	          	          	                    
          	               	1         	309B2     	TDR_DIFF_85_IN3_DN  
          	               	2         	309B2     	T1_GND              
          	               	3         	309B2     	T1_GND              
          	               	4         	309B2     	TDR_DIFF_85_IN3_DP  

X11       	TP_TDR_4P_FTS_TH	          	          	                    
          	               	1         	309B2     	TDR_DIFF_85_IN4_DN  
          	               	2         	309B2     	T1_GND              
          	               	3         	309B2     	T1_GND              
          	               	4         	309B2     	TDR_DIFF_85_IN4_DP  

X12       	TP_TDR_4P_FTS_TH	          	          	                    
          	               	1         	309A2     	TDR_DIFF_85_BOT_DN  
          	               	2         	309A2     	T1_GND              
          	               	3         	309A2     	T1_GND              
          	               	4         	309A2     	TDR_DIFF_85_BOT_DP  

X13       	TP_TDR_4P_FTS_TH	          	          	                    
          	               	1         	309B1     	TDR_DIFF_100_TOP_DP 
          	               	2         	309B2     	T1_GND              
          	               	3         	309B2     	T1_GND              
          	               	4         	309B1     	TDR_DIFF_100_TOP_DN 

X14       	TP_TDR_4P_FTS_TH	          	          	                    
          	               	1         	309B1     	TDR_DIFF_100_IN1_DP 
          	               	2         	309B2     	T1_GND              
          	               	3         	309B2     	T1_GND              
          	               	4         	309B1     	TDR_DIFF_100_IN1_DN 

X15       	TP_TDR_4P_FTS_TH	          	          	                    
          	               	1         	309B1     	TDR_DIFF_100_IN2_DP 
          	               	2         	309B2     	T1_GND              
          	               	3         	309B2     	T1_GND              
          	               	4         	309B1     	TDR_DIFF_100_IN2_DN 

X16       	TP_TDR_4P_FTS_TH	          	          	                    
          	               	1         	309B1     	TDR_DIFF_100_IN3_DP 
          	               	2         	309B2     	T1_GND              
          	               	3         	309B2     	T1_GND              
          	               	4         	309B1     	TDR_DIFF_100_IN3_DN 

X17       	TP_TDR_4P_FTS_TH	          	          	                    
          	               	1         	309B1     	TDR_DIFF_100_IN4_DP 
          	               	2         	309B2     	T1_GND              
          	               	3         	309B2     	T1_GND              
          	               	4         	309B1     	TDR_DIFF_100_IN4_DN 

X18       	TP_TDR_4P_FTS_TH	          	          	                    
          	               	1         	309A1     	TDR_DIFF_100_BOT_DP 
          	               	2         	309A2     	T1_GND              
          	               	3         	309A2     	T1_GND              
          	               	4         	309A1     	TDR_DIFF_100_BOT_DN 

X19       	TP_TDR_4P_FTS_TH	          	          	                    
          	               	1         	309B1     	TDR_DIFF_100_TOP_DN 
          	               	2         	309B1     	T1_GND              
          	               	3         	309B1     	T1_GND              
          	               	4         	309B1     	TDR_DIFF_100_TOP_DP 

X20       	TP_TDR_4P_FTS_TH	          	          	                    
          	               	1         	309B1     	TDR_DIFF_100_IN1_DN 
          	               	2         	309B1     	T1_GND              
          	               	3         	309B1     	T1_GND              
          	               	4         	309B1     	TDR_DIFF_100_IN1_DP 

X21       	TP_TDR_4P_FTS_TH	          	          	                    
          	               	1         	309B1     	TDR_DIFF_100_IN2_DN 
          	               	2         	309B1     	T1_GND              
          	               	3         	309B1     	T1_GND              
          	               	4         	309B1     	TDR_DIFF_100_IN2_DP 

X22       	TP_TDR_4P_FTS_TH	          	          	                    
          	               	1         	309B1     	TDR_DIFF_100_IN3_DN 
          	               	2         	309B1     	T1_GND              
          	               	3         	309B1     	T1_GND              
          	               	4         	309B1     	TDR_DIFF_100_IN3_DP 

X23       	TP_TDR_4P_FTS_TH	          	          	                    
          	               	1         	309B1     	TDR_DIFF_100_IN4_DN 
          	               	2         	309B1     	T1_GND              
          	               	3         	309B1     	T1_GND              
          	               	4         	309B1     	TDR_DIFF_100_IN4_DP 

X24       	TP_TDR_4P_FTS_TH	          	          	                    
          	               	1         	309A1     	TDR_DIFF_100_BOT_DN 
          	               	2         	309A1     	T1_GND              
          	               	3         	309A1     	T1_GND              
          	               	4         	309A1     	TDR_DIFF_100_BOT_DP 

X25       	TP_TDR_4P_FTS_TH	          	          	                    
          	               	1         	309A3     	TDR_DIFF_85_IN5_DP  
          	               	2         	309A3     	T1_GND              
          	               	3         	309A3     	T1_GND              
          	               	4         	309A3     	TDR_DIFF_85_IN5_DN  

X26       	TP_TDR_4P_FTS_TH	          	          	                    
          	               	1         	309A3     	TDR_DIFF_85_IN6_DP  
          	               	2         	309A3     	T1_GND              
          	               	3         	309A3     	T1_GND              
          	               	4         	309A3     	TDR_DIFF_85_IN6_DN  

X27       	TP_TDR_4P_FTS_TH	          	          	                    
          	               	1         	309A2     	TDR_DIFF_85_IN5_DN  
          	               	2         	309A2     	T1_GND              
          	               	3         	309A2     	T1_GND              
          	               	4         	309A2     	TDR_DIFF_85_IN5_DP  

X28       	TP_TDR_4P_FTS_TH	          	          	                    
          	               	1         	309A2     	TDR_DIFF_85_IN6_DN  
          	               	2         	309A2     	T1_GND              
          	               	3         	309A2     	T1_GND              
          	               	4         	309A2     	TDR_DIFF_85_IN6_DP  

X29       	TP_TDR_4P_FTS_TH	          	          	                    
          	               	1         	309A1     	TDR_DIFF_100_IN5_DP 
          	               	2         	309A2     	T1_GND              
          	               	3         	309A2     	T1_GND              
          	               	4         	309A1     	TDR_DIFF_100_IN5_DN 

X30       	TP_TDR_4P_FTS_TH	          	          	                    
          	               	1         	309A1     	TDR_DIFF_100_IN6_DP 
          	               	2         	309A2     	T1_GND              
          	               	3         	309A2     	T1_GND              
          	               	4         	309A1     	TDR_DIFF_100_IN6_DN 

X31       	TP_TDR_4P_FTS_TH	          	          	                    
          	               	1         	309A1     	TDR_DIFF_100_IN5_DN 
          	               	2         	309A1     	T1_GND              
          	               	3         	309A1     	T1_GND              
          	               	4         	309A1     	TDR_DIFF_100_IN5_DP 

X32       	TP_TDR_4P_FTS_TH	          	          	                    
          	               	1         	309A1     	TDR_DIFF_100_IN6_DN 
          	               	2         	309A1     	T1_GND              
          	               	3         	309A1     	T1_GND              
          	               	4         	309A1     	TDR_DIFF_100_IN6_DP 

Y1        	Q_CRYSTAL_SMLF 	          	          	                    
          	               	1         	179A3     	XTAL_PCH_RTC2_R     
          	               	2         	179A3     	XTAL_PCH_RTC1       

Y2        	Q_XTAL_4P_13BI_24GND	          	          	                    
          	               	1         	208A4     	XTAL_CLK_GEN1_25M_X1_R
          	               	2         	208A4     	GND                 
          	               	3         	208A4     	XTAL_CLK_GEN1_25M_X2
          	               	4         	208A4     	GND                 

Y3        	Q_XTAL_4P_13BI_24GND	          	          	                    
          	               	1         	212B4     	CLK_GEN2_XTAL_IN_R  
          	               	2         	212B4     	GND                 
          	               	3         	212B4     	CLK_GEN2_XTAL_OUT   
          	               	4         	212B4     	GND                 

Y4        	Q_XTAL_4P_13BI_24GND	          	          	                    
          	               	1         	152B1     	USB_HUB_XTAL_IN     
          	               	2         	152B1     	GND                 
          	               	3         	152B1     	USB_HUB_XTAL_OUT    
          	               	4         	152B1     	GND                 

Y7        	Q_XTAL_4P_13BI_24GND	          	          	                    
          	               	1         	179A4     	XTAL_PCH_25M_IN_R   
          	               	2         	179A4     	GND                 
          	               	3         	179A4     	XTAL_PCH_25M_OUT    
          	               	4         	179A4     	GND                 

Y9        	Q_XTAL_4P_13BI_24GND	          	          	                    
          	               	1         	196B1     	USB_HUB_2_XTAL_IN   
          	               	2         	196B1     	GND                 
          	               	3         	196B1     	USB_HUB_2_XTAL_OUT  
          	               	4         	196B1     	GND                 
